( ConstraintFile "baseboard_fab2"
	( constraintHeader
		( objectKey
			( logical )
		)
		( version
			( 16.6 )
		)
		( revisionNumber
			( logicalViewRevNum 586 )
			( physicalViewRevNum 0 )
			( otherViewRevNum 0 )
		)
		( contents
			( dictionaryExtensions )
			( worksheetCustomizations )
			( electricalConstraints )
			( netClasses )
			( properties )
		)
		( precision
			( units mil )
			( numberOfDecimalPlaces 2 )
		)
	)
	( DictionaryExtensions
		( Attribute
			( Name "BOM_COST" )
			( Description " " )
			( Value
				( DataType ( dString ) )
				( Status  sProperty  sPackage )
			)
			( Objects
				( ValidObjects  oGate  oGateDefn  oBlock  oPart  oDesign  oSystem  oPartDefn  oNet )
				( NoInherit
					( oGate oPin )
				)
			)
			( Analysis
			)
		)
		( Attribute
			( Name "MATERIAL" )
			( Description " " )
			( Value
				( DataType ( dString ) )
				( Status  sProperty  sPackage )
			)
			( Objects
				( ValidObjects  oGate  oGateDefn  oBlock  oPart  oDesign  oSystem  oPartDefn )
				( NoInherit
					( oGate oPin )
				)
			)
			( Analysis
			)
		)
		( Attribute
			( Name "SEC_TYPE" )
			( Description " " )
			( Value
				( DataType ( dString ) )
				( Status  sProperty  sPackage )
			)
			( Objects
				( ValidObjects  oGate  oGateDefn  oBlock  oPart  oDesign  oSystem  oPartDefn )
				( NoInherit
					( oGate oPin )
				)
			)
			( Analysis
			)
		)
		( Attribute
			( Name "TOLERANCE" )
			( Description " " )
			( Value
				( DataType ( dString ) )
				( Status  sProperty  sPackage )
			)
			( Objects
				( ValidObjects  oGate  oGateDefn  oBlock  oPart  oDesign  oSystem  oPartDefn )
				( NoInherit
					( oGate oPin )
				)
			)
			( Analysis
			)
		)
		( Attribute
			( Name "WATTAGE" )
			( Description " " )
			( Value
				( DataType ( dString ) )
				( Status  sProperty  sPackage )
			)
			( Objects
				( ValidObjects  oGate  oGateDefn  oBlock  oPart  oDesign  oSystem  oPartDefn )
				( NoInherit
					( oGate oPin )
				)
			)
			( Analysis
			)
		)
		( Attribute
			( Name "SKT_NUMBER" )
			( Description " " )
			( Value
				( DataType ( dString ) )
				( Status  sProperty  sPackage )
			)
			( Objects
				( ValidObjects  oGate  oGateDefn  oBlock  oPart  oDesign  oSystem  oPartDefn )
				( NoInherit
					( oGate oPin )
				)
			)
			( Analysis
			)
		)
		( Attribute
			( Name "CD_SEC" )
			( Description " " )
			( Value
				( DataType ( dString ) )
				( Status  sProperty  sPackage )
			)
			( Objects
				( ValidObjects  oGate  oGateDefn  oBlock  oPart  oDesign  oSystem  oPartDefn )
				( NoInherit
					( oGate oPin )
				)
			)
			( Analysis
			)
		)
		( Attribute
			( Name "CDS_LMAN_SYM_OUTLINE" )
			( Description " " )
			( Value
				( DataType ( dString ) )
				( Status  sProperty  sPackage )
			)
			( Objects
				( ValidObjects  oGate  oGateDefn  oBlock  oPart  oDesign  oSystem  oPartDefn )
				( NoInherit
					( oGate oPin )
				)
			)
			( Analysis
			)
		)
		( Attribute
			( Name "SKU" )
			( Description " " )
			( Value
				( DataType ( dString ) )
				( Status  sProperty  sPackage )
			)
			( Objects
				( ValidObjects  oGate  oGateDefn  oBlock  oPart  oDesign  oSystem  oPartDefn )
				( NoInherit
					( oGate oPin )
				)
			)
			( Analysis
			)
		)
		( Attribute
			( Name "COLOR" )
			( Description " " )
			( Value
				( DataType ( dString ) )
				( Status  sProperty  sPackage )
			)
			( Objects
				( ValidObjects  oGate  oGateDefn  oBlock  oPart  oDesign  oSystem  oPartDefn )
				( NoInherit
					( oGate oPin )
				)
			)
			( Analysis
			)
		)
		( Attribute
			( Name "VOLATGE" )
			( Description " " )
			( Value
				( DataType ( dString ) )
				( Status  sProperty  sPackage )
			)
			( Objects
				( ValidObjects  oNet  oXnet  oPinPair  oBus  oDiffPair  oECSet )
			)
			( Analysis
			)
		)
		( Attribute
			( Name "SPOF" )
			( Description " " )
			( Value
				( DataType ( dString ) )
				( Status  sProperty  sPackage )
			)
			( Objects
				( ValidObjects  oGate  oGateDefn  oBlock  oPart  oDesign  oSystem  oPartDefn )
				( NoInherit
					( oGate oPin )
				)
			)
			( Analysis
			)
		)
		( Attribute
			( Name "PIN_SHORT" )
			( Description " " )
			( Value
				( DataType ( dString ) )
				( Status  sProperty  sPackage )
			)
			( Objects
				( ValidObjects  oGate  oGateDefn  oBlock  oPart  oDesign  oSystem  oPartDefn )
				( NoInherit
					( oGate oPin )
				)
			)
			( Analysis
			)
		)
		( Attribute
			( Name "BOM" )
			( Description " " )
			( Value
				( DataType ( dString ) )
				( Status  sProperty  sPackage )
			)
			( Objects
				( ValidObjects  oGate  oGateDefn  oBlock  oPart  oDesign  oSystem  oPartDefn )
				( NoInherit
					( oGate oPin )
				)
			)
			( Analysis
			)
		)
		( Attribute
			( Name "FIN" )
			( Description " " )
			( Value
				( DataType ( dString ) )
				( Status  sProperty  sPackage )
			)
			( Objects
				( ValidObjects  oGate  oGateDefn  oBlock  oPart  oDesign  oSystem  oPartDefn )
				( NoInherit
					( oGate oPin )
				)
			)
			( Analysis
			)
		)
		( Attribute
			( Name "P1V5_STBY_IBMC" )
			( Description " " )
			( Value
				( DataType ( dString ) )
				( Status  sProperty  sPackage )
			)
			( Objects
				( ValidObjects  oGate  oGateDefn  oBlock  oPart  oDesign  oSystem  oPartDefn )
				( NoInherit
					( oGate oPin )
				)
			)
			( Analysis
			)
		)
		( Attribute
			( Name "P1V5_STBY_IBMC_VR" )
			( Description " " )
			( Value
				( DataType ( dString ) )
				( Status  sProperty  sPackage )
			)
			( Objects
				( ValidObjects  oGate  oGateDefn  oBlock  oPart  oDesign  oSystem  oPartDefn )
				( NoInherit
					( oGate oPin )
				)
			)
			( Analysis
			)
		)
		( Attribute
			( Name "DIMMSIED" )
			( Description " " )
			( Value
				( DataType ( dString ) )
				( Status  sProperty  sPackage )
			)
			( Objects
				( ValidObjects  oGate  oGateDefn  oBlock  oPart  oDesign  oSystem  oPartDefn )
				( NoInherit
					( oGate oPin )
				)
			)
			( Analysis
			)
		)
		( Attribute
			( Name "DIMMSIDE" )
			( Description " " )
			( Value
				( DataType ( dString ) )
				( Status  sProperty  sPackage )
			)
			( Objects
				( ValidObjects  oGate  oGateDefn  oBlock  oPart  oDesign  oSystem  oPartDefn )
				( NoInherit
					( oGate oPin )
				)
			)
			( Analysis
			)
		)
		( Attribute
			( Name "$location" )
			( Description "" )
			( Value
				( DataType ( dString ) )
				( Status  sProperty )
			)
			( Objects
				( ValidObjects  oAll )
			)
			( Analysis
			)
		)
		( Attribute
			( Name "$sec" )
			( Description "" )
			( Value
				( DataType ( dString ) )
				( Status  sProperty )
			)
			( Objects
				( ValidObjects  oAll )
			)
			( Analysis
			)
		)
		( Attribute
			( Name "RATED_CURRENT" )
			( Description " " )
			( Value
				( DataType ( dString ) )
				( Status  sProperty  sPackage )
			)
			( Objects
				( ValidObjects  oGate  oGateDefn  oBlock  oPart  oDesign  oSystem  oPartDefn )
				( NoInherit
					( oGate oPin )
				)
			)
			( Analysis
			)
		)
		( Attribute
			( Name "STATUS" )
			( Description " " )
			( Value
				( DataType ( dString ) )
				( Status  sProperty  sPackage )
			)
			( Objects
				( ValidObjects  oGate  oGateDefn  oBlock  oPart  oDesign  oSystem  oPartDefn )
				( NoInherit
					( oGate oPin )
				)
			)
			( Analysis
			)
		)
		( Attribute
			( Name "STTATUS" )
			( Description " " )
			( Value
				( DataType ( dString ) )
				( Status  sProperty  sPackage )
			)
			( Objects
				( ValidObjects  oGate  oGateDefn  oBlock  oPart  oDesign  oSystem  oPartDefn )
				( NoInherit
					( oGate oPin )
				)
			)
			( Analysis
			)
		)
		( Attribute
			( Name "SIDE_SKU" )
			( Description " " )
			( Value
				( DataType ( dString ) )
				( Status  sProperty  sPackage )
			)
			( Objects
				( ValidObjects  oGate  oGateDefn  oBlock  oPart  oDesign  oSystem  oPartDefn )
				( NoInherit
					( oGate oPin )
				)
			)
			( Analysis
			)
		)
	)
	( designConstraints
		( ruleChanges
			( allRules )
			( design "baseboard_fab2"
				( attribute "CDS_EXPORT_CONTENTS_MASK" "33330"
				)
				( attribute "CDS_EDIT_PNS_STATUS" "1"
					( Origin gFrontEnd )
				)
			)
			( signal "@baseboard_fab2_lib.baseboard_fab2(sch_1):a_cpu0_abc_rcomp0"
				( attribute "CDS_PHYS_NET_NAME" "A_CPU0_ABC_RCOMP0"
					( Origin gPackager )
				)
				( objectStatus "A_CPU0_ABC_RCOMP0" )
			)
			( signal "@baseboard_fab2_lib.baseboard_fab2(sch_1):a_cpu0_abc_rcomp1"
				( attribute "CDS_PHYS_NET_NAME" "A_CPU0_ABC_RCOMP1"
					( Origin gPackager )
				)
				( objectStatus "A_CPU0_ABC_RCOMP1" )
			)
			( signal "@baseboard_fab2_lib.baseboard_fab2(sch_1):a_cpu0_abc_rcomp2"
				( attribute "CDS_PHYS_NET_NAME" "A_CPU0_ABC_RCOMP2"
					( Origin gPackager )
				)
				( objectStatus "A_CPU0_ABC_RCOMP2" )
			)
			( signal "@baseboard_fab2_lib.baseboard_fab2(sch_1):a_cpu0_def_rcomp0"
				( attribute "CDS_PHYS_NET_NAME" "A_CPU0_DEF_RCOMP0"
					( Origin gPackager )
				)
				( objectStatus "A_CPU0_DEF_RCOMP0" )
			)
			( signal "@baseboard_fab2_lib.baseboard_fab2(sch_1):a_cpu0_def_rcomp1"
				( attribute "CDS_PHYS_NET_NAME" "A_CPU0_DEF_RCOMP1"
					( Origin gPackager )
				)
				( objectStatus "A_CPU0_DEF_RCOMP1" )
			)
			( signal "@baseboard_fab2_lib.baseboard_fab2(sch_1):a_cpu0_def_rcomp2"
				( attribute "CDS_PHYS_NET_NAME" "A_CPU0_DEF_RCOMP2"
					( Origin gPackager )
				)
				( objectStatus "A_CPU0_DEF_RCOMP2" )
			)
			( signal "@baseboard_fab2_lib.baseboard_fab2(sch_1):a_cpu0_mcp01_rbias"
				( attribute "CDS_PHYS_NET_NAME" "A_CPU0_MCP01_RBIAS"
					( Origin gPackager )
				)
				( objectStatus "A_CPU0_MCP01_RBIAS" )
			)
			( signal "@baseboard_fab2_lib.baseboard_fab2(sch_1):a_cpu0_pe012_rbias"
				( attribute "CDS_PHYS_NET_NAME" "A_CPU0_PE012_RBIAS"
					( Origin gPackager )
				)
				( objectStatus "A_CPU0_PE012_RBIAS" )
			)
			( signal "@baseboard_fab2_lib.baseboard_fab2(sch_1):a_cpu0_pe3_rbias"
				( attribute "CDS_PHYS_NET_NAME" "A_CPU0_PE3_RBIAS"
					( Origin gPackager )
				)
				( objectStatus "A_CPU0_PE3_RBIAS" )
			)
			( signal "@baseboard_fab2_lib.baseboard_fab2(sch_1):a_cpu0_upi01_rbias"
				( attribute "CDS_PHYS_NET_NAME" "A_CPU0_UPI01_RBIAS"
					( Origin gPackager )
				)
				( objectStatus "A_CPU0_UPI01_RBIAS" )
			)
			( signal "@baseboard_fab2_lib.baseboard_fab2(sch_1):a_cpu0_upi2_rbias"
				( attribute "CDS_PHYS_NET_NAME" "A_CPU0_UPI2_RBIAS"
					( Origin gPackager )
				)
				( objectStatus "A_CPU0_UPI2_RBIAS" )
			)
			( signal "@baseboard_fab2_lib.baseboard_fab2(sch_1):clk_100m_cpu0_bclk0_dn"
				( attribute "CDS_PHYS_NET_NAME" "CLK_100M_CPU0_BCLK0_DN"
					( Origin gPackager )
				)
				( objectStatus "CLK_100M_CPU0_BCLK0_DN" )
			)
			( signal "@baseboard_fab2_lib.baseboard_fab2(sch_1):clk_100m_cpu0_bclk0_dp"
				( attribute "CDS_PHYS_NET_NAME" "CLK_100M_CPU0_BCLK0_DP"
					( Origin gPackager )
				)
				( objectStatus "CLK_100M_CPU0_BCLK0_DP" )
			)
			( signal "@baseboard_fab2_lib.baseboard_fab2(sch_1):clk_100m_cpu0_bclk1_dn"
				( attribute "CDS_PHYS_NET_NAME" "CLK_100M_CPU0_BCLK1_DN"
					( Origin gPackager )
				)
				( objectStatus "CLK_100M_CPU0_BCLK1_DN" )
			)
			( signal "@baseboard_fab2_lib.baseboard_fab2(sch_1):clk_100m_cpu0_bclk1_dp"
				( attribute "CDS_PHYS_NET_NAME" "CLK_100M_CPU0_BCLK1_DP"
					( Origin gPackager )
				)
				( objectStatus "CLK_100M_CPU0_BCLK1_DP" )
			)
			( signal "@baseboard_fab2_lib.baseboard_fab2(sch_1):clk_100m_cpu0_bclk2_dn"
				( attribute "CDS_PHYS_NET_NAME" "CLK_100M_CPU0_BCLK2_DN"
					( Origin gPackager )
				)
				( objectStatus "CLK_100M_CPU0_BCLK2_DN" )
			)
			( signal "@baseboard_fab2_lib.baseboard_fab2(sch_1):clk_100m_cpu0_bclk2_dp"
				( attribute "CDS_PHYS_NET_NAME" "CLK_100M_CPU0_BCLK2_DP"
					( Origin gPackager )
				)
				( objectStatus "CLK_100M_CPU0_BCLK2_DP" )
			)
			( signal "@baseboard_fab2_lib.baseboard_fab2(sch_1):fm_cpu0_pkgid0"
				( attribute "CDS_PHYS_NET_NAME" "FM_CPU0_PKGID0"
					( Origin gPackager )
				)
				( objectStatus "FM_CPU0_PKGID0" )
			)
			( signal "@baseboard_fab2_lib.baseboard_fab2(sch_1):fm_cpu0_pkgid1"
				( attribute "CDS_PHYS_NET_NAME" "FM_CPU0_PKGID1"
					( Origin gPackager )
				)
				( objectStatus "FM_CPU0_PKGID1" )
			)
			( signal "@baseboard_fab2_lib.baseboard_fab2(sch_1):fm_cpu0_pkgid2"
				( attribute "CDS_PHYS_NET_NAME" "FM_CPU0_PKGID2"
					( Origin gPackager )
				)
				( objectStatus "FM_CPU0_PKGID2" )
			)
			( signal "@baseboard_fab2_lib.baseboard_fab2(sch_1):fm_cpu0_proc_id0"
				( attribute "CDS_PHYS_NET_NAME" "FM_CPU0_PROC_ID0"
					( Origin gPackager )
				)
				( objectStatus "FM_CPU0_PROC_ID0" )
			)
			( signal "@baseboard_fab2_lib.baseboard_fab2(sch_1):fm_cpu0_proc_id1"
				( attribute "CDS_PHYS_NET_NAME" "FM_CPU0_PROC_ID1"
					( Origin gPackager )
				)
				( objectStatus "FM_CPU0_PROC_ID1" )
			)
			( signal "@baseboard_fab2_lib.baseboard_fab2(sch_1):fm_cpu0_sktocc_lvt3_n"
				( attribute "CDS_PHYS_NET_NAME" "FM_CPU0_SKTOCC_LVT3_N"
					( Origin gPackager )
				)
				( attribute "PHYS_NET_NAME" "FM_CPU0_SKTOCC_LVT3_N"
					( Origin gPackager )
				)
				( objectStatus "FM_CPU0_SKTOCC_LVT3_N" )
			)
			( signal "@baseboard_fab2_lib.baseboard_fab2(sch_1):fm_cpu0_sm_wp"
				( attribute "CDS_PHYS_NET_NAME" "FM_CPU0_SM_WP"
					( Origin gPackager )
				)
				( objectStatus "FM_CPU0_SM_WP" )
			)
			( signal "@baseboard_fab2_lib.baseboard_fab2(sch_1):gnd"
				( alias ( signalRef "@baseboard_fab2_lib.baseboard_fab2(sch_1):page21_gnd") )
				( alias ( signalRef "@baseboard_fab2_lib.baseboard_fab2(sch_1):page22_gnd") )
				( alias ( signalRef "@baseboard_fab2_lib.baseboard_fab2(sch_1):page35_gnd") )
				( alias ( signalRef "@baseboard_fab2_lib.baseboard_fab2(sch_1):page37_gnd") )
				( alias ( signalRef "@baseboard_fab2_lib.baseboard_fab2(sch_1):page38_gnd") )
				( alias ( signalRef "@baseboard_fab2_lib.baseboard_fab2(sch_1):page40_gnd") )
				( alias ( signalRef "@baseboard_fab2_lib.baseboard_fab2(sch_1):page41_gnd") )
				( alias ( signalRef "@baseboard_fab2_lib.baseboard_fab2(sch_1):page42_gnd") )
				( alias ( signalRef "@baseboard_fab2_lib.baseboard_fab2(sch_1):page43_gnd") )
				( alias ( signalRef "@baseboard_fab2_lib.baseboard_fab2(sch_1):page44_gnd") )
				( alias ( signalRef "@baseboard_fab2_lib.baseboard_fab2(sch_1):page45_gnd") )
				( alias ( signalRef "@baseboard_fab2_lib.baseboard_fab2(sch_1):page46_gnd") )
				( alias ( signalRef "@baseboard_fab2_lib.baseboard_fab2(sch_1):page47_gnd") )
				( alias ( signalRef "@baseboard_fab2_lib.baseboard_fab2(sch_1):page48_gnd") )
				( alias ( signalRef "@baseboard_fab2_lib.baseboard_fab2(sch_1):page49_gnd") )
				( alias ( signalRef "@baseboard_fab2_lib.baseboard_fab2(sch_1):page50_gnd") )
				( alias ( signalRef "@baseboard_fab2_lib.baseboard_fab2(sch_1):page51_gnd") )
				( alias ( signalRef "@baseboard_fab2_lib.baseboard_fab2(sch_1):page52_gnd") )
				( alias ( signalRef "@baseboard_fab2_lib.baseboard_fab2(sch_1):page53_gnd") )
				( alias ( signalRef "@baseboard_fab2_lib.baseboard_fab2(sch_1):page54_gnd") )
				( alias ( signalRef "@baseboard_fab2_lib.baseboard_fab2(sch_1):page55_gnd") )
				( alias ( signalRef "@baseboard_fab2_lib.baseboard_fab2(sch_1):page56_gnd") )
				( alias ( signalRef "@baseboard_fab2_lib.baseboard_fab2(sch_1):page69_gnd") )
				( alias ( signalRef "@baseboard_fab2_lib.baseboard_fab2(sch_1):page71_gnd") )
				( alias ( signalRef "@baseboard_fab2_lib.baseboard_fab2(sch_1):page72_gnd") )
				( alias ( signalRef "@baseboard_fab2_lib.baseboard_fab2(sch_1):page74_gnd") )
				( alias ( signalRef "@baseboard_fab2_lib.baseboard_fab2(sch_1):page75_gnd") )
				( alias ( signalRef "@baseboard_fab2_lib.baseboard_fab2(sch_1):page76_gnd") )
				( alias ( signalRef "@baseboard_fab2_lib.baseboard_fab2(sch_1):page77_gnd") )
				( alias ( signalRef "@baseboard_fab2_lib.baseboard_fab2(sch_1):page78_gnd") )
				( alias ( signalRef "@baseboard_fab2_lib.baseboard_fab2(sch_1):page79_gnd") )
				( alias ( signalRef "@baseboard_fab2_lib.baseboard_fab2(sch_1):page80_gnd") )
				( alias ( signalRef "@baseboard_fab2_lib.baseboard_fab2(sch_1):page81_gnd") )
				( alias ( signalRef "@baseboard_fab2_lib.baseboard_fab2(sch_1):page82_gnd") )
				( alias ( signalRef "@baseboard_fab2_lib.baseboard_fab2(sch_1):page83_gnd") )
				( alias ( signalRef "@baseboard_fab2_lib.baseboard_fab2(sch_1):page84_gnd") )
				( alias ( signalRef "@baseboard_fab2_lib.baseboard_fab2(sch_1):page85_gnd") )
				( alias ( signalRef "@baseboard_fab2_lib.baseboard_fab2(sch_1):page86_gnd") )
				( alias ( signalRef "@baseboard_fab2_lib.baseboard_fab2(sch_1):page87_gnd") )
				( alias ( signalRef "@baseboard_fab2_lib.baseboard_fab2(sch_1):page88_gnd") )
				( alias ( signalRef "@baseboard_fab2_lib.baseboard_fab2(sch_1):page89_gnd") )
				( alias ( signalRef "@baseboard_fab2_lib.baseboard_fab2(sch_1):page90_gnd") )
				( alias ( signalRef "@baseboard_fab2_lib.baseboard_fab2(sch_1):page91_gnd") )
				( alias ( signalRef "@baseboard_fab2_lib.baseboard_fab2(sch_1):page92_gnd") )
				( alias ( signalRef "@baseboard_fab2_lib.baseboard_fab2(sch_1):page93_gnd") )
				( alias ( signalRef "@baseboard_fab2_lib.baseboard_fab2(sch_1):page94_gnd") )
				( alias ( signalRef "@baseboard_fab2_lib.baseboard_fab2(sch_1):page95_gnd") )
				( alias ( signalRef "@baseboard_fab2_lib.baseboard_fab2(sch_1):page96_gnd") )
				( alias ( signalRef "@baseboard_fab2_lib.baseboard_fab2(sch_1):page97_gnd") )
				( alias ( signalRef "@baseboard_fab2_lib.baseboard_fab2(sch_1):page98_gnd") )
				( alias ( signalRef "@baseboard_fab2_lib.baseboard_fab2(sch_1):page99_gnd") )
				( alias ( signalRef "@baseboard_fab2_lib.baseboard_fab2(sch_1):page100_gnd") )
				( alias ( signalRef "@baseboard_fab2_lib.baseboard_fab2(sch_1):page101_gnd") )
				( alias ( signalRef "@baseboard_fab2_lib.baseboard_fab2(sch_1):page102_gnd") )
				( alias ( signalRef "@baseboard_fab2_lib.baseboard_fab2(sch_1):page103_gnd") )
				( alias ( signalRef "@baseboard_fab2_lib.baseboard_fab2(sch_1):page104_gnd") )
				( alias ( signalRef "@baseboard_fab2_lib.baseboard_fab2(sch_1):page108_gnd") )
				( alias ( signalRef "@baseboard_fab2_lib.baseboard_fab2(sch_1):page109_gnd") )
				( alias ( signalRef "@baseboard_fab2_lib.baseboard_fab2(sch_1):page110_gnd") )
				( alias ( signalRef "@baseboard_fab2_lib.baseboard_fab2(sch_1):page111_gnd") )
				( alias ( signalRef "@baseboard_fab2_lib.baseboard_fab2(sch_1):page112_gnd") )
				( alias ( signalRef "@baseboard_fab2_lib.baseboard_fab2(sch_1):page113_gnd") )
				( alias ( signalRef "@baseboard_fab2_lib.baseboard_fab2(sch_1):page114_gnd") )
				( alias ( signalRef "@baseboard_fab2_lib.baseboard_fab2(sch_1):page115_gnd") )
				( alias ( signalRef "@baseboard_fab2_lib.baseboard_fab2(sch_1):page116_gnd") )
				( alias ( signalRef "@baseboard_fab2_lib.baseboard_fab2(sch_1):page118_gnd") )
				( alias ( signalRef "@baseboard_fab2_lib.baseboard_fab2(sch_1):page119_gnd") )
				( alias ( signalRef "@baseboard_fab2_lib.baseboard_fab2(sch_1):page120_gnd") )
				( alias ( signalRef "@baseboard_fab2_lib.baseboard_fab2(sch_1):page121_gnd") )
				( alias ( signalRef "@baseboard_fab2_lib.baseboard_fab2(sch_1):page123_gnd") )
				( alias ( signalRef "@baseboard_fab2_lib.baseboard_fab2(sch_1):page124_gnd") )
				( alias ( signalRef "@baseboard_fab2_lib.baseboard_fab2(sch_1):page125_gnd") )
				( alias ( signalRef "@baseboard_fab2_lib.baseboard_fab2(sch_1):page126_gnd") )
				( alias ( signalRef "@baseboard_fab2_lib.baseboard_fab2(sch_1):page127_gnd") )
				( alias ( signalRef "@baseboard_fab2_lib.baseboard_fab2(sch_1):page130_gnd") )
				( alias ( signalRef "@baseboard_fab2_lib.baseboard_fab2(sch_1):page131_gnd") )
				( alias ( signalRef "@baseboard_fab2_lib.baseboard_fab2(sch_1):page132_gnd") )
				( alias ( signalRef "@baseboard_fab2_lib.baseboard_fab2(sch_1):page133_gnd") )
				( alias ( signalRef "@baseboard_fab2_lib.baseboard_fab2(sch_1):page134_gnd") )
				( alias ( signalRef "@baseboard_fab2_lib.baseboard_fab2(sch_1):page135_gnd") )
				( alias ( signalRef "@baseboard_fab2_lib.baseboard_fab2(sch_1):page136_gnd") )
				( alias ( signalRef "@baseboard_fab2_lib.baseboard_fab2(sch_1):page137_gnd") )
				( alias ( signalRef "@baseboard_fab2_lib.baseboard_fab2(sch_1):page139_gnd") )
				( alias ( signalRef "@baseboard_fab2_lib.baseboard_fab2(sch_1):page140_gnd") )
				( alias ( signalRef "@baseboard_fab2_lib.baseboard_fab2(sch_1):page141_gnd") )
				( alias ( signalRef "@baseboard_fab2_lib.baseboard_fab2(sch_1):page142_gnd") )
				( alias ( signalRef "@baseboard_fab2_lib.baseboard_fab2(sch_1):page152_gnd") )
				( alias ( signalRef "@baseboard_fab2_lib.baseboard_fab2(sch_1):page153_gnd") )
				( alias ( signalRef "@baseboard_fab2_lib.baseboard_fab2(sch_1):page154_gnd") )
				( alias ( signalRef "@baseboard_fab2_lib.baseboard_fab2(sch_1):page155_gnd") )
				( alias ( signalRef "@baseboard_fab2_lib.baseboard_fab2(sch_1):page156_gnd") )
				( alias ( signalRef "@baseboard_fab2_lib.baseboard_fab2(sch_1):page157_gnd") )
				( alias ( signalRef "@baseboard_fab2_lib.baseboard_fab2(sch_1):page158_gnd") )
				( alias ( signalRef "@baseboard_fab2_lib.baseboard_fab2(sch_1):page161_gnd") )
				( alias ( signalRef "@baseboard_fab2_lib.baseboard_fab2(sch_1):page162_gnd") )
				( alias ( signalRef "@baseboard_fab2_lib.baseboard_fab2(sch_1):page163_gnd") )
				( alias ( signalRef "@baseboard_fab2_lib.baseboard_fab2(sch_1):page164_gnd") )
				( alias ( signalRef "@baseboard_fab2_lib.baseboard_fab2(sch_1):page165_gnd") )
				( alias ( signalRef "@baseboard_fab2_lib.baseboard_fab2(sch_1):page166_gnd") )
				( alias ( signalRef "@baseboard_fab2_lib.baseboard_fab2(sch_1):page167_gnd") )
				( alias ( signalRef "@baseboard_fab2_lib.baseboard_fab2(sch_1):page168_gnd") )
				( alias ( signalRef "@baseboard_fab2_lib.baseboard_fab2(sch_1):page169_gnd") )
				( alias ( signalRef "@baseboard_fab2_lib.baseboard_fab2(sch_1):page170_gnd") )
				( alias ( signalRef "@baseboard_fab2_lib.baseboard_fab2(sch_1):page172_gnd") )
				( alias ( signalRef "@baseboard_fab2_lib.baseboard_fab2(sch_1):page173_gnd") )
				( alias ( signalRef "@baseboard_fab2_lib.baseboard_fab2(sch_1):page174_gnd") )
				( alias ( signalRef "@baseboard_fab2_lib.baseboard_fab2(sch_1):page175_gnd") )
				( alias ( signalRef "@baseboard_fab2_lib.baseboard_fab2(sch_1):page176_gnd") )
				( alias ( signalRef "@baseboard_fab2_lib.baseboard_fab2(sch_1):page177_gnd") )
				( alias ( signalRef "@baseboard_fab2_lib.baseboard_fab2(sch_1):page181_gnd") )
				( alias ( signalRef "@baseboard_fab2_lib.baseboard_fab2(sch_1):page182_gnd") )
				( alias ( signalRef "@baseboard_fab2_lib.baseboard_fab2(sch_1):page183_gnd") )
				( alias ( signalRef "@baseboard_fab2_lib.baseboard_fab2(sch_1):page184_gnd") )
				( alias ( signalRef "@baseboard_fab2_lib.baseboard_fab2(sch_1):page185_gnd") )
				( alias ( signalRef "@baseboard_fab2_lib.baseboard_fab2(sch_1):page186_gnd") )
				( alias ( signalRef "@baseboard_fab2_lib.baseboard_fab2(sch_1):page187_gnd") )
				( alias ( signalRef "@baseboard_fab2_lib.baseboard_fab2(sch_1):page188_gnd") )
				( alias ( signalRef "@baseboard_fab2_lib.baseboard_fab2(sch_1):page189_gnd") )
				( alias ( signalRef "@baseboard_fab2_lib.baseboard_fab2(sch_1):page192_gnd") )
				( alias ( signalRef "@baseboard_fab2_lib.baseboard_fab2(sch_1):page193_gnd") )
				( alias ( signalRef "@baseboard_fab2_lib.baseboard_fab2(sch_1):page194_gnd") )
				( alias ( signalRef "@baseboard_fab2_lib.baseboard_fab2(sch_1):page195_gnd") )
				( alias ( signalRef "@baseboard_fab2_lib.baseboard_fab2(sch_1):page196_gnd") )
				( alias ( signalRef "@baseboard_fab2_lib.baseboard_fab2(sch_1):page197_gnd") )
				( alias ( signalRef "@baseboard_fab2_lib.baseboard_fab2(sch_1):page198_gnd") )
				( alias ( signalRef "@baseboard_fab2_lib.baseboard_fab2(sch_1):page199_gnd") )
				( alias ( signalRef "@baseboard_fab2_lib.baseboard_fab2(sch_1):page200_gnd") )
				( alias ( signalRef "@baseboard_fab2_lib.baseboard_fab2(sch_1):page201_gnd") )
				( alias ( signalRef "@baseboard_fab2_lib.baseboard_fab2(sch_1):page202_gnd") )
				( alias ( signalRef "@baseboard_fab2_lib.baseboard_fab2(sch_1):page203_gnd") )
				( alias ( signalRef "@baseboard_fab2_lib.baseboard_fab2(sch_1):page204_gnd") )
				( alias ( signalRef "@baseboard_fab2_lib.baseboard_fab2(sch_1):page205_gnd") )
				( alias ( signalRef "@baseboard_fab2_lib.baseboard_fab2(sch_1):page206_gnd") )
				( alias ( signalRef "@baseboard_fab2_lib.baseboard_fab2(sch_1):page207_gnd") )
				( alias ( signalRef "@baseboard_fab2_lib.baseboard_fab2(sch_1):page208_gnd") )
				( alias ( signalRef "@baseboard_fab2_lib.baseboard_fab2(sch_1):page209_gnd") )
				( alias ( signalRef "@baseboard_fab2_lib.baseboard_fab2(sch_1):page210_gnd") )
				( alias ( signalRef "@baseboard_fab2_lib.baseboard_fab2(sch_1):page211_gnd") )
				( alias ( signalRef "@baseboard_fab2_lib.baseboard_fab2(sch_1):page212_gnd") )
				( alias ( signalRef "@baseboard_fab2_lib.baseboard_fab2(sch_1):page213_gnd") )
				( alias ( signalRef "@baseboard_fab2_lib.baseboard_fab2(sch_1):page214_gnd") )
				( alias ( signalRef "@baseboard_fab2_lib.baseboard_fab2(sch_1):page215_gnd") )
				( alias ( signalRef "@baseboard_fab2_lib.baseboard_fab2(sch_1):page216_gnd") )
				( alias ( signalRef "@baseboard_fab2_lib.baseboard_fab2(sch_1):page217_gnd") )
				( alias ( signalRef "@baseboard_fab2_lib.baseboard_fab2(sch_1):page218_gnd") )
				( alias ( signalRef "@baseboard_fab2_lib.baseboard_fab2(sch_1):page219_gnd") )
				( alias ( signalRef "@baseboard_fab2_lib.baseboard_fab2(sch_1):page220_gnd") )
				( alias ( signalRef "@baseboard_fab2_lib.baseboard_fab2(sch_1):page221_gnd") )
				( alias ( signalRef "@baseboard_fab2_lib.baseboard_fab2(sch_1):page222_gnd") )
				( alias ( signalRef "@baseboard_fab2_lib.baseboard_fab2(sch_1):page223_gnd") )
				( alias ( signalRef "@baseboard_fab2_lib.baseboard_fab2(sch_1):page224_gnd") )
				( alias ( signalRef "@baseboard_fab2_lib.baseboard_fab2(sch_1):page225_gnd") )
				( alias ( signalRef "@baseboard_fab2_lib.baseboard_fab2(sch_1):page226_gnd") )
				( alias ( signalRef "@baseboard_fab2_lib.baseboard_fab2(sch_1):page227_gnd") )
				( alias ( signalRef "@baseboard_fab2_lib.baseboard_fab2(sch_1):page228_gnd") )
				( alias ( signalRef "@baseboard_fab2_lib.baseboard_fab2(sch_1):page229_gnd") )
				( alias ( signalRef "@baseboard_fab2_lib.baseboard_fab2(sch_1):page230_gnd") )
				( alias ( signalRef "@baseboard_fab2_lib.baseboard_fab2(sch_1):page231_gnd") )
				( alias ( signalRef "@baseboard_fab2_lib.baseboard_fab2(sch_1):page232_gnd") )
				( alias ( signalRef "@baseboard_fab2_lib.baseboard_fab2(sch_1):page233_gnd") )
				( alias ( signalRef "@baseboard_fab2_lib.baseboard_fab2(sch_1):page234_gnd") )
				( alias ( signalRef "@baseboard_fab2_lib.baseboard_fab2(sch_1):page235_gnd") )
				( alias ( signalRef "@baseboard_fab2_lib.baseboard_fab2(sch_1):page236_gnd") )
				( alias ( signalRef "@baseboard_fab2_lib.baseboard_fab2(sch_1):page237_gnd") )
				( alias ( signalRef "@baseboard_fab2_lib.baseboard_fab2(sch_1):page238_gnd") )
				( alias ( signalRef "@baseboard_fab2_lib.baseboard_fab2(sch_1):page239_gnd") )
				( alias ( signalRef "@baseboard_fab2_lib.baseboard_fab2(sch_1):page240_gnd") )
				( alias ( signalRef "@baseboard_fab2_lib.baseboard_fab2(sch_1):page241_gnd") )
				( alias ( signalRef "@baseboard_fab2_lib.baseboard_fab2(sch_1):page242_gnd") )
				( alias ( signalRef "@baseboard_fab2_lib.baseboard_fab2(sch_1):page243_gnd") )
				( alias ( signalRef "@baseboard_fab2_lib.baseboard_fab2(sch_1):page245_gnd") )
				( alias ( signalRef "@baseboard_fab2_lib.baseboard_fab2(sch_1):page246_gnd") )
				( alias ( signalRef "@baseboard_fab2_lib.baseboard_fab2(sch_1):page247_gnd") )
				( alias ( signalRef "@baseboard_fab2_lib.baseboard_fab2(sch_1):page249_gnd") )
				( alias ( signalRef "@baseboard_fab2_lib.baseboard_fab2(sch_1):page150_gnd") )
				( alias ( signalRef "@baseboard_fab2_lib.baseboard_fab2(sch_1):page143_gnd") )
				( alias ( signalRef "@baseboard_fab2_lib.baseboard_fab2(sch_1):page144_gnd") )
				( alias ( signalRef "@baseboard_fab2_lib.baseboard_fab2(sch_1):page145_gnd") )
				( alias ( signalRef "@baseboard_fab2_lib.baseboard_fab2(sch_1):page146_gnd") )
				( alias ( signalRef "@baseboard_fab2_lib.baseboard_fab2(sch_1):page147_gnd") )
				( alias ( signalRef "@baseboard_fab2_lib.baseboard_fab2(sch_1):page148_gnd") )
				( alias ( signalRef "@baseboard_fab2_lib.baseboard_fab2(sch_1):page151_gnd") )
				( alias ( signalRef "@baseboard_fab2_lib.baseboard_fab2(sch_1):page149_gnd") )
				( attribute "CDS_PHYS_NET_NAME" "GND"
					( Origin gPackager )
				)
				( attribute "PHYS_NET_NAME" "GND"
					( Origin gPackager )
				)
				( attribute "VOLTAGE" "0.0V"
					( Units "uVoltage" "V" 1.000000)
					( Status sAliasFlattened )
					( Status sAliasConflict )
					( Origin gFrontEnd )
				)
				( attribute "BOM_COST" "TBD"
					( Status sAliasFlattened )
					( Origin gFrontEnd )
				)
				( attribute "ROOM" "TBD"
					( Status sAliasFlattened )
					( Origin gFrontEnd )
				)
				( objectStatus "GND" )
			)
			( signal "@baseboard_fab2_lib.baseboard_fab2(sch_1):page21_gnd"
				( attribute "VOLTAGE" "0.0V"
					( Units "uVoltage" "V" 1.000000)
					( Origin gFrontEnd )
				)
				( objectFlag fObjectAlias )
				( objectStatus "page21_gnd" )
			)
			( signal "@baseboard_fab2_lib.baseboard_fab2(sch_1):page22_gnd"
				( attribute "VOLTAGE" "0.0V"
					( Units "uVoltage" "V" 1.000000)
					( Origin gFrontEnd )
				)
				( objectFlag fObjectAlias )
				( objectStatus "page22_gnd" )
			)
			( signal "@baseboard_fab2_lib.baseboard_fab2(sch_1):page35_gnd"
				( attribute "VOLTAGE" "0.0V"
					( Units "uVoltage" "V" 1.000000)
					( Origin gFrontEnd )
				)
				( objectFlag fObjectAlias )
				( objectStatus "page35_gnd" )
			)
			( signal "@baseboard_fab2_lib.baseboard_fab2(sch_1):page37_gnd"
				( attribute "VOLTAGE" "0.0V"
					( Units "uVoltage" "V" 1.000000)
					( Origin gFrontEnd )
				)
				( objectFlag fObjectAlias )
				( objectStatus "page37_gnd" )
			)
			( signal "@baseboard_fab2_lib.baseboard_fab2(sch_1):page38_gnd"
				( attribute "VOLTAGE" "0.0V"
					( Units "uVoltage" "V" 1.000000)
					( Origin gFrontEnd )
				)
				( objectFlag fObjectAlias )
				( objectStatus "page38_gnd" )
			)
			( signal "@baseboard_fab2_lib.baseboard_fab2(sch_1):page40_gnd"
				( attribute "VOLTAGE" "0.0V"
					( Units "uVoltage" "V" 1.000000)
					( Origin gFrontEnd )
				)
				( objectFlag fObjectAlias )
				( objectStatus "page40_gnd" )
			)
			( signal "@baseboard_fab2_lib.baseboard_fab2(sch_1):page41_gnd"
				( attribute "VOLTAGE" "0.0V"
					( Units "uVoltage" "V" 1.000000)
					( Origin gFrontEnd )
				)
				( objectFlag fObjectAlias )
				( objectStatus "page41_gnd" )
			)
			( signal "@baseboard_fab2_lib.baseboard_fab2(sch_1):page42_gnd"
				( attribute "VOLTAGE" "0"
					( Units "uVoltage" "V" 1.000000)
					( Origin gFrontEnd )
				)
				( objectFlag fObjectAlias )
				( objectStatus "page42_gnd" )
			)
			( signal "@baseboard_fab2_lib.baseboard_fab2(sch_1):page43_gnd"
				( attribute "VOLTAGE" "0"
					( Units "uVoltage" "V" 1.000000)
					( Origin gFrontEnd )
				)
				( objectFlag fObjectAlias )
				( objectStatus "page43_gnd" )
			)
			( signal "@baseboard_fab2_lib.baseboard_fab2(sch_1):page44_gnd"
				( attribute "VOLTAGE" "0"
					( Units "uVoltage" "V" 1.000000)
					( Origin gFrontEnd )
				)
				( objectFlag fObjectAlias )
				( objectStatus "page44_gnd" )
			)
			( signal "@baseboard_fab2_lib.baseboard_fab2(sch_1):page45_gnd"
				( attribute "VOLTAGE" "0"
					( Units "uVoltage" "V" 1.000000)
					( Origin gFrontEnd )
				)
				( objectFlag fObjectAlias )
				( objectStatus "page45_gnd" )
			)
			( signal "@baseboard_fab2_lib.baseboard_fab2(sch_1):page46_gnd"
				( attribute "VOLTAGE" "0"
					( Units "uVoltage" "V" 1.000000)
					( Origin gFrontEnd )
				)
				( objectFlag fObjectAlias )
				( objectStatus "page46_gnd" )
			)
			( signal "@baseboard_fab2_lib.baseboard_fab2(sch_1):page47_gnd"
				( attribute "VOLTAGE" "0"
					( Units "uVoltage" "V" 1.000000)
					( Origin gFrontEnd )
				)
				( objectFlag fObjectAlias )
				( objectStatus "page47_gnd" )
			)
			( signal "@baseboard_fab2_lib.baseboard_fab2(sch_1):page48_gnd"
				( attribute "VOLTAGE" "0"
					( Units "uVoltage" "V" 1.000000)
					( Origin gFrontEnd )
				)
				( objectFlag fObjectAlias )
				( objectStatus "page48_gnd" )
			)
			( signal "@baseboard_fab2_lib.baseboard_fab2(sch_1):page49_gnd"
				( attribute "BOM_COST" "TBD"
					( Origin gFrontEnd )
				)
				( attribute "ROOM" "TBD"
					( Origin gFrontEnd )
				)
				( attribute "VOLTAGE" "0"
					( Units "uVoltage" "V" 1.000000)
					( Origin gFrontEnd )
				)
				( objectFlag fObjectAlias )
				( objectStatus "page49_gnd" )
			)
			( signal "@baseboard_fab2_lib.baseboard_fab2(sch_1):page50_gnd"
				( attribute "VOLTAGE" "0"
					( Units "uVoltage" "V" 1.000000)
					( Origin gFrontEnd )
				)
				( objectFlag fObjectAlias )
				( objectStatus "page50_gnd" )
			)
			( signal "@baseboard_fab2_lib.baseboard_fab2(sch_1):page51_gnd"
				( attribute "VOLTAGE" "0"
					( Units "uVoltage" "V" 1.000000)
					( Origin gFrontEnd )
				)
				( objectFlag fObjectAlias )
				( objectStatus "page51_gnd" )
			)
			( signal "@baseboard_fab2_lib.baseboard_fab2(sch_1):page52_gnd"
				( attribute "VOLTAGE" "0"
					( Units "uVoltage" "V" 1.000000)
					( Origin gFrontEnd )
				)
				( objectFlag fObjectAlias )
				( objectStatus "page52_gnd" )
			)
			( signal "@baseboard_fab2_lib.baseboard_fab2(sch_1):page53_gnd"
				( attribute "VOLTAGE" "0"
					( Units "uVoltage" "V" 1.000000)
					( Origin gFrontEnd )
				)
				( objectFlag fObjectAlias )
				( objectStatus "page53_gnd" )
			)
			( signal "@baseboard_fab2_lib.baseboard_fab2(sch_1):page54_gnd"
				( attribute "VOLTAGE" "0"
					( Units "uVoltage" "V" 1.000000)
					( Origin gFrontEnd )
				)
				( objectFlag fObjectAlias )
				( objectStatus "page54_gnd" )
			)
			( signal "@baseboard_fab2_lib.baseboard_fab2(sch_1):page55_gnd"
				( attribute "VOLTAGE" "0.0V"
					( Units "uVoltage" "V" 1.000000)
					( Origin gFrontEnd )
				)
				( objectFlag fObjectAlias )
				( objectStatus "page55_gnd" )
			)
			( signal "@baseboard_fab2_lib.baseboard_fab2(sch_1):page56_gnd"
				( attribute "VOLTAGE" "0.0V"
					( Units "uVoltage" "V" 1.000000)
					( Origin gFrontEnd )
				)
				( objectFlag fObjectAlias )
				( objectStatus "page56_gnd" )
			)
			( signal "@baseboard_fab2_lib.baseboard_fab2(sch_1):page69_gnd"
				( attribute "VOLTAGE" "0.0V"
					( Units "uVoltage" "V" 1.000000)
					( Origin gFrontEnd )
				)
				( objectFlag fObjectAlias )
				( objectStatus "page69_gnd" )
			)
			( signal "@baseboard_fab2_lib.baseboard_fab2(sch_1):page71_gnd"
				( attribute "VOLTAGE" "0.0V"
					( Units "uVoltage" "V" 1.000000)
					( Origin gFrontEnd )
				)
				( objectFlag fObjectAlias )
				( objectStatus "page71_gnd" )
			)
			( signal "@baseboard_fab2_lib.baseboard_fab2(sch_1):page72_gnd"
				( attribute "VOLTAGE" "0.0V"
					( Units "uVoltage" "V" 1.000000)
					( Origin gFrontEnd )
				)
				( objectFlag fObjectAlias )
				( objectStatus "page72_gnd" )
			)
			( signal "@baseboard_fab2_lib.baseboard_fab2(sch_1):page74_gnd"
				( attribute "VOLTAGE" "0.0V"
					( Units "uVoltage" "V" 1.000000)
					( Origin gFrontEnd )
				)
				( objectFlag fObjectAlias )
				( objectStatus "page74_gnd" )
			)
			( signal "@baseboard_fab2_lib.baseboard_fab2(sch_1):page75_gnd"
				( attribute "VOLTAGE" "0.0V"
					( Units "uVoltage" "V" 1.000000)
					( Origin gFrontEnd )
				)
				( objectFlag fObjectAlias )
				( objectStatus "page75_gnd" )
			)
			( signal "@baseboard_fab2_lib.baseboard_fab2(sch_1):page76_gnd"
				( attribute "VOLTAGE" "0"
					( Units "uVoltage" "V" 1.000000)
					( Origin gFrontEnd )
				)
				( objectFlag fObjectAlias )
				( objectStatus "page76_gnd" )
			)
			( signal "@baseboard_fab2_lib.baseboard_fab2(sch_1):page77_gnd"
				( attribute "VOLTAGE" "0"
					( Units "uVoltage" "V" 1.000000)
					( Origin gFrontEnd )
				)
				( objectFlag fObjectAlias )
				( objectStatus "page77_gnd" )
			)
			( signal "@baseboard_fab2_lib.baseboard_fab2(sch_1):page78_gnd"
				( attribute "VOLTAGE" "0.0V"
					( Units "uVoltage" "V" 1.000000)
					( Origin gFrontEnd )
				)
				( objectFlag fObjectAlias )
				( objectStatus "page78_gnd" )
			)
			( signal "@baseboard_fab2_lib.baseboard_fab2(sch_1):page79_gnd"
				( attribute "VOLTAGE" "0"
					( Units "uVoltage" "V" 1.000000)
					( Origin gFrontEnd )
				)
				( objectFlag fObjectAlias )
				( objectStatus "page79_gnd" )
			)
			( signal "@baseboard_fab2_lib.baseboard_fab2(sch_1):page80_gnd"
				( attribute "VOLTAGE" "0"
					( Units "uVoltage" "V" 1.000000)
					( Origin gFrontEnd )
				)
				( objectFlag fObjectAlias )
				( objectStatus "page80_gnd" )
			)
			( signal "@baseboard_fab2_lib.baseboard_fab2(sch_1):page81_gnd"
				( attribute "VOLTAGE" "0"
					( Units "uVoltage" "V" 1.000000)
					( Origin gFrontEnd )
				)
				( objectFlag fObjectAlias )
				( objectStatus "page81_gnd" )
			)
			( signal "@baseboard_fab2_lib.baseboard_fab2(sch_1):page82_gnd"
				( attribute "VOLTAGE" "0"
					( Units "uVoltage" "V" 1.000000)
					( Origin gFrontEnd )
				)
				( objectFlag fObjectAlias )
				( objectStatus "page82_gnd" )
			)
			( signal "@baseboard_fab2_lib.baseboard_fab2(sch_1):page83_gnd"
				( attribute "VOLTAGE" "0"
					( Units "uVoltage" "V" 1.000000)
					( Origin gFrontEnd )
				)
				( objectFlag fObjectAlias )
				( objectStatus "page83_gnd" )
			)
			( signal "@baseboard_fab2_lib.baseboard_fab2(sch_1):page84_gnd"
				( attribute "VOLTAGE" "0"
					( Units "uVoltage" "V" 1.000000)
					( Origin gFrontEnd )
				)
				( objectFlag fObjectAlias )
				( objectStatus "page84_gnd" )
			)
			( signal "@baseboard_fab2_lib.baseboard_fab2(sch_1):page85_gnd"
				( attribute "VOLTAGE" "0"
					( Units "uVoltage" "V" 1.000000)
					( Origin gFrontEnd )
				)
				( objectFlag fObjectAlias )
				( objectStatus "page85_gnd" )
			)
			( signal "@baseboard_fab2_lib.baseboard_fab2(sch_1):page86_gnd"
				( attribute "VOLTAGE" "0"
					( Units "uVoltage" "V" 1.000000)
					( Origin gFrontEnd )
				)
				( objectFlag fObjectAlias )
				( objectStatus "page86_gnd" )
			)
			( signal "@baseboard_fab2_lib.baseboard_fab2(sch_1):page87_gnd"
				( attribute "VOLTAGE" "0"
					( Units "uVoltage" "V" 1.000000)
					( Origin gFrontEnd )
				)
				( objectFlag fObjectAlias )
				( objectStatus "page87_gnd" )
			)
			( signal "@baseboard_fab2_lib.baseboard_fab2(sch_1):page88_gnd"
				( attribute "VOLTAGE" "0"
					( Units "uVoltage" "V" 1.000000)
					( Origin gFrontEnd )
				)
				( objectFlag fObjectAlias )
				( objectStatus "page88_gnd" )
			)
			( signal "@baseboard_fab2_lib.baseboard_fab2(sch_1):page89_gnd"
				( attribute "VOLTAGE" "0.0V"
					( Units "uVoltage" "V" 1.000000)
					( Origin gFrontEnd )
				)
				( objectFlag fObjectAlias )
				( objectStatus "page89_gnd" )
			)
			( signal "@baseboard_fab2_lib.baseboard_fab2(sch_1):page90_gnd"
				( attribute "VOLTAGE" "0"
					( Units "uVoltage" "V" 1.000000)
					( Origin gFrontEnd )
				)
				( objectFlag fObjectAlias )
				( objectStatus "page90_gnd" )
			)
			( signal "@baseboard_fab2_lib.baseboard_fab2(sch_1):page91_gnd"
				( attribute "VOLTAGE" "0.0V"
					( Units "uVoltage" "V" 1.000000)
					( Origin gFrontEnd )
				)
				( objectFlag fObjectAlias )
				( objectStatus "page91_gnd" )
			)
			( signal "@baseboard_fab2_lib.baseboard_fab2(sch_1):page92_gnd"
				( attribute "VOLTAGE" "0"
					( Units "uVoltage" "V" 1.000000)
					( Origin gFrontEnd )
				)
				( objectFlag fObjectAlias )
				( objectStatus "page92_gnd" )
			)
			( signal "@baseboard_fab2_lib.baseboard_fab2(sch_1):page93_gnd"
				( attribute "VOLTAGE" "0"
					( Units "uVoltage" "V" 1.000000)
					( Origin gFrontEnd )
				)
				( objectFlag fObjectAlias )
				( objectStatus "page93_gnd" )
			)
			( signal "@baseboard_fab2_lib.baseboard_fab2(sch_1):page94_gnd"
				( attribute "VOLTAGE" "0"
					( Units "uVoltage" "V" 1.000000)
					( Origin gFrontEnd )
				)
				( objectFlag fObjectAlias )
				( objectStatus "page94_gnd" )
			)
			( signal "@baseboard_fab2_lib.baseboard_fab2(sch_1):page95_gnd"
				( attribute "VOLTAGE" "0"
					( Units "uVoltage" "V" 1.000000)
					( Origin gFrontEnd )
				)
				( objectFlag fObjectAlias )
				( objectStatus "page95_gnd" )
			)
			( signal "@baseboard_fab2_lib.baseboard_fab2(sch_1):page96_gnd"
				( attribute "VOLTAGE" "0.0V"
					( Units "uVoltage" "V" 1.000000)
					( Origin gFrontEnd )
				)
				( objectFlag fObjectAlias )
				( objectStatus "page96_gnd" )
			)
			( signal "@baseboard_fab2_lib.baseboard_fab2(sch_1):page97_gnd"
				( attribute "VOLTAGE" "0.0V"
					( Units "uVoltage" "V" 1.000000)
					( Origin gFrontEnd )
				)
				( objectFlag fObjectAlias )
				( objectStatus "page97_gnd" )
			)
			( signal "@baseboard_fab2_lib.baseboard_fab2(sch_1):page98_gnd"
				( attribute "VOLTAGE" "0"
					( Units "uVoltage" "V" 1.000000)
					( Origin gFrontEnd )
				)
				( objectFlag fObjectAlias )
				( objectStatus "page98_gnd" )
			)
			( signal "@baseboard_fab2_lib.baseboard_fab2(sch_1):page99_gnd"
				( attribute "VOLTAGE" "0"
					( Units "uVoltage" "V" 1.000000)
					( Origin gFrontEnd )
				)
				( objectFlag fObjectAlias )
				( objectStatus "page99_gnd" )
			)
			( signal "@baseboard_fab2_lib.baseboard_fab2(sch_1):page100_gnd"
				( attribute "VOLTAGE" "0"
					( Units "uVoltage" "V" 1.000000)
					( Origin gFrontEnd )
				)
				( objectFlag fObjectAlias )
				( objectStatus "page100_gnd" )
			)
			( signal "@baseboard_fab2_lib.baseboard_fab2(sch_1):page101_gnd"
				( attribute "VOLTAGE" "0.0V"
					( Units "uVoltage" "V" 1.000000)
					( Origin gFrontEnd )
				)
				( objectFlag fObjectAlias )
				( objectStatus "page101_gnd" )
			)
			( signal "@baseboard_fab2_lib.baseboard_fab2(sch_1):page102_gnd"
				( attribute "VOLTAGE" "0.0V"
					( Units "uVoltage" "V" 1.000000)
					( Origin gFrontEnd )
				)
				( objectFlag fObjectAlias )
				( objectStatus "page102_gnd" )
			)
			( signal "@baseboard_fab2_lib.baseboard_fab2(sch_1):page103_gnd"
				( attribute "VOLTAGE" "0.0V"
					( Units "uVoltage" "V" 1.000000)
					( Origin gFrontEnd )
				)
				( objectFlag fObjectAlias )
				( objectStatus "page103_gnd" )
			)
			( signal "@baseboard_fab2_lib.baseboard_fab2(sch_1):page104_gnd"
				( attribute "VOLTAGE" "0.0V"
					( Units "uVoltage" "V" 1.000000)
					( Origin gFrontEnd )
				)
				( objectFlag fObjectAlias )
				( objectStatus "page104_gnd" )
			)
			( signal "@baseboard_fab2_lib.baseboard_fab2(sch_1):page108_gnd"
				( attribute "VOLTAGE" "0"
					( Units "uVoltage" "V" 1.000000)
					( Origin gFrontEnd )
				)
				( objectFlag fObjectAlias )
				( objectStatus "page108_gnd" )
			)
			( signal "@baseboard_fab2_lib.baseboard_fab2(sch_1):page109_gnd"
				( attribute "VOLTAGE" "0"
					( Units "uVoltage" "V" 1.000000)
					( Origin gFrontEnd )
				)
				( objectFlag fObjectAlias )
				( objectStatus "page109_gnd" )
			)
			( signal "@baseboard_fab2_lib.baseboard_fab2(sch_1):page110_gnd"
				( attribute "VOLTAGE" "0.0V"
					( Units "uVoltage" "V" 1.000000)
					( Origin gFrontEnd )
				)
				( objectFlag fObjectAlias )
				( objectStatus "page110_gnd" )
			)
			( signal "@baseboard_fab2_lib.baseboard_fab2(sch_1):page111_gnd"
				( attribute "VOLTAGE" "0.0V"
					( Units "uVoltage" "V" 1.000000)
					( Origin gFrontEnd )
				)
				( objectFlag fObjectAlias )
				( objectStatus "page111_gnd" )
			)
			( signal "@baseboard_fab2_lib.baseboard_fab2(sch_1):page112_gnd"
				( attribute "VOLTAGE" "0.0V"
					( Units "uVoltage" "V" 1.000000)
					( Origin gFrontEnd )
				)
				( objectFlag fObjectAlias )
				( objectStatus "page112_gnd" )
			)
			( signal "@baseboard_fab2_lib.baseboard_fab2(sch_1):page113_gnd"
				( attribute "VOLTAGE" "0.0V"
					( Units "uVoltage" "V" 1.000000)
					( Origin gFrontEnd )
				)
				( objectFlag fObjectAlias )
				( objectStatus "page113_gnd" )
			)
			( signal "@baseboard_fab2_lib.baseboard_fab2(sch_1):page114_gnd"
				( attribute "VOLTAGE" "0.0V"
					( Units "uVoltage" "V" 1.000000)
					( Origin gFrontEnd )
				)
				( objectFlag fObjectAlias )
				( objectStatus "page114_gnd" )
			)
			( signal "@baseboard_fab2_lib.baseboard_fab2(sch_1):page115_gnd"
				( attribute "VOLTAGE" "0.0V"
					( Units "uVoltage" "V" 1.000000)
					( Origin gFrontEnd )
				)
				( objectFlag fObjectAlias )
				( objectStatus "page115_gnd" )
			)
			( signal "@baseboard_fab2_lib.baseboard_fab2(sch_1):page116_gnd"
				( attribute "VOLTAGE" "0.0V"
					( Units "uVoltage" "V" 1.000000)
					( Origin gFrontEnd )
				)
				( objectFlag fObjectAlias )
				( objectStatus "page116_gnd" )
			)
			( signal "@baseboard_fab2_lib.baseboard_fab2(sch_1):page118_gnd"
				( attribute "VOLTAGE" "0.0V"
					( Units "uVoltage" "V" 1.000000)
					( Origin gFrontEnd )
				)
				( objectFlag fObjectAlias )
				( objectStatus "page118_gnd" )
			)
			( signal "@baseboard_fab2_lib.baseboard_fab2(sch_1):page119_gnd"
				( attribute "VOLTAGE" "0.0V"
					( Units "uVoltage" "V" 1.000000)
					( Origin gFrontEnd )
				)
				( objectFlag fObjectAlias )
				( objectStatus "page119_gnd" )
			)
			( signal "@baseboard_fab2_lib.baseboard_fab2(sch_1):page120_gnd"
				( attribute "VOLTAGE" "0.0V"
					( Units "uVoltage" "V" 1.000000)
					( Origin gFrontEnd )
				)
				( objectFlag fObjectAlias )
				( objectStatus "page120_gnd" )
			)
			( signal "@baseboard_fab2_lib.baseboard_fab2(sch_1):page121_gnd"
				( attribute "VOLTAGE" "0.0V"
					( Units "uVoltage" "V" 1.000000)
					( Origin gFrontEnd )
				)
				( objectFlag fObjectAlias )
				( objectStatus "page121_gnd" )
			)
			( signal "@baseboard_fab2_lib.baseboard_fab2(sch_1):page123_gnd"
				( attribute "VOLTAGE" "0.0V"
					( Units "uVoltage" "V" 1.000000)
					( Origin gFrontEnd )
				)
				( objectFlag fObjectAlias )
				( objectStatus "page123_gnd" )
			)
			( signal "@baseboard_fab2_lib.baseboard_fab2(sch_1):page124_gnd"
				( attribute "VOLTAGE" "0.0V"
					( Units "uVoltage" "V" 1.000000)
					( Origin gFrontEnd )
				)
				( objectFlag fObjectAlias )
				( objectStatus "page124_gnd" )
			)
			( signal "@baseboard_fab2_lib.baseboard_fab2(sch_1):page125_gnd"
				( attribute "VOLTAGE" "0.0V"
					( Units "uVoltage" "V" 1.000000)
					( Origin gFrontEnd )
				)
				( objectFlag fObjectAlias )
				( objectStatus "page125_gnd" )
			)
			( signal "@baseboard_fab2_lib.baseboard_fab2(sch_1):page126_gnd"
				( attribute "VOLTAGE" "0.0V"
					( Units "uVoltage" "V" 1.000000)
					( Origin gFrontEnd )
				)
				( objectFlag fObjectAlias )
				( objectStatus "page126_gnd" )
			)
			( signal "@baseboard_fab2_lib.baseboard_fab2(sch_1):page127_gnd"
				( attribute "VOLTAGE" "0.0V"
					( Units "uVoltage" "V" 1.000000)
					( Origin gFrontEnd )
				)
				( objectFlag fObjectAlias )
				( objectStatus "page127_gnd" )
			)
			( signal "@baseboard_fab2_lib.baseboard_fab2(sch_1):page130_gnd"
				( attribute "VOLTAGE" "0"
					( Units "uVoltage" "V" 1.000000)
					( Origin gFrontEnd )
				)
				( objectFlag fObjectAlias )
				( objectStatus "page130_gnd" )
			)
			( signal "@baseboard_fab2_lib.baseboard_fab2(sch_1):page131_gnd"
				( attribute "VOLTAGE" "0"
					( Units "uVoltage" "V" 1.000000)
					( Origin gFrontEnd )
				)
				( objectFlag fObjectAlias )
				( objectStatus "page131_gnd" )
			)
			( signal "@baseboard_fab2_lib.baseboard_fab2(sch_1):page132_gnd"
				( attribute "VOLTAGE" "0.0V"
					( Units "uVoltage" "V" 1.000000)
					( Origin gFrontEnd )
				)
				( objectFlag fObjectAlias )
				( objectStatus "page132_gnd" )
			)
			( signal "@baseboard_fab2_lib.baseboard_fab2(sch_1):page133_gnd"
				( attribute "VOLTAGE" "0"
					( Units "uVoltage" "V" 1.000000)
					( Origin gFrontEnd )
				)
				( objectFlag fObjectAlias )
				( objectStatus "page133_gnd" )
			)
			( signal "@baseboard_fab2_lib.baseboard_fab2(sch_1):page134_gnd"
				( attribute "VOLTAGE" "0"
					( Units "uVoltage" "V" 1.000000)
					( Origin gFrontEnd )
				)
				( objectFlag fObjectAlias )
				( objectStatus "page134_gnd" )
			)
			( signal "@baseboard_fab2_lib.baseboard_fab2(sch_1):page135_gnd"
				( attribute "VOLTAGE" "0.0V"
					( Units "uVoltage" "V" 1.000000)
					( Origin gFrontEnd )
				)
				( objectFlag fObjectAlias )
				( objectStatus "page135_gnd" )
			)
			( signal "@baseboard_fab2_lib.baseboard_fab2(sch_1):page136_gnd"
				( attribute "VOLTAGE" "0"
					( Units "uVoltage" "V" 1.000000)
					( Origin gFrontEnd )
				)
				( objectFlag fObjectAlias )
				( objectStatus "page136_gnd" )
			)
			( signal "@baseboard_fab2_lib.baseboard_fab2(sch_1):page137_gnd"
				( attribute "VOLTAGE" "0"
					( Units "uVoltage" "V" 1.000000)
					( Origin gFrontEnd )
				)
				( objectFlag fObjectAlias )
				( objectStatus "page137_gnd" )
			)
			( signal "@baseboard_fab2_lib.baseboard_fab2(sch_1):page139_gnd"
				( attribute "VOLTAGE" "0.0V"
					( Units "uVoltage" "V" 1.000000)
					( Origin gFrontEnd )
				)
				( objectFlag fObjectAlias )
				( objectStatus "page139_gnd" )
			)
			( signal "@baseboard_fab2_lib.baseboard_fab2(sch_1):page140_gnd"
				( attribute "VOLTAGE" "0.0V"
					( Units "uVoltage" "V" 1.000000)
					( Origin gFrontEnd )
				)
				( objectFlag fObjectAlias )
				( objectStatus "page140_gnd" )
			)
			( signal "@baseboard_fab2_lib.baseboard_fab2(sch_1):page141_gnd"
				( attribute "VOLTAGE" "0.0V"
					( Units "uVoltage" "V" 1.000000)
					( Origin gFrontEnd )
				)
				( objectFlag fObjectAlias )
				( objectStatus "page141_gnd" )
			)
			( signal "@baseboard_fab2_lib.baseboard_fab2(sch_1):page142_gnd"
				( attribute "VOLTAGE" "0.0V"
					( Units "uVoltage" "V" 1.000000)
					( Origin gFrontEnd )
				)
				( objectFlag fObjectAlias )
				( objectStatus "page142_gnd" )
			)
			( signal "@baseboard_fab2_lib.baseboard_fab2(sch_1):page152_gnd"
				( attribute "VOLTAGE" "0.0V"
					( Units "uVoltage" "V" 1.000000)
					( Origin gFrontEnd )
				)
				( objectFlag fObjectAlias )
				( objectStatus "page152_gnd" )
			)
			( signal "@baseboard_fab2_lib.baseboard_fab2(sch_1):page153_gnd"
				( attribute "VOLTAGE" "0.0V"
					( Units "uVoltage" "V" 1.000000)
					( Origin gFrontEnd )
				)
				( objectFlag fObjectAlias )
				( objectStatus "page153_gnd" )
			)
			( signal "@baseboard_fab2_lib.baseboard_fab2(sch_1):page154_gnd"
				( attribute "VOLTAGE" "0.0V"
					( Units "uVoltage" "V" 1.000000)
					( Origin gFrontEnd )
				)
				( objectFlag fObjectAlias )
				( objectStatus "page154_gnd" )
			)
			( signal "@baseboard_fab2_lib.baseboard_fab2(sch_1):page155_gnd"
				( attribute "VOLTAGE" "0.0V"
					( Units "uVoltage" "V" 1.000000)
					( Origin gFrontEnd )
				)
				( objectFlag fObjectAlias )
				( objectStatus "page155_gnd" )
			)
			( signal "@baseboard_fab2_lib.baseboard_fab2(sch_1):page156_gnd"
				( attribute "VOLTAGE" "0.0V"
					( Units "uVoltage" "V" 1.000000)
					( Origin gFrontEnd )
				)
				( objectFlag fObjectAlias )
				( objectStatus "page156_gnd" )
			)
			( signal "@baseboard_fab2_lib.baseboard_fab2(sch_1):page157_gnd"
				( attribute "VOLTAGE" "0.0V"
					( Units "uVoltage" "V" 1.000000)
					( Origin gFrontEnd )
				)
				( objectFlag fObjectAlias )
				( objectStatus "page157_gnd" )
			)
			( signal "@baseboard_fab2_lib.baseboard_fab2(sch_1):page158_gnd"
				( attribute "VOLTAGE" "0.0V"
					( Units "uVoltage" "V" 1.000000)
					( Origin gFrontEnd )
				)
				( objectFlag fObjectAlias )
				( objectStatus "page158_gnd" )
			)
			( signal "@baseboard_fab2_lib.baseboard_fab2(sch_1):page161_gnd"
				( attribute "VOLTAGE" "0.0V"
					( Units "uVoltage" "V" 1.000000)
					( Origin gFrontEnd )
				)
				( objectFlag fObjectAlias )
				( objectStatus "page161_gnd" )
			)
			( signal "@baseboard_fab2_lib.baseboard_fab2(sch_1):page162_gnd"
				( attribute "VOLTAGE" "0.0V"
					( Units "uVoltage" "V" 1.000000)
					( Origin gFrontEnd )
				)
				( objectFlag fObjectAlias )
				( objectStatus "page162_gnd" )
			)
			( signal "@baseboard_fab2_lib.baseboard_fab2(sch_1):page163_gnd"
				( attribute "VOLTAGE" "0"
					( Units "uVoltage" "V" 1.000000)
					( Origin gFrontEnd )
				)
				( objectFlag fObjectAlias )
				( objectStatus "page163_gnd" )
			)
			( signal "@baseboard_fab2_lib.baseboard_fab2(sch_1):page164_gnd"
				( attribute "VOLTAGE" "0.0V"
					( Units "uVoltage" "V" 1.000000)
					( Origin gFrontEnd )
				)
				( objectFlag fObjectAlias )
				( objectStatus "page164_gnd" )
			)
			( signal "@baseboard_fab2_lib.baseboard_fab2(sch_1):page165_gnd"
				( attribute "VOLTAGE" "0.0V"
					( Units "uVoltage" "V" 1.000000)
					( Origin gFrontEnd )
				)
				( objectFlag fObjectAlias )
				( objectStatus "page165_gnd" )
			)
			( signal "@baseboard_fab2_lib.baseboard_fab2(sch_1):page166_gnd"
				( attribute "VOLTAGE" "0.0V"
					( Units "uVoltage" "V" 1.000000)
					( Origin gFrontEnd )
				)
				( objectFlag fObjectAlias )
				( objectStatus "page166_gnd" )
			)
			( signal "@baseboard_fab2_lib.baseboard_fab2(sch_1):page167_gnd"
				( attribute "VOLTAGE" "0.0V"
					( Units "uVoltage" "V" 1.000000)
					( Origin gFrontEnd )
				)
				( objectFlag fObjectAlias )
				( objectStatus "page167_gnd" )
			)
			( signal "@baseboard_fab2_lib.baseboard_fab2(sch_1):page168_gnd"
				( attribute "VOLTAGE" "0.0V"
					( Units "uVoltage" "V" 1.000000)
					( Origin gFrontEnd )
				)
				( objectFlag fObjectAlias )
				( objectStatus "page168_gnd" )
			)
			( signal "@baseboard_fab2_lib.baseboard_fab2(sch_1):page169_gnd"
				( attribute "VOLTAGE" "0"
					( Units "uVoltage" "V" 1.000000)
					( Origin gFrontEnd )
				)
				( objectFlag fObjectAlias )
				( objectStatus "page169_gnd" )
			)
			( signal "@baseboard_fab2_lib.baseboard_fab2(sch_1):page170_gnd"
				( attribute "VOLTAGE" "0.0V"
					( Units "uVoltage" "V" 1.000000)
					( Origin gFrontEnd )
				)
				( objectFlag fObjectAlias )
				( objectStatus "page170_gnd" )
			)
			( signal "@baseboard_fab2_lib.baseboard_fab2(sch_1):page172_gnd"
				( attribute "VOLTAGE" "0"
					( Units "uVoltage" "V" 1.000000)
					( Origin gFrontEnd )
				)
				( objectFlag fObjectAlias )
				( objectStatus "page172_gnd" )
			)
			( signal "@baseboard_fab2_lib.baseboard_fab2(sch_1):page173_gnd"
				( attribute "VOLTAGE" "0.0V"
					( Units "uVoltage" "V" 1.000000)
					( Origin gFrontEnd )
				)
				( objectFlag fObjectAlias )
				( objectStatus "page173_gnd" )
			)
			( signal "@baseboard_fab2_lib.baseboard_fab2(sch_1):page174_gnd"
				( attribute "VOLTAGE" "0.0V"
					( Units "uVoltage" "V" 1.000000)
					( Origin gFrontEnd )
				)
				( objectFlag fObjectAlias )
				( objectStatus "page174_gnd" )
			)
			( signal "@baseboard_fab2_lib.baseboard_fab2(sch_1):page175_gnd"
				( attribute "VOLTAGE" "0.0V"
					( Units "uVoltage" "V" 1.000000)
					( Origin gFrontEnd )
				)
				( objectFlag fObjectAlias )
				( objectStatus "page175_gnd" )
			)
			( signal "@baseboard_fab2_lib.baseboard_fab2(sch_1):page176_gnd"
				( attribute "VOLTAGE" "0"
					( Units "uVoltage" "V" 1.000000)
					( Origin gFrontEnd )
				)
				( objectFlag fObjectAlias )
				( objectStatus "page176_gnd" )
			)
			( signal "@baseboard_fab2_lib.baseboard_fab2(sch_1):page177_gnd"
				( attribute "VOLTAGE" "0"
					( Units "uVoltage" "V" 1.000000)
					( Origin gFrontEnd )
				)
				( objectFlag fObjectAlias )
				( objectStatus "page177_gnd" )
			)
			( signal "@baseboard_fab2_lib.baseboard_fab2(sch_1):page181_gnd"
				( attribute "VOLTAGE" "0"
					( Units "uVoltage" "V" 1.000000)
					( Origin gFrontEnd )
				)
				( objectFlag fObjectAlias )
				( objectStatus "page181_gnd" )
			)
			( signal "@baseboard_fab2_lib.baseboard_fab2(sch_1):page182_gnd"
				( attribute "VOLTAGE" "0"
					( Units "uVoltage" "V" 1.000000)
					( Origin gFrontEnd )
				)
				( objectFlag fObjectAlias )
				( objectStatus "page182_gnd" )
			)
			( signal "@baseboard_fab2_lib.baseboard_fab2(sch_1):page183_gnd"
				( attribute "VOLTAGE" "0.0V"
					( Units "uVoltage" "V" 1.000000)
					( Origin gFrontEnd )
				)
				( objectFlag fObjectAlias )
				( objectStatus "page183_gnd" )
			)
			( signal "@baseboard_fab2_lib.baseboard_fab2(sch_1):page184_gnd"
				( attribute "VOLTAGE" "0"
					( Units "uVoltage" "V" 1.000000)
					( Origin gFrontEnd )
				)
				( objectFlag fObjectAlias )
				( objectStatus "page184_gnd" )
			)
			( signal "@baseboard_fab2_lib.baseboard_fab2(sch_1):page185_gnd"
				( attribute "VOLTAGE" "0.0V"
					( Units "uVoltage" "V" 1.000000)
					( Origin gFrontEnd )
				)
				( objectFlag fObjectAlias )
				( objectStatus "page185_gnd" )
			)
			( signal "@baseboard_fab2_lib.baseboard_fab2(sch_1):page186_gnd"
				( attribute "VOLTAGE" "0"
					( Units "uVoltage" "V" 1.000000)
					( Origin gFrontEnd )
				)
				( objectFlag fObjectAlias )
				( objectStatus "page186_gnd" )
			)
			( signal "@baseboard_fab2_lib.baseboard_fab2(sch_1):page187_gnd"
				( attribute "VOLTAGE" "0"
					( Units "uVoltage" "V" 1.000000)
					( Origin gFrontEnd )
				)
				( objectFlag fObjectAlias )
				( objectStatus "page187_gnd" )
			)
			( signal "@baseboard_fab2_lib.baseboard_fab2(sch_1):page188_gnd"
				( attribute "VOLTAGE" "0"
					( Units "uVoltage" "V" 1.000000)
					( Origin gFrontEnd )
				)
				( objectFlag fObjectAlias )
				( objectStatus "page188_gnd" )
			)
			( signal "@baseboard_fab2_lib.baseboard_fab2(sch_1):page189_gnd"
				( attribute "VOLTAGE" "0.0V"
					( Units "uVoltage" "V" 1.000000)
					( Origin gFrontEnd )
				)
				( objectFlag fObjectAlias )
				( objectStatus "page189_gnd" )
			)
			( signal "@baseboard_fab2_lib.baseboard_fab2(sch_1):page192_gnd"
				( attribute "VOLTAGE" "0.0V"
					( Units "uVoltage" "V" 1.000000)
					( Origin gFrontEnd )
				)
				( objectFlag fObjectAlias )
				( objectStatus "page192_gnd" )
			)
			( signal "@baseboard_fab2_lib.baseboard_fab2(sch_1):page193_gnd"
				( attribute "VOLTAGE" "0.0V"
					( Units "uVoltage" "V" 1.000000)
					( Origin gFrontEnd )
				)
				( objectFlag fObjectAlias )
				( objectStatus "page193_gnd" )
			)
			( signal "@baseboard_fab2_lib.baseboard_fab2(sch_1):page194_gnd"
				( attribute "VOLTAGE" "0"
					( Units "uVoltage" "V" 1.000000)
					( Origin gFrontEnd )
				)
				( objectFlag fObjectAlias )
				( objectStatus "page194_gnd" )
			)
			( signal "@baseboard_fab2_lib.baseboard_fab2(sch_1):page195_gnd"
				( attribute "VOLTAGE" "0.0V"
					( Units "uVoltage" "V" 1.000000)
					( Origin gFrontEnd )
				)
				( objectFlag fObjectAlias )
				( objectStatus "page195_gnd" )
			)
			( signal "@baseboard_fab2_lib.baseboard_fab2(sch_1):page196_gnd"
				( attribute "VOLTAGE" "0.0V"
					( Units "uVoltage" "V" 1.000000)
					( Origin gFrontEnd )
				)
				( objectFlag fObjectAlias )
				( objectStatus "page196_gnd" )
			)
			( signal "@baseboard_fab2_lib.baseboard_fab2(sch_1):page197_gnd"
				( attribute "VOLTAGE" "0.0V"
					( Units "uVoltage" "V" 1.000000)
					( Origin gFrontEnd )
				)
				( objectFlag fObjectAlias )
				( objectStatus "page197_gnd" )
			)
			( signal "@baseboard_fab2_lib.baseboard_fab2(sch_1):page198_gnd"
				( attribute "VOLTAGE" "0.0V"
					( Units "uVoltage" "V" 1.000000)
					( Origin gFrontEnd )
				)
				( objectFlag fObjectAlias )
				( objectStatus "page198_gnd" )
			)
			( signal "@baseboard_fab2_lib.baseboard_fab2(sch_1):page199_gnd"
				( attribute "VOLTAGE" "0"
					( Units "uVoltage" "V" 1.000000)
					( Origin gFrontEnd )
				)
				( objectFlag fObjectAlias )
				( objectStatus "page199_gnd" )
			)
			( signal "@baseboard_fab2_lib.baseboard_fab2(sch_1):page200_gnd"
				( attribute "VOLTAGE" "0.0V"
					( Units "uVoltage" "V" 1.000000)
					( Origin gFrontEnd )
				)
				( objectFlag fObjectAlias )
				( objectStatus "page200_gnd" )
			)
			( signal "@baseboard_fab2_lib.baseboard_fab2(sch_1):page201_gnd"
				( attribute "VOLTAGE" "0"
					( Units "uVoltage" "V" 1.000000)
					( Origin gFrontEnd )
				)
				( objectFlag fObjectAlias )
				( objectStatus "page201_gnd" )
			)
			( signal "@baseboard_fab2_lib.baseboard_fab2(sch_1):page202_gnd"
				( attribute "VOLTAGE" "0"
					( Units "uVoltage" "V" 1.000000)
					( Origin gFrontEnd )
				)
				( objectFlag fObjectAlias )
				( objectStatus "page202_gnd" )
			)
			( signal "@baseboard_fab2_lib.baseboard_fab2(sch_1):page203_gnd"
				( attribute "VOLTAGE" "0"
					( Units "uVoltage" "V" 1.000000)
					( Origin gFrontEnd )
				)
				( objectFlag fObjectAlias )
				( objectStatus "page203_gnd" )
			)
			( signal "@baseboard_fab2_lib.baseboard_fab2(sch_1):page204_gnd"
				( attribute "VOLTAGE" "0"
					( Units "uVoltage" "V" 1.000000)
					( Origin gFrontEnd )
				)
				( objectFlag fObjectAlias )
				( objectStatus "page204_gnd" )
			)
			( signal "@baseboard_fab2_lib.baseboard_fab2(sch_1):page205_gnd"
				( attribute "VOLTAGE" "0"
					( Units "uVoltage" "V" 1.000000)
					( Origin gFrontEnd )
				)
				( objectFlag fObjectAlias )
				( objectStatus "page205_gnd" )
			)
			( signal "@baseboard_fab2_lib.baseboard_fab2(sch_1):page206_gnd"
				( attribute "VOLTAGE" "0"
					( Units "uVoltage" "V" 1.000000)
					( Origin gFrontEnd )
				)
				( objectFlag fObjectAlias )
				( objectStatus "page206_gnd" )
			)
			( signal "@baseboard_fab2_lib.baseboard_fab2(sch_1):page207_gnd"
				( attribute "VOLTAGE" "0"
					( Units "uVoltage" "V" 1.000000)
					( Origin gFrontEnd )
				)
				( objectFlag fObjectAlias )
				( objectStatus "page207_gnd" )
			)
			( signal "@baseboard_fab2_lib.baseboard_fab2(sch_1):page208_gnd"
				( attribute "VOLTAGE" "0"
					( Units "uVoltage" "V" 1.000000)
					( Origin gFrontEnd )
				)
				( objectFlag fObjectAlias )
				( objectStatus "page208_gnd" )
			)
			( signal "@baseboard_fab2_lib.baseboard_fab2(sch_1):page209_gnd"
				( attribute "VOLTAGE" "0"
					( Units "uVoltage" "V" 1.000000)
					( Origin gFrontEnd )
				)
				( objectFlag fObjectAlias )
				( objectStatus "page209_gnd" )
			)
			( signal "@baseboard_fab2_lib.baseboard_fab2(sch_1):page210_gnd"
				( attribute "VOLTAGE" "0"
					( Units "uVoltage" "V" 1.000000)
					( Origin gFrontEnd )
				)
				( objectFlag fObjectAlias )
				( objectStatus "page210_gnd" )
			)
			( signal "@baseboard_fab2_lib.baseboard_fab2(sch_1):page211_gnd"
				( attribute "VOLTAGE" "0"
					( Units "uVoltage" "V" 1.000000)
					( Origin gFrontEnd )
				)
				( objectFlag fObjectAlias )
				( objectStatus "page211_gnd" )
			)
			( signal "@baseboard_fab2_lib.baseboard_fab2(sch_1):page212_gnd"
				( attribute "VOLTAGE" "0"
					( Units "uVoltage" "V" 1.000000)
					( Origin gFrontEnd )
				)
				( objectFlag fObjectAlias )
				( objectStatus "page212_gnd" )
			)
			( signal "@baseboard_fab2_lib.baseboard_fab2(sch_1):page213_gnd"
				( attribute "VOLTAGE" "0"
					( Units "uVoltage" "V" 1.000000)
					( Origin gFrontEnd )
				)
				( objectFlag fObjectAlias )
				( objectStatus "page213_gnd" )
			)
			( signal "@baseboard_fab2_lib.baseboard_fab2(sch_1):page214_gnd"
				( attribute "VOLTAGE" "0"
					( Units "uVoltage" "V" 1.000000)
					( Origin gFrontEnd )
				)
				( objectFlag fObjectAlias )
				( objectStatus "page214_gnd" )
			)
			( signal "@baseboard_fab2_lib.baseboard_fab2(sch_1):page215_gnd"
				( attribute "VOLTAGE" "0"
					( Units "uVoltage" "V" 1.000000)
					( Origin gFrontEnd )
				)
				( objectFlag fObjectAlias )
				( objectStatus "page215_gnd" )
			)
			( signal "@baseboard_fab2_lib.baseboard_fab2(sch_1):page216_gnd"
				( attribute "VOLTAGE" "0"
					( Units "uVoltage" "V" 1.000000)
					( Origin gFrontEnd )
				)
				( objectFlag fObjectAlias )
				( objectStatus "page216_gnd" )
			)
			( signal "@baseboard_fab2_lib.baseboard_fab2(sch_1):page217_gnd"
				( attribute "VOLTAGE" "0"
					( Units "uVoltage" "V" 1.000000)
					( Origin gFrontEnd )
				)
				( objectFlag fObjectAlias )
				( objectStatus "page217_gnd" )
			)
			( signal "@baseboard_fab2_lib.baseboard_fab2(sch_1):page218_gnd"
				( attribute "VOLTAGE" "0"
					( Units "uVoltage" "V" 1.000000)
					( Origin gFrontEnd )
				)
				( objectFlag fObjectAlias )
				( objectStatus "page218_gnd" )
			)
			( signal "@baseboard_fab2_lib.baseboard_fab2(sch_1):page219_gnd"
				( attribute "VOLTAGE" "0"
					( Units "uVoltage" "V" 1.000000)
					( Origin gFrontEnd )
				)
				( objectFlag fObjectAlias )
				( objectStatus "page219_gnd" )
			)
			( signal "@baseboard_fab2_lib.baseboard_fab2(sch_1):page220_gnd"
				( attribute "VOLTAGE" "0"
					( Units "uVoltage" "V" 1.000000)
					( Origin gFrontEnd )
				)
				( objectFlag fObjectAlias )
				( objectStatus "page220_gnd" )
			)
			( signal "@baseboard_fab2_lib.baseboard_fab2(sch_1):page221_gnd"
				( attribute "VOLTAGE" "0.0V"
					( Units "uVoltage" "V" 1.000000)
					( Origin gFrontEnd )
				)
				( objectFlag fObjectAlias )
				( objectStatus "page221_gnd" )
			)
			( signal "@baseboard_fab2_lib.baseboard_fab2(sch_1):page222_gnd"
				( attribute "VOLTAGE" "0.0V"
					( Units "uVoltage" "V" 1.000000)
					( Origin gFrontEnd )
				)
				( objectFlag fObjectAlias )
				( objectStatus "page222_gnd" )
			)
			( signal "@baseboard_fab2_lib.baseboard_fab2(sch_1):page223_gnd"
				( attribute "VOLTAGE" "0"
					( Units "uVoltage" "V" 1.000000)
					( Origin gFrontEnd )
				)
				( objectFlag fObjectAlias )
				( objectStatus "page223_gnd" )
			)
			( signal "@baseboard_fab2_lib.baseboard_fab2(sch_1):page224_gnd"
				( attribute "VOLTAGE" "0"
					( Units "uVoltage" "V" 1.000000)
					( Origin gFrontEnd )
				)
				( objectFlag fObjectAlias )
				( objectStatus "page224_gnd" )
			)
			( signal "@baseboard_fab2_lib.baseboard_fab2(sch_1):page225_gnd"
				( attribute "VOLTAGE" "0"
					( Units "uVoltage" "V" 1.000000)
					( Origin gFrontEnd )
				)
				( objectFlag fObjectAlias )
				( objectStatus "page225_gnd" )
			)
			( signal "@baseboard_fab2_lib.baseboard_fab2(sch_1):page226_gnd"
				( attribute "VOLTAGE" "0"
					( Units "uVoltage" "V" 1.000000)
					( Origin gFrontEnd )
				)
				( objectFlag fObjectAlias )
				( objectStatus "page226_gnd" )
			)
			( signal "@baseboard_fab2_lib.baseboard_fab2(sch_1):page227_gnd"
				( attribute "VOLTAGE" "0"
					( Units "uVoltage" "V" 1.000000)
					( Origin gFrontEnd )
				)
				( objectFlag fObjectAlias )
				( objectStatus "page227_gnd" )
			)
			( signal "@baseboard_fab2_lib.baseboard_fab2(sch_1):page228_gnd"
				( attribute "VOLTAGE" "0"
					( Units "uVoltage" "V" 1.000000)
					( Origin gFrontEnd )
				)
				( objectFlag fObjectAlias )
				( objectStatus "page228_gnd" )
			)
			( signal "@baseboard_fab2_lib.baseboard_fab2(sch_1):page229_gnd"
				( attribute "VOLTAGE" "0.0V"
					( Units "uVoltage" "V" 1.000000)
					( Origin gFrontEnd )
				)
				( objectFlag fObjectAlias )
				( objectStatus "page229_gnd" )
			)
			( signal "@baseboard_fab2_lib.baseboard_fab2(sch_1):page230_gnd"
				( attribute "VOLTAGE" "0.0V"
					( Units "uVoltage" "V" 1.000000)
					( Origin gFrontEnd )
				)
				( objectFlag fObjectAlias )
				( objectStatus "page230_gnd" )
			)
			( signal "@baseboard_fab2_lib.baseboard_fab2(sch_1):page231_gnd"
				( attribute "VOLTAGE" "0"
					( Units "uVoltage" "V" 1.000000)
					( Origin gFrontEnd )
				)
				( objectFlag fObjectAlias )
				( objectStatus "page231_gnd" )
			)
			( signal "@baseboard_fab2_lib.baseboard_fab2(sch_1):page232_gnd"
				( attribute "VOLTAGE" "0"
					( Units "uVoltage" "V" 1.000000)
					( Origin gFrontEnd )
				)
				( objectFlag fObjectAlias )
				( objectStatus "page232_gnd" )
			)
			( signal "@baseboard_fab2_lib.baseboard_fab2(sch_1):page233_gnd"
				( attribute "VOLTAGE" "0"
					( Units "uVoltage" "V" 1.000000)
					( Origin gFrontEnd )
				)
				( objectFlag fObjectAlias )
				( objectStatus "page233_gnd" )
			)
			( signal "@baseboard_fab2_lib.baseboard_fab2(sch_1):page234_gnd"
				( attribute "VOLTAGE" "0"
					( Units "uVoltage" "V" 1.000000)
					( Origin gFrontEnd )
				)
				( objectFlag fObjectAlias )
				( objectStatus "page234_gnd" )
			)
			( signal "@baseboard_fab2_lib.baseboard_fab2(sch_1):page235_gnd"
				( attribute "VOLTAGE" "0"
					( Units "uVoltage" "V" 1.000000)
					( Origin gFrontEnd )
				)
				( objectFlag fObjectAlias )
				( objectStatus "page235_gnd" )
			)
			( signal "@baseboard_fab2_lib.baseboard_fab2(sch_1):page236_gnd"
				( attribute "VOLTAGE" "0.0V"
					( Units "uVoltage" "V" 1.000000)
					( Origin gFrontEnd )
				)
				( objectFlag fObjectAlias )
				( objectStatus "page236_gnd" )
			)
			( signal "@baseboard_fab2_lib.baseboard_fab2(sch_1):page237_gnd"
				( attribute "VOLTAGE" "0.0V"
					( Units "uVoltage" "V" 1.000000)
					( Origin gFrontEnd )
				)
				( objectFlag fObjectAlias )
				( objectStatus "page237_gnd" )
			)
			( signal "@baseboard_fab2_lib.baseboard_fab2(sch_1):page238_gnd"
				( attribute "VOLTAGE" "0.0V"
					( Units "uVoltage" "V" 1.000000)
					( Origin gFrontEnd )
				)
				( objectFlag fObjectAlias )
				( objectStatus "page238_gnd" )
			)
			( signal "@baseboard_fab2_lib.baseboard_fab2(sch_1):page239_gnd"
				( attribute "VOLTAGE" "0.0V"
					( Units "uVoltage" "V" 1.000000)
					( Origin gFrontEnd )
				)
				( objectFlag fObjectAlias )
				( objectStatus "page239_gnd" )
			)
			( signal "@baseboard_fab2_lib.baseboard_fab2(sch_1):page240_gnd"
				( attribute "VOLTAGE" "0"
					( Units "uVoltage" "V" 1.000000)
					( Origin gFrontEnd )
				)
				( objectFlag fObjectAlias )
				( objectStatus "page240_gnd" )
			)
			( signal "@baseboard_fab2_lib.baseboard_fab2(sch_1):page241_gnd"
				( attribute "VOLTAGE" "0"
					( Units "uVoltage" "V" 1.000000)
					( Origin gFrontEnd )
				)
				( objectFlag fObjectAlias )
				( objectStatus "page241_gnd" )
			)
			( signal "@baseboard_fab2_lib.baseboard_fab2(sch_1):page242_gnd"
				( attribute "VOLTAGE" "0"
					( Units "uVoltage" "V" 1.000000)
					( Origin gFrontEnd )
				)
				( objectFlag fObjectAlias )
				( objectStatus "page242_gnd" )
			)
			( signal "@baseboard_fab2_lib.baseboard_fab2(sch_1):page243_gnd"
				( attribute "VOLTAGE" "0"
					( Units "uVoltage" "V" 1.000000)
					( Origin gFrontEnd )
				)
				( objectFlag fObjectAlias )
				( objectStatus "page243_gnd" )
			)
			( signal "@baseboard_fab2_lib.baseboard_fab2(sch_1):page245_gnd"
				( attribute "BOM_COST" "TBD"
					( Origin gFrontEnd )
				)
				( attribute "CDS_PHYS_NET_NAME" "GND"
					( Origin gPackager )
				)
				( attribute "ROOM" "TBD"
					( Origin gFrontEnd )
				)
				( attribute "VOLTAGE" "0"
					( Units "uVoltage" "V" 1.000000)
					( Origin gFrontEnd )
				)
				( objectFlag fObjectAlias )
				( objectStatus "page245_gnd" )
			)
			( signal "@baseboard_fab2_lib.baseboard_fab2(sch_1):page246_gnd"
				( attribute "VOLTAGE" "0"
					( Units "uVoltage" "V" 1.000000)
					( Origin gFrontEnd )
				)
				( objectFlag fObjectAlias )
				( objectStatus "page246_gnd" )
			)
			( signal "@baseboard_fab2_lib.baseboard_fab2(sch_1):page247_gnd"
				( attribute "VOLTAGE" "0.0V"
					( Units "uVoltage" "V" 1.000000)
					( Origin gFrontEnd )
				)
				( objectFlag fObjectAlias )
				( objectStatus "page247_gnd" )
			)
			( signal "@baseboard_fab2_lib.baseboard_fab2(sch_1):page249_gnd"
				( attribute "VOLTAGE" "0.0V"
					( Units "uVoltage" "V" 1.000000)
					( Origin gFrontEnd )
				)
				( objectFlag fObjectAlias )
				( objectStatus "page249_gnd" )
			)
			( signal "@baseboard_fab2_lib.baseboard_fab2(sch_1):page150_gnd"
				( attribute "VOLTAGE" "0.0V"
					( Units "uVoltage" "V" 1.000000)
					( Origin gFrontEnd )
				)
				( objectFlag fObjectAlias )
				( objectStatus "page150_gnd" )
			)
			( signal "@baseboard_fab2_lib.baseboard_fab2(sch_1):page143_gnd"
				( attribute "VOLTAGE" "0.0V"
					( Units "uVoltage" "V" 1.000000)
					( Origin gFrontEnd )
				)
				( objectFlag fObjectAlias )
				( objectStatus "page143_gnd" )
			)
			( signal "@baseboard_fab2_lib.baseboard_fab2(sch_1):page144_gnd"
				( attribute "VOLTAGE" "0.0V"
					( Units "uVoltage" "V" 1.000000)
					( Origin gFrontEnd )
				)
				( objectFlag fObjectAlias )
				( objectStatus "page144_gnd" )
			)
			( signal "@baseboard_fab2_lib.baseboard_fab2(sch_1):page145_gnd"
				( attribute "VOLTAGE" "0.0V"
					( Units "uVoltage" "V" 1.000000)
					( Origin gFrontEnd )
				)
				( objectFlag fObjectAlias )
				( objectStatus "page145_gnd" )
			)
			( signal "@baseboard_fab2_lib.baseboard_fab2(sch_1):page146_gnd"
				( attribute "VOLTAGE" "0.0V"
					( Units "uVoltage" "V" 1.000000)
					( Origin gFrontEnd )
				)
				( objectFlag fObjectAlias )
				( objectStatus "page146_gnd" )
			)
			( signal "@baseboard_fab2_lib.baseboard_fab2(sch_1):page147_gnd"
				( attribute "VOLTAGE" "0.0V"
					( Units "uVoltage" "V" 1.000000)
					( Origin gFrontEnd )
				)
				( objectFlag fObjectAlias )
				( objectStatus "page147_gnd" )
			)
			( signal "@baseboard_fab2_lib.baseboard_fab2(sch_1):page148_gnd"
				( attribute "VOLTAGE" "0.0V"
					( Units "uVoltage" "V" 1.000000)
					( Origin gFrontEnd )
				)
				( objectFlag fObjectAlias )
				( objectStatus "page148_gnd" )
			)
			( signal "@baseboard_fab2_lib.baseboard_fab2(sch_1):page151_gnd"
				( attribute "VOLTAGE" "0.0V"
					( Units "uVoltage" "V" 1.000000)
					( Origin gFrontEnd )
				)
				( objectFlag fObjectAlias )
				( objectStatus "page151_gnd" )
			)
			( signal "@baseboard_fab2_lib.baseboard_fab2(sch_1):page149_gnd"
				( attribute "VOLTAGE" "0.0V"
					( Units "uVoltage" "V" 1.000000)
					( Origin gFrontEnd )
				)
				( objectFlag fObjectAlias )
				( objectStatus "page149_gnd" )
			)
			( signal "@baseboard_fab2_lib.baseboard_fab2(sch_1):page150_vcc_a_1v1"
				( objectFlag fObjectAlias )
				( objectStatus "page150_vcc_a_1v1" )
			)
			( signal "@baseboard_fab2_lib.baseboard_fab2(sch_1):page144_irq_dimm_save_lvt3_n"
				( attribute "CDS_PHYS_NET_NAME" "IRQ_DIMM_SAVE_LVT3_N"
					( Origin gPackager )
				)
				( attribute "PHYS_NET_NAME" "IRQ_DIMM_SAVE_LVT3_N"
					( Origin gFrontEnd )
				)
				( objectFlag fObjectAlias )
				( objectStatus "page144_irq_dimm_save_lvt3_n" )
			)
			( signal "@baseboard_fab2_lib.baseboard_fab2(sch_1):h_cpu0_bmcinit"
				( attribute "CDS_PHYS_NET_NAME" "H_CPU0_BMCINIT"
					( Origin gPackager )
				)
				( objectStatus "H_CPU0_BMCINIT" )
			)
			( signal "@baseboard_fab2_lib.baseboard_fab2(sch_1):h_cpu0_caterr_g_n"
				( attribute "CDS_PHYS_NET_NAME" "H_CPU0_CATERR_G_N"
					( Origin gPackager )
				)
				( objectStatus "H_CPU0_CATERR_G_N" )
			)
			( signal "@baseboard_fab2_lib.baseboard_fab2(sch_1):h_cpu0_err0_g_n"
				( attribute "CDS_PHYS_NET_NAME" "H_CPU0_ERR0_G_N"
					( Origin gPackager )
				)
				( objectStatus "H_CPU0_ERR0_G_N" )
			)
			( signal "@baseboard_fab2_lib.baseboard_fab2(sch_1):h_cpu0_err1_g_n"
				( attribute "CDS_PHYS_NET_NAME" "H_CPU0_ERR1_G_N"
					( Origin gPackager )
				)
				( objectStatus "H_CPU0_ERR1_G_N" )
			)
			( signal "@baseboard_fab2_lib.baseboard_fab2(sch_1):h_cpu0_err2_g_n"
				( attribute "CDS_PHYS_NET_NAME" "H_CPU0_ERR2_G_N"
					( Origin gPackager )
				)
				( objectStatus "H_CPU0_ERR2_G_N" )
			)
			( signal "@baseboard_fab2_lib.baseboard_fab2(sch_1):h_cpu0_fast_wake_n"
				( attribute "CDS_PHYS_NET_NAME" "H_CPU0_FAST_WAKE_N"
					( Origin gPackager )
				)
				( objectStatus "H_CPU0_FAST_WAKE_N" )
			)
			( signal "@baseboard_fab2_lib.baseboard_fab2(sch_1):h_cpu0_memabc_memhot_g_n"
				( attribute "CDS_PHYS_NET_NAME" "H_CPU0_MEMABC_MEMHOT_G_N"
					( Origin gPackager )
				)
				( objectStatus "H_CPU0_MEMABC_MEMHOT_G_N" )
			)
			( signal "@baseboard_fab2_lib.baseboard_fab2(sch_1):h_cpu0_memdef_memhot_g_n"
				( attribute "CDS_PHYS_NET_NAME" "H_CPU0_MEMDEF_MEMHOT_G_N"
					( Origin gPackager )
				)
				( objectStatus "H_CPU0_MEMDEF_MEMHOT_G_N" )
			)
			( signal "@baseboard_fab2_lib.baseboard_fab2(sch_1):h_cpu0_msmi_g_n"
				( attribute "CDS_PHYS_NET_NAME" "H_CPU0_MSMI_G_N"
					( Origin gPackager )
				)
				( objectStatus "H_CPU0_MSMI_G_N" )
			)
			( signal "@baseboard_fab2_lib.baseboard_fab2(sch_1):h_cpu0_prochot_g_n"
				( attribute "CDS_PHYS_NET_NAME" "H_CPU0_PROCHOT_G_N"
					( Origin gPackager )
				)
				( objectStatus "H_CPU0_PROCHOT_G_N" )
			)
			( signal "@baseboard_fab2_lib.baseboard_fab2(sch_1):h_cpu0_thermtrip_g_n"
				( attribute "CDS_PHYS_NET_NAME" "H_CPU0_THERMTRIP_G_N"
					( Origin gPackager )
				)
				( objectStatus "H_CPU0_THERMTRIP_G_N" )
			)
			( signal "@baseboard_fab2_lib.baseboard_fab2(sch_1):h_pm_sync_gtl"
				( attribute "CDS_PHYS_NET_NAME" "H_PM_SYNC_GTL"
					( Origin gPackager )
				)
				( objectStatus "H_PM_SYNC_GTL" )
			)
			( signal "@baseboard_fab2_lib.baseboard_fab2(sch_1):h_pm_sync_gtl_r1"
				( attribute "CDS_PHYS_NET_NAME" "H_PM_SYNC_GTL_R1"
					( Origin gPackager )
				)
				( objectStatus "H_PM_SYNC_GTL_R1" )
			)
			( signal "@baseboard_fab2_lib.baseboard_fab2(sch_1):h_pmsync_clk_24m"
				( attribute "CDS_PHYS_NET_NAME" "H_PMSYNC_CLK_24M"
					( Origin gPackager )
				)
				( objectStatus "H_PMSYNC_CLK_24M" )
			)
			( signal "@baseboard_fab2_lib.baseboard_fab2(sch_1):h_pmsync_clk_24m_cpu0"
				( attribute "CDS_PHYS_NET_NAME" "H_PMSYNC_CLK_24M_CPU0"
					( Origin gPackager )
				)
				( objectStatus "H_PMSYNC_CLK_24M_CPU0" )
			)
			( signal "@baseboard_fab2_lib.baseboard_fab2(sch_1):m_a_cpu_vref"
				( attribute "CDS_PHYS_NET_NAME" "M_A_CPU_VREF"
					( Origin gPackager )
				)
				( objectStatus "M_A_CPU_VREF" )
			)
			( signal "@baseboard_fab2_lib.baseboard_fab2(sch_1):m_abc_rst_n"
				( attribute "CDS_PHYS_NET_NAME" "M_ABC_RST_N"
					( Origin gPackager )
				)
				( objectStatus "M_ABC_RST_N" )
			)
			( signal "@baseboard_fab2_lib.baseboard_fab2(sch_1):m_b_cpu_vref"
				( attribute "CDS_PHYS_NET_NAME" "M_B_CPU_VREF"
					( Origin gPackager )
				)
				( objectStatus "M_B_CPU_VREF" )
			)
			( signal "@baseboard_fab2_lib.baseboard_fab2(sch_1):m_c_cpu_vref"
				( attribute "CDS_PHYS_NET_NAME" "M_C_CPU_VREF"
					( Origin gPackager )
				)
				( objectStatus "M_C_CPU_VREF" )
			)
			( signal "@baseboard_fab2_lib.baseboard_fab2(sch_1):m_d_cpu_vref"
				( attribute "CDS_PHYS_NET_NAME" "M_D_CPU_VREF"
					( Origin gPackager )
				)
				( objectStatus "M_D_CPU_VREF" )
			)
			( signal "@baseboard_fab2_lib.baseboard_fab2(sch_1):m_def_rst_n"
				( attribute "CDS_PHYS_NET_NAME" "M_DEF_RST_N"
					( Origin gPackager )
				)
				( objectStatus "M_DEF_RST_N" )
			)
			( signal "@baseboard_fab2_lib.baseboard_fab2(sch_1):m_e_cpu_vref"
				( attribute "CDS_PHYS_NET_NAME" "M_E_CPU_VREF"
					( Origin gPackager )
				)
				( objectStatus "M_E_CPU_VREF" )
			)
			( signal "@baseboard_fab2_lib.baseboard_fab2(sch_1):m_f_cpu_vref"
				( attribute "CDS_PHYS_NET_NAME" "M_F_CPU_VREF"
					( Origin gPackager )
				)
				( objectStatus "M_F_CPU_VREF" )
			)
			( signal "@baseboard_fab2_lib.baseboard_fab2(sch_1):p3v3_stby"
				( alias ( signalRef "@baseboard_fab2_lib.baseboard_fab2(sch_1):page21_p3v3_stby") )
				( alias ( signalRef "@baseboard_fab2_lib.baseboard_fab2(sch_1):page38_p3v3_stby") )
				( alias ( signalRef "@baseboard_fab2_lib.baseboard_fab2(sch_1):page55_p3v3_stby") )
				( alias ( signalRef "@baseboard_fab2_lib.baseboard_fab2(sch_1):page72_p3v3_stby") )
				( alias ( signalRef "@baseboard_fab2_lib.baseboard_fab2(sch_1):page89_p3v3_stby") )
				( alias ( signalRef "@baseboard_fab2_lib.baseboard_fab2(sch_1):page94_p3v3_stby") )
				( alias ( signalRef "@baseboard_fab2_lib.baseboard_fab2(sch_1):page95_p3v3_stby") )
				( alias ( signalRef "@baseboard_fab2_lib.baseboard_fab2(sch_1):page96_p3v3_stby") )
				( alias ( signalRef "@baseboard_fab2_lib.baseboard_fab2(sch_1):page101_p3v3_stby") )
				( alias ( signalRef "@baseboard_fab2_lib.baseboard_fab2(sch_1):page108_p3v3_stby") )
				( alias ( signalRef "@baseboard_fab2_lib.baseboard_fab2(sch_1):page111_p3v3_stby") )
				( alias ( signalRef "@baseboard_fab2_lib.baseboard_fab2(sch_1):page112_p3v3_stby") )
				( alias ( signalRef "@baseboard_fab2_lib.baseboard_fab2(sch_1):page113_p3v3_stby") )
				( alias ( signalRef "@baseboard_fab2_lib.baseboard_fab2(sch_1):page118_p3v3_stby") )
				( alias ( signalRef "@baseboard_fab2_lib.baseboard_fab2(sch_1):page119_p3v3_stby") )
				( alias ( signalRef "@baseboard_fab2_lib.baseboard_fab2(sch_1):page121_p3v3_stby") )
				( alias ( signalRef "@baseboard_fab2_lib.baseboard_fab2(sch_1):page122_p3v3_stby") )
				( alias ( signalRef "@baseboard_fab2_lib.baseboard_fab2(sch_1):page125_p3v3_stby") )
				( alias ( signalRef "@baseboard_fab2_lib.baseboard_fab2(sch_1):page126_p3v3_stby") )
				( alias ( signalRef "@baseboard_fab2_lib.baseboard_fab2(sch_1):page130_p3v3_stby") )
				( alias ( signalRef "@baseboard_fab2_lib.baseboard_fab2(sch_1):page133_p3v3_stby") )
				( alias ( signalRef "@baseboard_fab2_lib.baseboard_fab2(sch_1):page134_p3v3_stby") )
				( alias ( signalRef "@baseboard_fab2_lib.baseboard_fab2(sch_1):page135_p3v3_stby") )
				( alias ( signalRef "@baseboard_fab2_lib.baseboard_fab2(sch_1):page136_p3v3_stby") )
				( alias ( signalRef "@baseboard_fab2_lib.baseboard_fab2(sch_1):page137_p3v3_stby") )
				( alias ( signalRef "@baseboard_fab2_lib.baseboard_fab2(sch_1):page138_p3v3_stby") )
				( alias ( signalRef "@baseboard_fab2_lib.baseboard_fab2(sch_1):page139_p3v3_stby") )
				( alias ( signalRef "@baseboard_fab2_lib.baseboard_fab2(sch_1):page140_p3v3_stby") )
				( alias ( signalRef "@baseboard_fab2_lib.baseboard_fab2(sch_1):page141_p3v3_stby") )
				( alias ( signalRef "@baseboard_fab2_lib.baseboard_fab2(sch_1):page142_p3v3_stby") )
				( alias ( signalRef "@baseboard_fab2_lib.baseboard_fab2(sch_1):page150_p3v3_stby") )
				( alias ( signalRef "@baseboard_fab2_lib.baseboard_fab2(sch_1):page153_p3v3_stby") )
				( alias ( signalRef "@baseboard_fab2_lib.baseboard_fab2(sch_1):page154_p3v3_stby") )
				( alias ( signalRef "@baseboard_fab2_lib.baseboard_fab2(sch_1):page155_p3v3_stby") )
				( alias ( signalRef "@baseboard_fab2_lib.baseboard_fab2(sch_1):page156_p3v3_stby") )
				( alias ( signalRef "@baseboard_fab2_lib.baseboard_fab2(sch_1):page157_p3v3_stby") )
				( alias ( signalRef "@baseboard_fab2_lib.baseboard_fab2(sch_1):page158_p3v3_stby") )
				( alias ( signalRef "@baseboard_fab2_lib.baseboard_fab2(sch_1):page159_p3v3_stby") )
				( alias ( signalRef "@baseboard_fab2_lib.baseboard_fab2(sch_1):page160_p3v3_stby") )
				( alias ( signalRef "@baseboard_fab2_lib.baseboard_fab2(sch_1):page161_p3v3_stby") )
				( alias ( signalRef "@baseboard_fab2_lib.baseboard_fab2(sch_1):page162_p3v3_stby") )
				( alias ( signalRef "@baseboard_fab2_lib.baseboard_fab2(sch_1):page163_p3v3_stby") )
				( alias ( signalRef "@baseboard_fab2_lib.baseboard_fab2(sch_1):page164_p3v3_stby") )
				( alias ( signalRef "@baseboard_fab2_lib.baseboard_fab2(sch_1):page165_p3v3_stby") )
				( alias ( signalRef "@baseboard_fab2_lib.baseboard_fab2(sch_1):page167_p3v3_stby") )
				( alias ( signalRef "@baseboard_fab2_lib.baseboard_fab2(sch_1):page168_p3v3_stby") )
				( alias ( signalRef "@baseboard_fab2_lib.baseboard_fab2(sch_1):page169_p3v3_stby") )
				( alias ( signalRef "@baseboard_fab2_lib.baseboard_fab2(sch_1):page170_p3v3_stby") )
				( alias ( signalRef "@baseboard_fab2_lib.baseboard_fab2(sch_1):page175_p3v3_stby") )
				( alias ( signalRef "@baseboard_fab2_lib.baseboard_fab2(sch_1):page176_p3v3_stby") )
				( alias ( signalRef "@baseboard_fab2_lib.baseboard_fab2(sch_1):page177_p3v3_stby") )
				( alias ( signalRef "@baseboard_fab2_lib.baseboard_fab2(sch_1):page178_p3v3_stby") )
				( alias ( signalRef "@baseboard_fab2_lib.baseboard_fab2(sch_1):page181_p3v3_stby") )
				( alias ( signalRef "@baseboard_fab2_lib.baseboard_fab2(sch_1):page183_p3v3_stby") )
				( alias ( signalRef "@baseboard_fab2_lib.baseboard_fab2(sch_1):page184_p3v3_stby") )
				( alias ( signalRef "@baseboard_fab2_lib.baseboard_fab2(sch_1):page185_p3v3_stby") )
				( alias ( signalRef "@baseboard_fab2_lib.baseboard_fab2(sch_1):page186_p3v3_stby") )
				( alias ( signalRef "@baseboard_fab2_lib.baseboard_fab2(sch_1):page188_p3v3_stby") )
				( alias ( signalRef "@baseboard_fab2_lib.baseboard_fab2(sch_1):page189_p3v3_stby") )
				( alias ( signalRef "@baseboard_fab2_lib.baseboard_fab2(sch_1):page191_p3v3_stby") )
				( alias ( signalRef "@baseboard_fab2_lib.baseboard_fab2(sch_1):page192_p3v3_stby") )
				( alias ( signalRef "@baseboard_fab2_lib.baseboard_fab2(sch_1):page193_p3v3_stby") )
				( alias ( signalRef "@baseboard_fab2_lib.baseboard_fab2(sch_1):page194_p3v3_stby") )
				( alias ( signalRef "@baseboard_fab2_lib.baseboard_fab2(sch_1):page196_p3v3_stby") )
				( alias ( signalRef "@baseboard_fab2_lib.baseboard_fab2(sch_1):page198_p3v3_stby") )
				( alias ( signalRef "@baseboard_fab2_lib.baseboard_fab2(sch_1):page200_p3v3_stby") )
				( alias ( signalRef "@baseboard_fab2_lib.baseboard_fab2(sch_1):page201_p3v3_stby") )
				( alias ( signalRef "@baseboard_fab2_lib.baseboard_fab2(sch_1):page206_p3v3_stby") )
				( alias ( signalRef "@baseboard_fab2_lib.baseboard_fab2(sch_1):page211_p3v3_stby") )
				( alias ( signalRef "@baseboard_fab2_lib.baseboard_fab2(sch_1):page213_p3v3_stby") )
				( alias ( signalRef "@baseboard_fab2_lib.baseboard_fab2(sch_1):page215_p3v3_stby") )
				( alias ( signalRef "@baseboard_fab2_lib.baseboard_fab2(sch_1):page218_p3v3_stby") )
				( alias ( signalRef "@baseboard_fab2_lib.baseboard_fab2(sch_1):page223_p3v3_stby") )
				( alias ( signalRef "@baseboard_fab2_lib.baseboard_fab2(sch_1):page226_p3v3_stby") )
				( alias ( signalRef "@baseboard_fab2_lib.baseboard_fab2(sch_1):page231_p3v3_stby") )
				( alias ( signalRef "@baseboard_fab2_lib.baseboard_fab2(sch_1):page232_p3v3_stby") )
				( alias ( signalRef "@baseboard_fab2_lib.baseboard_fab2(sch_1):page233_p3v3_stby") )
				( alias ( signalRef "@baseboard_fab2_lib.baseboard_fab2(sch_1):page234_p3v3_stby") )
				( alias ( signalRef "@baseboard_fab2_lib.baseboard_fab2(sch_1):page235_p3v3_stby") )
				( alias ( signalRef "@baseboard_fab2_lib.baseboard_fab2(sch_1):page237_p3v3_stby") )
				( alias ( signalRef "@baseboard_fab2_lib.baseboard_fab2(sch_1):page238_p3v3_stby") )
				( alias ( signalRef "@baseboard_fab2_lib.baseboard_fab2(sch_1):page239_p3v3_stby") )
				( alias ( signalRef "@baseboard_fab2_lib.baseboard_fab2(sch_1):page240_p3v3_stby") )
				( alias ( signalRef "@baseboard_fab2_lib.baseboard_fab2(sch_1):page246_p3v3_stby") )
				( alias ( signalRef "@baseboard_fab2_lib.baseboard_fab2(sch_1):page247_p3v3_stby") )
				( alias ( signalRef "@baseboard_fab2_lib.baseboard_fab2(sch_1):page249_p3v3_stby") )
				( alias ( signalRef "@baseboard_fab2_lib.baseboard_fab2(sch_1):page145_p3v3_stby") )
				( alias ( signalRef "@baseboard_fab2_lib.baseboard_fab2(sch_1):page148_p3v3_stby") )
				( alias ( signalRef "@baseboard_fab2_lib.baseboard_fab2(sch_1):page151_p3v3_stby") )
				( alias ( signalRef "@baseboard_fab2_lib.baseboard_fab2(sch_1):page146_p3v3_stby") )
				( alias ( signalRef "@baseboard_fab2_lib.baseboard_fab2(sch_1):page147_p3v3_stby") )
				( alias ( signalRef "@baseboard_fab2_lib.baseboard_fab2(sch_1):page149_p3v3_stby") )
				( attribute "CDS_PHYS_NET_NAME" "P3V3_STBY"
					( Origin gPackager )
				)
				( attribute "VOLTAGE" "3.3V"
					( Units "uVoltage" "V" 1.000000)
					( Status sAliasFlattened )
					( Status sAliasConflict )
					( Origin gFrontEnd )
				)
				( objectStatus "P3V3_STBY" )
			)
			( signal "@baseboard_fab2_lib.baseboard_fab2(sch_1):page21_p3v3_stby"
				( attribute "VOLTAGE" "3.3V"
					( Units "uVoltage" "V" 1.000000)
					( Origin gFrontEnd )
				)
				( objectFlag fObjectAlias )
				( objectStatus "page21_p3v3_stby" )
			)
			( signal "@baseboard_fab2_lib.baseboard_fab2(sch_1):page38_p3v3_stby"
				( attribute "VOLTAGE" "3.3V"
					( Units "uVoltage" "V" 1.000000)
					( Origin gFrontEnd )
				)
				( objectFlag fObjectAlias )
				( objectStatus "page38_p3v3_stby" )
			)
			( signal "@baseboard_fab2_lib.baseboard_fab2(sch_1):page55_p3v3_stby"
				( attribute "VOLTAGE" "3.3V"
					( Units "uVoltage" "V" 1.000000)
					( Origin gFrontEnd )
				)
				( objectFlag fObjectAlias )
				( objectStatus "page55_p3v3_stby" )
			)
			( signal "@baseboard_fab2_lib.baseboard_fab2(sch_1):page72_p3v3_stby"
				( attribute "VOLTAGE" "3.3V"
					( Units "uVoltage" "V" 1.000000)
					( Origin gFrontEnd )
				)
				( objectFlag fObjectAlias )
				( objectStatus "page72_p3v3_stby" )
			)
			( signal "@baseboard_fab2_lib.baseboard_fab2(sch_1):page89_p3v3_stby"
				( attribute "VOLTAGE" "3.3V"
					( Units "uVoltage" "V" 1.000000)
					( Origin gFrontEnd )
				)
				( objectFlag fObjectAlias )
				( objectStatus "page89_p3v3_stby" )
			)
			( signal "@baseboard_fab2_lib.baseboard_fab2(sch_1):page94_p3v3_stby"
				( attribute "VOLTAGE" "3.3V"
					( Units "uVoltage" "V" 1.000000)
					( Origin gFrontEnd )
				)
				( objectFlag fObjectAlias )
				( objectStatus "page94_p3v3_stby" )
			)
			( signal "@baseboard_fab2_lib.baseboard_fab2(sch_1):page95_p3v3_stby"
				( attribute "VOLTAGE" "3.3V"
					( Units "uVoltage" "V" 1.000000)
					( Origin gFrontEnd )
				)
				( objectFlag fObjectAlias )
				( objectStatus "page95_p3v3_stby" )
			)
			( signal "@baseboard_fab2_lib.baseboard_fab2(sch_1):page96_p3v3_stby"
				( attribute "VOLTAGE" "3.3V"
					( Units "uVoltage" "V" 1.000000)
					( Origin gFrontEnd )
				)
				( objectFlag fObjectAlias )
				( objectStatus "page96_p3v3_stby" )
			)
			( signal "@baseboard_fab2_lib.baseboard_fab2(sch_1):page101_p3v3_stby"
				( attribute "VOLTAGE" "3.3"
					( Units "uVoltage" "V" 1.000000)
					( Origin gFrontEnd )
				)
				( objectFlag fObjectAlias )
				( objectStatus "page101_p3v3_stby" )
			)
			( signal "@baseboard_fab2_lib.baseboard_fab2(sch_1):page108_p3v3_stby"
				( attribute "VOLTAGE" "3.3V"
					( Units "uVoltage" "V" 1.000000)
					( Origin gFrontEnd )
				)
				( objectFlag fObjectAlias )
				( objectStatus "page108_p3v3_stby" )
			)
			( signal "@baseboard_fab2_lib.baseboard_fab2(sch_1):page111_p3v3_stby"
				( attribute "VOLTAGE" "3.3V"
					( Units "uVoltage" "V" 1.000000)
					( Origin gFrontEnd )
				)
				( objectFlag fObjectAlias )
				( objectStatus "page111_p3v3_stby" )
			)
			( signal "@baseboard_fab2_lib.baseboard_fab2(sch_1):page112_p3v3_stby"
				( attribute "VOLTAGE" "+3.3V"
					( Units "uVoltage" "V" 1.000000)
					( Origin gFrontEnd )
				)
				( objectFlag fObjectAlias )
				( objectStatus "page112_p3v3_stby" )
			)
			( signal "@baseboard_fab2_lib.baseboard_fab2(sch_1):page113_p3v3_stby"
				( attribute "VOLTAGE" "3.3V"
					( Units "uVoltage" "V" 1.000000)
					( Origin gFrontEnd )
				)
				( objectFlag fObjectAlias )
				( objectStatus "page113_p3v3_stby" )
			)
			( signal "@baseboard_fab2_lib.baseboard_fab2(sch_1):page118_p3v3_stby"
				( attribute "VOLTAGE" "3.3V"
					( Units "uVoltage" "V" 1.000000)
					( Origin gFrontEnd )
				)
				( objectFlag fObjectAlias )
				( objectStatus "page118_p3v3_stby" )
			)
			( signal "@baseboard_fab2_lib.baseboard_fab2(sch_1):page119_p3v3_stby"
				( attribute "VOLTAGE" "3.3V"
					( Units "uVoltage" "V" 1.000000)
					( Origin gFrontEnd )
				)
				( objectFlag fObjectAlias )
				( objectStatus "page119_p3v3_stby" )
			)
			( signal "@baseboard_fab2_lib.baseboard_fab2(sch_1):page121_p3v3_stby"
				( attribute "VOLTAGE" "3.3V"
					( Units "uVoltage" "V" 1.000000)
					( Origin gFrontEnd )
				)
				( objectFlag fObjectAlias )
				( objectStatus "page121_p3v3_stby" )
			)
			( signal "@baseboard_fab2_lib.baseboard_fab2(sch_1):page122_p3v3_stby"
				( attribute "VOLTAGE" "3.3V"
					( Units "uVoltage" "V" 1.000000)
					( Origin gFrontEnd )
				)
				( objectFlag fObjectAlias )
				( objectStatus "page122_p3v3_stby" )
			)
			( signal "@baseboard_fab2_lib.baseboard_fab2(sch_1):page125_p3v3_stby"
				( attribute "VOLTAGE" "3.3V"
					( Units "uVoltage" "V" 1.000000)
					( Origin gFrontEnd )
				)
				( objectFlag fObjectAlias )
				( objectStatus "page125_p3v3_stby" )
			)
			( signal "@baseboard_fab2_lib.baseboard_fab2(sch_1):page126_p3v3_stby"
				( attribute "VOLTAGE" "3.3V"
					( Units "uVoltage" "V" 1.000000)
					( Origin gFrontEnd )
				)
				( objectFlag fObjectAlias )
				( objectStatus "page126_p3v3_stby" )
			)
			( signal "@baseboard_fab2_lib.baseboard_fab2(sch_1):page130_p3v3_stby"
				( attribute "VOLTAGE" "3.3V"
					( Units "uVoltage" "V" 1.000000)
					( Origin gFrontEnd )
				)
				( objectFlag fObjectAlias )
				( objectStatus "page130_p3v3_stby" )
			)
			( signal "@baseboard_fab2_lib.baseboard_fab2(sch_1):page133_p3v3_stby"
				( attribute "VOLTAGE" "3.3V"
					( Units "uVoltage" "V" 1.000000)
					( Origin gFrontEnd )
				)
				( objectFlag fObjectAlias )
				( objectStatus "page133_p3v3_stby" )
			)
			( signal "@baseboard_fab2_lib.baseboard_fab2(sch_1):page134_p3v3_stby"
				( attribute "VOLTAGE" "3.3V"
					( Units "uVoltage" "V" 1.000000)
					( Origin gFrontEnd )
				)
				( objectFlag fObjectAlias )
				( objectStatus "page134_p3v3_stby" )
			)
			( signal "@baseboard_fab2_lib.baseboard_fab2(sch_1):page135_p3v3_stby"
				( attribute "VOLTAGE" "3.3V"
					( Units "uVoltage" "V" 1.000000)
					( Origin gFrontEnd )
				)
				( objectFlag fObjectAlias )
				( objectStatus "page135_p3v3_stby" )
			)
			( signal "@baseboard_fab2_lib.baseboard_fab2(sch_1):page136_p3v3_stby"
				( attribute "VOLTAGE" "3.3V"
					( Units "uVoltage" "V" 1.000000)
					( Origin gFrontEnd )
				)
				( objectFlag fObjectAlias )
				( objectStatus "page136_p3v3_stby" )
			)
			( signal "@baseboard_fab2_lib.baseboard_fab2(sch_1):page137_p3v3_stby"
				( attribute "VOLTAGE" "3.3V"
					( Units "uVoltage" "V" 1.000000)
					( Origin gFrontEnd )
				)
				( objectFlag fObjectAlias )
				( objectStatus "page137_p3v3_stby" )
			)
			( signal "@baseboard_fab2_lib.baseboard_fab2(sch_1):page138_p3v3_stby"
				( attribute "VOLTAGE" "3.3V"
					( Units "uVoltage" "V" 1.000000)
					( Origin gFrontEnd )
				)
				( objectFlag fObjectAlias )
				( objectStatus "page138_p3v3_stby" )
			)
			( signal "@baseboard_fab2_lib.baseboard_fab2(sch_1):page139_p3v3_stby"
				( attribute "VOLTAGE" "3.3V"
					( Units "uVoltage" "V" 1.000000)
					( Origin gFrontEnd )
				)
				( objectFlag fObjectAlias )
				( objectStatus "page139_p3v3_stby" )
			)
			( signal "@baseboard_fab2_lib.baseboard_fab2(sch_1):page140_p3v3_stby"
				( attribute "VOLTAGE" "3.3V"
					( Units "uVoltage" "V" 1.000000)
					( Origin gFrontEnd )
				)
				( objectFlag fObjectAlias )
				( objectStatus "page140_p3v3_stby" )
			)
			( signal "@baseboard_fab2_lib.baseboard_fab2(sch_1):page141_p3v3_stby"
				( attribute "VOLTAGE" "3.3V"
					( Units "uVoltage" "V" 1.000000)
					( Origin gFrontEnd )
				)
				( objectFlag fObjectAlias )
				( objectStatus "page141_p3v3_stby" )
			)
			( signal "@baseboard_fab2_lib.baseboard_fab2(sch_1):page142_p3v3_stby"
				( attribute "VOLTAGE" "3.3V"
					( Units "uVoltage" "V" 1.000000)
					( Origin gFrontEnd )
				)
				( objectFlag fObjectAlias )
				( objectStatus "page142_p3v3_stby" )
			)
			( signal "@baseboard_fab2_lib.baseboard_fab2(sch_1):page150_p3v3_stby"
				( attribute "VOLTAGE" "3.3V"
					( Units "uVoltage" "V" 1.000000)
					( Origin gFrontEnd )
				)
				( objectFlag fObjectAlias )
				( objectStatus "page150_p3v3_stby" )
			)
			( signal "@baseboard_fab2_lib.baseboard_fab2(sch_1):page153_p3v3_stby"
				( attribute "VOLTAGE" "3.3V"
					( Units "uVoltage" "V" 1.000000)
					( Origin gFrontEnd )
				)
				( objectFlag fObjectAlias )
				( objectStatus "page153_p3v3_stby" )
			)
			( signal "@baseboard_fab2_lib.baseboard_fab2(sch_1):page154_p3v3_stby"
				( attribute "VOLTAGE" "3.3V"
					( Units "uVoltage" "V" 1.000000)
					( Origin gFrontEnd )
				)
				( objectFlag fObjectAlias )
				( objectStatus "page154_p3v3_stby" )
			)
			( signal "@baseboard_fab2_lib.baseboard_fab2(sch_1):page155_p3v3_stby"
				( attribute "VOLTAGE" "3.3V"
					( Units "uVoltage" "V" 1.000000)
					( Origin gFrontEnd )
				)
				( objectFlag fObjectAlias )
				( objectStatus "page155_p3v3_stby" )
			)
			( signal "@baseboard_fab2_lib.baseboard_fab2(sch_1):page156_p3v3_stby"
				( attribute "VOLTAGE" "3.3V"
					( Units "uVoltage" "V" 1.000000)
					( Origin gFrontEnd )
				)
				( objectFlag fObjectAlias )
				( objectStatus "page156_p3v3_stby" )
			)
			( signal "@baseboard_fab2_lib.baseboard_fab2(sch_1):page157_p3v3_stby"
				( attribute "VOLTAGE" "3.3V"
					( Units "uVoltage" "V" 1.000000)
					( Origin gFrontEnd )
				)
				( objectFlag fObjectAlias )
				( objectStatus "page157_p3v3_stby" )
			)
			( signal "@baseboard_fab2_lib.baseboard_fab2(sch_1):page158_p3v3_stby"
				( attribute "VOLTAGE" "3.3V"
					( Units "uVoltage" "V" 1.000000)
					( Origin gFrontEnd )
				)
				( objectFlag fObjectAlias )
				( objectStatus "page158_p3v3_stby" )
			)
			( signal "@baseboard_fab2_lib.baseboard_fab2(sch_1):page159_p3v3_stby"
				( attribute "VOLTAGE" "3.3V"
					( Units "uVoltage" "V" 1.000000)
					( Origin gFrontEnd )
				)
				( objectFlag fObjectAlias )
				( objectStatus "page159_p3v3_stby" )
			)
			( signal "@baseboard_fab2_lib.baseboard_fab2(sch_1):page160_p3v3_stby"
				( attribute "VOLTAGE" "3.3V"
					( Units "uVoltage" "V" 1.000000)
					( Origin gFrontEnd )
				)
				( objectFlag fObjectAlias )
				( objectStatus "page160_p3v3_stby" )
			)
			( signal "@baseboard_fab2_lib.baseboard_fab2(sch_1):page161_p3v3_stby"
				( attribute "VOLTAGE" "3.3V"
					( Units "uVoltage" "V" 1.000000)
					( Origin gFrontEnd )
				)
				( objectFlag fObjectAlias )
				( objectStatus "page161_p3v3_stby" )
			)
			( signal "@baseboard_fab2_lib.baseboard_fab2(sch_1):page162_p3v3_stby"
				( attribute "VOLTAGE" "3.3V"
					( Units "uVoltage" "V" 1.000000)
					( Origin gFrontEnd )
				)
				( objectFlag fObjectAlias )
				( objectStatus "page162_p3v3_stby" )
			)
			( signal "@baseboard_fab2_lib.baseboard_fab2(sch_1):page163_p3v3_stby"
				( attribute "VOLTAGE" "3.3V"
					( Units "uVoltage" "V" 1.000000)
					( Origin gFrontEnd )
				)
				( objectFlag fObjectAlias )
				( objectStatus "page163_p3v3_stby" )
			)
			( signal "@baseboard_fab2_lib.baseboard_fab2(sch_1):page164_p3v3_stby"
				( attribute "VOLTAGE" "3.3V"
					( Units "uVoltage" "V" 1.000000)
					( Origin gFrontEnd )
				)
				( objectFlag fObjectAlias )
				( objectStatus "page164_p3v3_stby" )
			)
			( signal "@baseboard_fab2_lib.baseboard_fab2(sch_1):page165_p3v3_stby"
				( attribute "VOLTAGE" "3.3V"
					( Units "uVoltage" "V" 1.000000)
					( Origin gFrontEnd )
				)
				( objectFlag fObjectAlias )
				( objectStatus "page165_p3v3_stby" )
			)
			( signal "@baseboard_fab2_lib.baseboard_fab2(sch_1):page167_p3v3_stby"
				( attribute "VOLTAGE" "3.3V"
					( Units "uVoltage" "V" 1.000000)
					( Origin gFrontEnd )
				)
				( objectFlag fObjectAlias )
				( objectStatus "page167_p3v3_stby" )
			)
			( signal "@baseboard_fab2_lib.baseboard_fab2(sch_1):page168_p3v3_stby"
				( attribute "VOLTAGE" "3.3V"
					( Units "uVoltage" "V" 1.000000)
					( Origin gFrontEnd )
				)
				( objectFlag fObjectAlias )
				( objectStatus "page168_p3v3_stby" )
			)
			( signal "@baseboard_fab2_lib.baseboard_fab2(sch_1):page169_p3v3_stby"
				( attribute "VOLTAGE" "3.3V"
					( Units "uVoltage" "V" 1.000000)
					( Origin gFrontEnd )
				)
				( objectFlag fObjectAlias )
				( objectStatus "page169_p3v3_stby" )
			)
			( signal "@baseboard_fab2_lib.baseboard_fab2(sch_1):page170_p3v3_stby"
				( attribute "VOLTAGE" "3.3V"
					( Units "uVoltage" "V" 1.000000)
					( Origin gFrontEnd )
				)
				( objectFlag fObjectAlias )
				( objectStatus "page170_p3v3_stby" )
			)
			( signal "@baseboard_fab2_lib.baseboard_fab2(sch_1):page175_p3v3_stby"
				( attribute "VOLTAGE" "3.3V"
					( Units "uVoltage" "V" 1.000000)
					( Origin gFrontEnd )
				)
				( objectFlag fObjectAlias )
				( objectStatus "page175_p3v3_stby" )
			)
			( signal "@baseboard_fab2_lib.baseboard_fab2(sch_1):page176_p3v3_stby"
				( attribute "VOLTAGE" "3.3V"
					( Units "uVoltage" "V" 1.000000)
					( Origin gFrontEnd )
				)
				( objectFlag fObjectAlias )
				( objectStatus "page176_p3v3_stby" )
			)
			( signal "@baseboard_fab2_lib.baseboard_fab2(sch_1):page177_p3v3_stby"
				( attribute "VOLTAGE" "3.3V"
					( Units "uVoltage" "V" 1.000000)
					( Origin gFrontEnd )
				)
				( objectFlag fObjectAlias )
				( objectStatus "page177_p3v3_stby" )
			)
			( signal "@baseboard_fab2_lib.baseboard_fab2(sch_1):page178_p3v3_stby"
				( attribute "VOLTAGE" "3.3V"
					( Units "uVoltage" "V" 1.000000)
					( Origin gFrontEnd )
				)
				( objectFlag fObjectAlias )
				( objectStatus "page178_p3v3_stby" )
			)
			( signal "@baseboard_fab2_lib.baseboard_fab2(sch_1):page181_p3v3_stby"
				( attribute "VOLTAGE" "3.3V"
					( Units "uVoltage" "V" 1.000000)
					( Origin gFrontEnd )
				)
				( objectFlag fObjectAlias )
				( objectStatus "page181_p3v3_stby" )
			)
			( signal "@baseboard_fab2_lib.baseboard_fab2(sch_1):page183_p3v3_stby"
				( attribute "VOLTAGE" "3.3V"
					( Units "uVoltage" "V" 1.000000)
					( Origin gFrontEnd )
				)
				( objectFlag fObjectAlias )
				( objectStatus "page183_p3v3_stby" )
			)
			( signal "@baseboard_fab2_lib.baseboard_fab2(sch_1):page184_p3v3_stby"
				( attribute "VOLTAGE" "3.3V"
					( Units "uVoltage" "V" 1.000000)
					( Origin gFrontEnd )
				)
				( objectFlag fObjectAlias )
				( objectStatus "page184_p3v3_stby" )
			)
			( signal "@baseboard_fab2_lib.baseboard_fab2(sch_1):page185_p3v3_stby"
				( attribute "VOLTAGE" "3.3V"
					( Units "uVoltage" "V" 1.000000)
					( Origin gFrontEnd )
				)
				( objectFlag fObjectAlias )
				( objectStatus "page185_p3v3_stby" )
			)
			( signal "@baseboard_fab2_lib.baseboard_fab2(sch_1):page186_p3v3_stby"
				( attribute "VOLTAGE" "3.3V"
					( Units "uVoltage" "V" 1.000000)
					( Origin gFrontEnd )
				)
				( objectFlag fObjectAlias )
				( objectStatus "page186_p3v3_stby" )
			)
			( signal "@baseboard_fab2_lib.baseboard_fab2(sch_1):page188_p3v3_stby"
				( attribute "VOLTAGE" "3.3V"
					( Units "uVoltage" "V" 1.000000)
					( Origin gFrontEnd )
				)
				( objectFlag fObjectAlias )
				( objectStatus "page188_p3v3_stby" )
			)
			( signal "@baseboard_fab2_lib.baseboard_fab2(sch_1):page189_p3v3_stby"
				( attribute "VOLTAGE" "3.3V"
					( Units "uVoltage" "V" 1.000000)
					( Origin gFrontEnd )
				)
				( objectFlag fObjectAlias )
				( objectStatus "page189_p3v3_stby" )
			)
			( signal "@baseboard_fab2_lib.baseboard_fab2(sch_1):page191_p3v3_stby"
				( attribute "VOLTAGE" "3.3V"
					( Units "uVoltage" "V" 1.000000)
					( Origin gFrontEnd )
				)
				( objectFlag fObjectAlias )
				( objectStatus "page191_p3v3_stby" )
			)
			( signal "@baseboard_fab2_lib.baseboard_fab2(sch_1):page192_p3v3_stby"
				( attribute "VOLTAGE" "3.3V"
					( Units "uVoltage" "V" 1.000000)
					( Origin gFrontEnd )
				)
				( objectFlag fObjectAlias )
				( objectStatus "page192_p3v3_stby" )
			)
			( signal "@baseboard_fab2_lib.baseboard_fab2(sch_1):page193_p3v3_stby"
				( attribute "VOLTAGE" "+3.3V"
					( Units "uVoltage" "V" 1.000000)
					( Origin gFrontEnd )
				)
				( objectFlag fObjectAlias )
				( objectStatus "page193_p3v3_stby" )
			)
			( signal "@baseboard_fab2_lib.baseboard_fab2(sch_1):page194_p3v3_stby"
				( attribute "VOLTAGE" "+3.3V"
					( Units "uVoltage" "V" 1.000000)
					( Origin gFrontEnd )
				)
				( objectFlag fObjectAlias )
				( objectStatus "page194_p3v3_stby" )
			)
			( signal "@baseboard_fab2_lib.baseboard_fab2(sch_1):page196_p3v3_stby"
				( attribute "VOLTAGE" "3.3V"
					( Units "uVoltage" "V" 1.000000)
					( Origin gFrontEnd )
				)
				( objectFlag fObjectAlias )
				( objectStatus "page196_p3v3_stby" )
			)
			( signal "@baseboard_fab2_lib.baseboard_fab2(sch_1):page198_p3v3_stby"
				( attribute "VOLTAGE" "3.3V"
					( Units "uVoltage" "V" 1.000000)
					( Origin gFrontEnd )
				)
				( objectFlag fObjectAlias )
				( objectStatus "page198_p3v3_stby" )
			)
			( signal "@baseboard_fab2_lib.baseboard_fab2(sch_1):page200_p3v3_stby"
				( attribute "VOLTAGE" "+3.3V"
					( Units "uVoltage" "V" 1.000000)
					( Origin gFrontEnd )
				)
				( objectFlag fObjectAlias )
				( objectStatus "page200_p3v3_stby" )
			)
			( signal "@baseboard_fab2_lib.baseboard_fab2(sch_1):page201_p3v3_stby"
				( attribute "VOLTAGE" "3.3V"
					( Units "uVoltage" "V" 1.000000)
					( Origin gFrontEnd )
				)
				( objectFlag fObjectAlias )
				( objectStatus "page201_p3v3_stby" )
			)
			( signal "@baseboard_fab2_lib.baseboard_fab2(sch_1):page206_p3v3_stby"
				( attribute "VOLTAGE" "3.3V"
					( Units "uVoltage" "V" 1.000000)
					( Origin gFrontEnd )
				)
				( objectFlag fObjectAlias )
				( objectStatus "page206_p3v3_stby" )
			)
			( signal "@baseboard_fab2_lib.baseboard_fab2(sch_1):page211_p3v3_stby"
				( attribute "VOLTAGE" "3.3V"
					( Units "uVoltage" "V" 1.000000)
					( Origin gFrontEnd )
				)
				( objectFlag fObjectAlias )
				( objectStatus "page211_p3v3_stby" )
			)
			( signal "@baseboard_fab2_lib.baseboard_fab2(sch_1):page213_p3v3_stby"
				( attribute "VOLTAGE" "3.3V"
					( Units "uVoltage" "V" 1.000000)
					( Origin gFrontEnd )
				)
				( objectFlag fObjectAlias )
				( objectStatus "page213_p3v3_stby" )
			)
			( signal "@baseboard_fab2_lib.baseboard_fab2(sch_1):page215_p3v3_stby"
				( attribute "VOLTAGE" "3.3V"
					( Units "uVoltage" "V" 1.000000)
					( Origin gFrontEnd )
				)
				( objectFlag fObjectAlias )
				( objectStatus "page215_p3v3_stby" )
			)
			( signal "@baseboard_fab2_lib.baseboard_fab2(sch_1):page218_p3v3_stby"
				( attribute "VOLTAGE" "3.3V"
					( Units "uVoltage" "V" 1.000000)
					( Origin gFrontEnd )
				)
				( objectFlag fObjectAlias )
				( objectStatus "page218_p3v3_stby" )
			)
			( signal "@baseboard_fab2_lib.baseboard_fab2(sch_1):page223_p3v3_stby"
				( attribute "VOLTAGE" "3.3V"
					( Units "uVoltage" "V" 1.000000)
					( Origin gFrontEnd )
				)
				( objectFlag fObjectAlias )
				( objectStatus "page223_p3v3_stby" )
			)
			( signal "@baseboard_fab2_lib.baseboard_fab2(sch_1):page226_p3v3_stby"
				( attribute "VOLTAGE" "3.3V"
					( Units "uVoltage" "V" 1.000000)
					( Origin gFrontEnd )
				)
				( objectFlag fObjectAlias )
				( objectStatus "page226_p3v3_stby" )
			)
			( signal "@baseboard_fab2_lib.baseboard_fab2(sch_1):page231_p3v3_stby"
				( attribute "VOLTAGE" "+3.3V"
					( Units "uVoltage" "V" 1.000000)
					( Origin gFrontEnd )
				)
				( objectFlag fObjectAlias )
				( objectStatus "page231_p3v3_stby" )
			)
			( signal "@baseboard_fab2_lib.baseboard_fab2(sch_1):page232_p3v3_stby"
				( attribute "VOLTAGE" "+3.3V"
					( Units "uVoltage" "V" 1.000000)
					( Origin gFrontEnd )
				)
				( objectFlag fObjectAlias )
				( objectStatus "page232_p3v3_stby" )
			)
			( signal "@baseboard_fab2_lib.baseboard_fab2(sch_1):page233_p3v3_stby"
				( attribute "VOLTAGE" "+3.3V"
					( Units "uVoltage" "V" 1.000000)
					( Origin gFrontEnd )
				)
				( objectFlag fObjectAlias )
				( objectStatus "page233_p3v3_stby" )
			)
			( signal "@baseboard_fab2_lib.baseboard_fab2(sch_1):page234_p3v3_stby"
				( attribute "VOLTAGE" "+3.3V"
					( Units "uVoltage" "V" 1.000000)
					( Origin gFrontEnd )
				)
				( objectFlag fObjectAlias )
				( objectStatus "page234_p3v3_stby" )
			)
			( signal "@baseboard_fab2_lib.baseboard_fab2(sch_1):page235_p3v3_stby"
				( attribute "VOLTAGE" "3.3V"
					( Units "uVoltage" "V" 1.000000)
					( Origin gFrontEnd )
				)
				( objectFlag fObjectAlias )
				( objectStatus "page235_p3v3_stby" )
			)
			( signal "@baseboard_fab2_lib.baseboard_fab2(sch_1):page237_p3v3_stby"
				( attribute "VOLTAGE" "3.3V"
					( Units "uVoltage" "V" 1.000000)
					( Origin gFrontEnd )
				)
				( objectFlag fObjectAlias )
				( objectStatus "page237_p3v3_stby" )
			)
			( signal "@baseboard_fab2_lib.baseboard_fab2(sch_1):page238_p3v3_stby"
				( attribute "VOLTAGE" "3.3V"
					( Units "uVoltage" "V" 1.000000)
					( Origin gFrontEnd )
				)
				( objectFlag fObjectAlias )
				( objectStatus "page238_p3v3_stby" )
			)
			( signal "@baseboard_fab2_lib.baseboard_fab2(sch_1):page239_p3v3_stby"
				( attribute "VOLTAGE" "3.3V"
					( Units "uVoltage" "V" 1.000000)
					( Origin gFrontEnd )
				)
				( objectFlag fObjectAlias )
				( objectStatus "page239_p3v3_stby" )
			)
			( signal "@baseboard_fab2_lib.baseboard_fab2(sch_1):page240_p3v3_stby"
				( attribute "VOLTAGE" "+3.3V"
					( Units "uVoltage" "V" 1.000000)
					( Origin gFrontEnd )
				)
				( objectFlag fObjectAlias )
				( objectStatus "page240_p3v3_stby" )
			)
			( signal "@baseboard_fab2_lib.baseboard_fab2(sch_1):page246_p3v3_stby"
				( attribute "VOLTAGE" "3.3V"
					( Units "uVoltage" "V" 1.000000)
					( Origin gFrontEnd )
				)
				( objectFlag fObjectAlias )
				( objectStatus "page246_p3v3_stby" )
			)
			( signal "@baseboard_fab2_lib.baseboard_fab2(sch_1):page247_p3v3_stby"
				( attribute "VOLTAGE" "3.3V"
					( Units "uVoltage" "V" 1.000000)
					( Origin gFrontEnd )
				)
				( objectFlag fObjectAlias )
				( objectStatus "page247_p3v3_stby" )
			)
			( signal "@baseboard_fab2_lib.baseboard_fab2(sch_1):page249_p3v3_stby"
				( attribute "VOLTAGE" "3.3V"
					( Units "uVoltage" "V" 1.000000)
					( Origin gFrontEnd )
				)
				( objectFlag fObjectAlias )
				( objectStatus "page249_p3v3_stby" )
			)
			( signal "@baseboard_fab2_lib.baseboard_fab2(sch_1):page145_p3v3_stby"
				( attribute "VOLTAGE" "3.3V"
					( Units "uVoltage" "V" 1.000000)
					( Origin gFrontEnd )
				)
				( objectFlag fObjectAlias )
				( objectStatus "page145_p3v3_stby" )
			)
			( signal "@baseboard_fab2_lib.baseboard_fab2(sch_1):page148_p3v3_stby"
				( attribute "VOLTAGE" "3.3V"
					( Units "uVoltage" "V" 1.000000)
					( Origin gFrontEnd )
				)
				( objectFlag fObjectAlias )
				( objectStatus "page148_p3v3_stby" )
			)
			( signal "@baseboard_fab2_lib.baseboard_fab2(sch_1):page151_p3v3_stby"
				( attribute "VOLTAGE" "3.3V"
					( Units "uVoltage" "V" 1.000000)
					( Origin gFrontEnd )
				)
				( objectFlag fObjectAlias )
				( objectStatus "page151_p3v3_stby" )
			)
			( signal "@baseboard_fab2_lib.baseboard_fab2(sch_1):page146_p3v3_stby"
				( attribute "VOLTAGE" "3.3V"
					( Units "uVoltage" "V" 1.000000)
					( Origin gFrontEnd )
				)
				( objectFlag fObjectAlias )
				( objectStatus "page146_p3v3_stby" )
			)
			( signal "@baseboard_fab2_lib.baseboard_fab2(sch_1):page147_p3v3_stby"
				( attribute "VOLTAGE" "3.3V"
					( Units "uVoltage" "V" 1.000000)
					( Origin gFrontEnd )
				)
				( objectFlag fObjectAlias )
				( objectStatus "page147_p3v3_stby" )
			)
			( signal "@baseboard_fab2_lib.baseboard_fab2(sch_1):page149_p3v3_stby"
				( attribute "VOLTAGE" "3.3V"
					( Units "uVoltage" "V" 1.000000)
					( Origin gFrontEnd )
				)
				( objectFlag fObjectAlias )
				( objectStatus "page149_p3v3_stby" )
			)
			( signal "@baseboard_fab2_lib.baseboard_fab2(sch_1):smb_ie_3v3aux_scl"
				( attribute "CDS_PHYS_NET_NAME" "SMB_IE_3V3AUX_SCL"
					( Origin gPackager )
				)
				( objectStatus "SMB_IE_3V3AUX_SCL" )
			)
			( signal "@baseboard_fab2_lib.baseboard_fab2(sch_1):page150_vcc_dacav3v3"
				( objectFlag fObjectAlias )
				( objectStatus "page150_vcc_dacav3v3" )
			)
			( signal "@baseboard_fab2_lib.baseboard_fab2(sch_1):pd_cpu0_bist_enable"
				( attribute "CDS_PHYS_NET_NAME" "PD_CPU0_BIST_ENABLE"
					( Origin gPackager )
				)
				( objectStatus "PD_CPU0_BIST_ENABLE" )
			)
			( signal "@baseboard_fab2_lib.baseboard_fab2(sch_1):pd_cpu0_ksfc_dis"
				( attribute "CDS_PHYS_NET_NAME" "PD_CPU0_KSFC_DIS"
					( Origin gPackager )
				)
				( objectStatus "PD_CPU0_KSFC_DIS" )
			)
			( signal "@baseboard_fab2_lib.baseboard_fab2(sch_1):pd_cpu0_test12"
				( attribute "CDS_PHYS_NET_NAME" "PD_CPU0_TEST12"
					( Origin gPackager )
				)
				( objectStatus "PD_CPU0_TEST12" )
			)
			( signal "@baseboard_fab2_lib.baseboard_fab2(sch_1):pd_cpu0_test13"
				( attribute "CDS_PHYS_NET_NAME" "PD_CPU0_TEST13"
					( Origin gPackager )
				)
				( objectStatus "PD_CPU0_TEST13" )
			)
			( signal "@baseboard_fab2_lib.baseboard_fab2(sch_1):pd_cpu0_test14"
				( attribute "CDS_PHYS_NET_NAME" "PD_CPU0_TEST14"
					( Origin gPackager )
				)
				( objectStatus "PD_CPU0_TEST14" )
			)
			( signal "@baseboard_fab2_lib.baseboard_fab2(sch_1):pd_cpu0_txt_plten"
				( attribute "CDS_PHYS_NET_NAME" "PD_CPU0_TXT_PLTEN"
					( Origin gPackager )
				)
				( objectStatus "PD_CPU0_TXT_PLTEN" )
			)
			( signal "@baseboard_fab2_lib.baseboard_fab2(sch_1):pd_pirom_cpu0_addr0"
				( attribute "CDS_PHYS_NET_NAME" "PD_PIROM_CPU0_ADDR0"
					( Origin gPackager )
				)
				( objectStatus "PD_PIROM_CPU0_ADDR0" )
			)
			( signal "@baseboard_fab2_lib.baseboard_fab2(sch_1):pd_pirom_cpu0_addr1"
				( attribute "CDS_PHYS_NET_NAME" "PD_PIROM_CPU0_ADDR1"
					( Origin gPackager )
				)
				( objectStatus "PD_PIROM_CPU0_ADDR1" )
			)
			( signal "@baseboard_fab2_lib.baseboard_fab2(sch_1):pd_pirom_cpu0_addr2"
				( attribute "CDS_PHYS_NET_NAME" "PD_PIROM_CPU0_ADDR2"
					( Origin gPackager )
				)
				( objectStatus "PD_PIROM_CPU0_ADDR2" )
			)
			( signal "@baseboard_fab2_lib.baseboard_fab2(sch_1):peci_cpu_g"
				( attribute "CDS_PHYS_NET_NAME" "PECI_CPU_G"
					( Origin gPackager )
				)
				( objectStatus "PECI_CPU_G" )
			)
			( signal "@baseboard_fab2_lib.baseboard_fab2(sch_1):pu_cpu0_ear_n"
				( attribute "CDS_PHYS_NET_NAME" "PU_CPU0_EAR_N"
					( Origin gPackager )
				)
				( objectStatus "PU_CPU0_EAR_N" )
			)
			( signal "@baseboard_fab2_lib.baseboard_fab2(sch_1):pu_cpu0_frmagent"
				( attribute "CDS_PHYS_NET_NAME" "PU_CPU0_FRMAGENT"
					( Origin gPackager )
				)
				( objectStatus "PU_CPU0_FRMAGENT" )
			)
			( signal "@baseboard_fab2_lib.baseboard_fab2(sch_1):pu_cpu0_legacy_skt"
				( attribute "CDS_PHYS_NET_NAME" "PU_CPU0_LEGACY_SKT"
					( Origin gPackager )
				)
				( objectStatus "PU_CPU0_LEGACY_SKT" )
			)
			( signal "@baseboard_fab2_lib.baseboard_fab2(sch_1):pu_cpu0_safe_mode_boot"
				( attribute "CDS_PHYS_NET_NAME" "PU_CPU0_SAFE_MODE_BOOT"
					( Origin gPackager )
				)
				( objectStatus "PU_CPU0_SAFE_MODE_BOOT" )
			)
			( signal "@baseboard_fab2_lib.baseboard_fab2(sch_1):pu_cpu0_socket_id_0"
				( attribute "CDS_PHYS_NET_NAME" "PU_CPU0_SOCKET_ID_0"
					( Origin gPackager )
				)
				( objectStatus "PU_CPU0_SOCKET_ID_0" )
			)
			( signal "@baseboard_fab2_lib.baseboard_fab2(sch_1):pu_cpu0_socket_id_1"
				( attribute "CDS_PHYS_NET_NAME" "PU_CPU0_SOCKET_ID_1"
					( Origin gPackager )
				)
				( objectStatus "PU_CPU0_SOCKET_ID_1" )
			)
			( signal "@baseboard_fab2_lib.baseboard_fab2(sch_1):pu_cpu0_tsc_sync"
				( attribute "CDS_PHYS_NET_NAME" "PU_CPU0_TSC_SYNC"
					( Origin gPackager )
				)
				( objectStatus "PU_CPU0_TSC_SYNC" )
			)
			( signal "@baseboard_fab2_lib.baseboard_fab2(sch_1):pu_cpu0_txt_agent"
				( attribute "CDS_PHYS_NET_NAME" "PU_CPU0_TXT_AGENT"
					( Origin gPackager )
				)
				( objectStatus "PU_CPU0_TXT_AGENT" )
			)
			( signal "@baseboard_fab2_lib.baseboard_fab2(sch_1):pvccio_cpu0"
				( alias ( signalRef "@baseboard_fab2_lib.baseboard_fab2(sch_1):page21_pvccio_cpu0") )
				( alias ( signalRef "@baseboard_fab2_lib.baseboard_fab2(sch_1):page37_pvccio_cpu0") )
				( alias ( signalRef "@baseboard_fab2_lib.baseboard_fab2(sch_1):page38_pvccio_cpu0") )
				( alias ( signalRef "@baseboard_fab2_lib.baseboard_fab2(sch_1):page39_pvccio_cpu0") )
				( alias ( signalRef "@baseboard_fab2_lib.baseboard_fab2(sch_1):page42_pvccio_cpu0") )
				( alias ( signalRef "@baseboard_fab2_lib.baseboard_fab2(sch_1):page90_pvccio_cpu0") )
				( alias ( signalRef "@baseboard_fab2_lib.baseboard_fab2(sch_1):page92_pvccio_cpu0") )
				( alias ( signalRef "@baseboard_fab2_lib.baseboard_fab2(sch_1):page93_pvccio_cpu0") )
				( alias ( signalRef "@baseboard_fab2_lib.baseboard_fab2(sch_1):page96_pvccio_cpu0") )
				( alias ( signalRef "@baseboard_fab2_lib.baseboard_fab2(sch_1):page97_pvccio_cpu0") )
				( alias ( signalRef "@baseboard_fab2_lib.baseboard_fab2(sch_1):page99_pvccio_cpu0") )
				( alias ( signalRef "@baseboard_fab2_lib.baseboard_fab2(sch_1):page111_pvccio_cpu0") )
				( alias ( signalRef "@baseboard_fab2_lib.baseboard_fab2(sch_1):page112_pvccio_cpu0") )
				( alias ( signalRef "@baseboard_fab2_lib.baseboard_fab2(sch_1):page152_pvccio_cpu0") )
				( alias ( signalRef "@baseboard_fab2_lib.baseboard_fab2(sch_1):page166_pvccio_cpu0") )
				( alias ( signalRef "@baseboard_fab2_lib.baseboard_fab2(sch_1):page194_pvccio_cpu0") )
				( alias ( signalRef "@baseboard_fab2_lib.baseboard_fab2(sch_1):page201_pvccio_cpu0") )
				( alias ( signalRef "@baseboard_fab2_lib.baseboard_fab2(sch_1):page211_pvccio_cpu0") )
				( alias ( signalRef "@baseboard_fab2_lib.baseboard_fab2(sch_1):page212_pvccio_cpu0") )
				( alias ( signalRef "@baseboard_fab2_lib.baseboard_fab2(sch_1):page215_pvccio_cpu0") )
				( alias ( signalRef "@baseboard_fab2_lib.baseboard_fab2(sch_1):page218_pvccio_cpu0") )
				( alias ( signalRef "@baseboard_fab2_lib.baseboard_fab2(sch_1):page148_pvccio_cpu0") )
				( attribute "CDS_PHYS_NET_NAME" "PVCCIO_CPU0"
					( Origin gPackager )
				)
				( attribute "VOLTAGE" "1.1V"
					( Units "uVoltage" "V" 1.000000)
					( Status sAliasFlattened )
					( Origin gFrontEnd )
				)
				( objectStatus "PVCCIO_CPU0" )
			)
			( signal "@baseboard_fab2_lib.baseboard_fab2(sch_1):page21_pvccio_cpu0"
				( attribute "VOLTAGE" "1.1V"
					( Units "uVoltage" "V" 1.000000)
					( Origin gFrontEnd )
				)
				( objectFlag fObjectAlias )
				( objectStatus "page21_pvccio_cpu0" )
			)
			( signal "@baseboard_fab2_lib.baseboard_fab2(sch_1):page37_pvccio_cpu0"
				( attribute "VOLTAGE" "1.1V"
					( Units "uVoltage" "V" 1.000000)
					( Origin gFrontEnd )
				)
				( objectFlag fObjectAlias )
				( objectStatus "page37_pvccio_cpu0" )
			)
			( signal "@baseboard_fab2_lib.baseboard_fab2(sch_1):page38_pvccio_cpu0"
				( attribute "VOLTAGE" "1.1V"
					( Units "uVoltage" "V" 1.000000)
					( Origin gFrontEnd )
				)
				( objectFlag fObjectAlias )
				( objectStatus "page38_pvccio_cpu0" )
			)
			( signal "@baseboard_fab2_lib.baseboard_fab2(sch_1):page39_pvccio_cpu0"
				( attribute "VOLTAGE" "1.1V"
					( Units "uVoltage" "V" 1.000000)
					( Origin gFrontEnd )
				)
				( objectFlag fObjectAlias )
				( objectStatus "page39_pvccio_cpu0" )
			)
			( signal "@baseboard_fab2_lib.baseboard_fab2(sch_1):page42_pvccio_cpu0"
				( attribute "VOLTAGE" "1.1V"
					( Units "uVoltage" "V" 1.000000)
					( Origin gFrontEnd )
				)
				( objectFlag fObjectAlias )
				( objectStatus "page42_pvccio_cpu0" )
			)
			( signal "@baseboard_fab2_lib.baseboard_fab2(sch_1):page90_pvccio_cpu0"
				( attribute "VOLTAGE" "1.1V"
					( Units "uVoltage" "V" 1.000000)
					( Origin gFrontEnd )
				)
				( objectFlag fObjectAlias )
				( objectStatus "page90_pvccio_cpu0" )
			)
			( signal "@baseboard_fab2_lib.baseboard_fab2(sch_1):page92_pvccio_cpu0"
				( attribute "VOLTAGE" "1.1V"
					( Units "uVoltage" "V" 1.000000)
					( Origin gFrontEnd )
				)
				( objectFlag fObjectAlias )
				( objectStatus "page92_pvccio_cpu0" )
			)
			( signal "@baseboard_fab2_lib.baseboard_fab2(sch_1):page93_pvccio_cpu0"
				( attribute "VOLTAGE" "1.1V"
					( Units "uVoltage" "V" 1.000000)
					( Origin gFrontEnd )
				)
				( objectFlag fObjectAlias )
				( objectStatus "page93_pvccio_cpu0" )
			)
			( signal "@baseboard_fab2_lib.baseboard_fab2(sch_1):page96_pvccio_cpu0"
				( attribute "VOLTAGE" "1.1V"
					( Units "uVoltage" "V" 1.000000)
					( Origin gFrontEnd )
				)
				( objectFlag fObjectAlias )
				( objectStatus "page96_pvccio_cpu0" )
			)
			( signal "@baseboard_fab2_lib.baseboard_fab2(sch_1):page97_pvccio_cpu0"
				( attribute "VOLTAGE" "1.1V"
					( Units "uVoltage" "V" 1.000000)
					( Origin gFrontEnd )
				)
				( objectFlag fObjectAlias )
				( objectStatus "page97_pvccio_cpu0" )
			)
			( signal "@baseboard_fab2_lib.baseboard_fab2(sch_1):page99_pvccio_cpu0"
				( attribute "VOLTAGE" "1.1V"
					( Units "uVoltage" "V" 1.000000)
					( Origin gFrontEnd )
				)
				( objectFlag fObjectAlias )
				( objectStatus "page99_pvccio_cpu0" )
			)
			( signal "@baseboard_fab2_lib.baseboard_fab2(sch_1):page111_pvccio_cpu0"
				( attribute "VOLTAGE" "1.1V"
					( Units "uVoltage" "V" 1.000000)
					( Origin gFrontEnd )
				)
				( objectFlag fObjectAlias )
				( objectStatus "page111_pvccio_cpu0" )
			)
			( signal "@baseboard_fab2_lib.baseboard_fab2(sch_1):page112_pvccio_cpu0"
				( attribute "VOLTAGE" "1.1V"
					( Units "uVoltage" "V" 1.000000)
					( Origin gFrontEnd )
				)
				( objectFlag fObjectAlias )
				( objectStatus "page112_pvccio_cpu0" )
			)
			( signal "@baseboard_fab2_lib.baseboard_fab2(sch_1):page152_pvccio_cpu0"
				( attribute "VOLTAGE" "1.1V"
					( Units "uVoltage" "V" 1.000000)
					( Origin gFrontEnd )
				)
				( objectFlag fObjectAlias )
				( objectStatus "page152_pvccio_cpu0" )
			)
			( signal "@baseboard_fab2_lib.baseboard_fab2(sch_1):page166_pvccio_cpu0"
				( attribute "VOLTAGE" "1.1V"
					( Units "uVoltage" "V" 1.000000)
					( Origin gFrontEnd )
				)
				( objectFlag fObjectAlias )
				( objectStatus "page166_pvccio_cpu0" )
			)
			( signal "@baseboard_fab2_lib.baseboard_fab2(sch_1):page194_pvccio_cpu0"
				( attribute "VOLTAGE" "1.1V"
					( Units "uVoltage" "V" 1.000000)
					( Origin gFrontEnd )
				)
				( objectFlag fObjectAlias )
				( objectStatus "page194_pvccio_cpu0" )
			)
			( signal "@baseboard_fab2_lib.baseboard_fab2(sch_1):page201_pvccio_cpu0"
				( attribute "VOLTAGE" "1.1V"
					( Units "uVoltage" "V" 1.000000)
					( Origin gFrontEnd )
				)
				( objectFlag fObjectAlias )
				( objectStatus "page201_pvccio_cpu0" )
			)
			( signal "@baseboard_fab2_lib.baseboard_fab2(sch_1):page211_pvccio_cpu0"
				( attribute "VOLTAGE" "1.1V"
					( Units "uVoltage" "V" 1.000000)
					( Origin gFrontEnd )
				)
				( objectFlag fObjectAlias )
				( objectStatus "page211_pvccio_cpu0" )
			)
			( signal "@baseboard_fab2_lib.baseboard_fab2(sch_1):page212_pvccio_cpu0"
				( attribute "VOLTAGE" "1.1V"
					( Units "uVoltage" "V" 1.000000)
					( Origin gFrontEnd )
				)
				( objectFlag fObjectAlias )
				( objectStatus "page212_pvccio_cpu0" )
			)
			( signal "@baseboard_fab2_lib.baseboard_fab2(sch_1):page215_pvccio_cpu0"
				( attribute "VOLTAGE" "1.1V"
					( Units "uVoltage" "V" 1.000000)
					( Origin gFrontEnd )
				)
				( objectFlag fObjectAlias )
				( objectStatus "page215_pvccio_cpu0" )
			)
			( signal "@baseboard_fab2_lib.baseboard_fab2(sch_1):page218_pvccio_cpu0"
				( attribute "VOLTAGE" "1.1V"
					( Units "uVoltage" "V" 1.000000)
					( Origin gFrontEnd )
				)
				( objectFlag fObjectAlias )
				( objectStatus "page218_pvccio_cpu0" )
			)
			( signal "@baseboard_fab2_lib.baseboard_fab2(sch_1):page148_pvccio_cpu0"
				( attribute "VOLTAGE" "1.1V"
					( Units "uVoltage" "V" 1.000000)
					( Origin gFrontEnd )
				)
				( objectFlag fObjectAlias )
				( objectStatus "page148_pvccio_cpu0" )
			)
			( signal "@baseboard_fab2_lib.baseboard_fab2(sch_1):p1v15_aux_bmc"
				( alias ( signalRef "@baseboard_fab2_lib.baseboard_fab2(sch_1):page238_p1v15_aux_bmc") )
				( alias ( signalRef "@baseboard_fab2_lib.baseboard_fab2(sch_1):page150_p1v15_aux_bmc") )
				( alias ( signalRef "@baseboard_fab2_lib.baseboard_fab2(sch_1):page148_p1v15_aux_bmc") )
				( attribute "VOLTAGE" "1.5"
					( Units "uVoltage" "V" 1.000000)
					( Status sAliasFlattened )
					( Origin gFrontEnd )
				)
				( attribute "CDS_PHYS_NET_NAME" "P1V15_AUX_BMC"
					( Origin gPackager )
				)
				( objectStatus "P1V15_AUX_BMC" )
			)
			( signal "@baseboard_fab2_lib.baseboard_fab2(sch_1):page238_p1v15_aux_bmc"
				( attribute "VOLTAGE" "1.5"
					( Units "uVoltage" "V" 1.000000)
					( Origin gFrontEnd )
				)
				( objectFlag fObjectAlias )
				( objectStatus "page238_p1v15_aux_bmc" )
			)
			( signal "@baseboard_fab2_lib.baseboard_fab2(sch_1):page150_p1v15_aux_bmc"
				( objectFlag fObjectAlias )
				( objectStatus "page150_p1v15_aux_bmc" )
			)
			( signal "@baseboard_fab2_lib.baseboard_fab2(sch_1):page148_p1v15_aux_bmc"
				( objectFlag fObjectAlias )
				( objectStatus "page148_p1v15_aux_bmc" )
			)
			( signal "@baseboard_fab2_lib.baseboard_fab2(sch_1):pwrgd_cpu0_drampwrok_abc_g"
				( attribute "CDS_PHYS_NET_NAME" "PWRGD_CPU0_DRAMPWROK_ABC_G"
					( Origin gPackager )
				)
				( objectStatus "PWRGD_CPU0_DRAMPWROK_ABC_G" )
			)
			( signal "@baseboard_fab2_lib.baseboard_fab2(sch_1):pwrgd_cpu0_drampwrok_def_g"
				( attribute "CDS_PHYS_NET_NAME" "PWRGD_CPU0_DRAMPWROK_DEF_G"
					( Origin gPackager )
				)
				( objectStatus "PWRGD_CPU0_DRAMPWROK_DEF_G" )
			)
			( signal "@baseboard_fab2_lib.baseboard_fab2(sch_1):pwrgd_cpu0_g"
				( attribute "CDS_PHYS_NET_NAME" "PWRGD_CPU0_G"
					( Origin gPackager )
				)
				( objectStatus "PWRGD_CPU0_G" )
			)
			( signal "@baseboard_fab2_lib.baseboard_fab2(sch_1):rst_cpu0_g_n"
				( attribute "CDS_PHYS_NET_NAME" "RST_CPU0_G_N"
					( Origin gPackager )
				)
				( objectStatus "RST_CPU0_G_N" )
			)
			( signal "@baseboard_fab2_lib.baseboard_fab2(sch_1):smb_ddr_abc_scl_g_r"
				( attribute "CDS_PHYS_NET_NAME" "SMB_DDR_ABC_SCL_G_R"
					( Origin gPackager )
				)
				( objectStatus "SMB_DDR_ABC_SCL_G_R" )
			)
			( signal "@baseboard_fab2_lib.baseboard_fab2(sch_1):smb_ddr_abc_sda_g_r"
				( attribute "CDS_PHYS_NET_NAME" "SMB_DDR_ABC_SDA_G_R"
					( Origin gPackager )
				)
				( objectStatus "SMB_DDR_ABC_SDA_G_R" )
			)
			( signal "@baseboard_fab2_lib.baseboard_fab2(sch_1):smb_ddr_def_scl_g_r"
				( attribute "CDS_PHYS_NET_NAME" "SMB_DDR_DEF_SCL_G_R"
					( Origin gPackager )
				)
				( objectStatus "SMB_DDR_DEF_SCL_G_R" )
			)
			( signal "@baseboard_fab2_lib.baseboard_fab2(sch_1):smb_ddr_def_sda_g_r"
				( attribute "CDS_PHYS_NET_NAME" "SMB_DDR_DEF_SDA_G_R"
					( Origin gPackager )
				)
				( objectStatus "SMB_DDR_DEF_SDA_G_R" )
			)
			( signal "@baseboard_fab2_lib.baseboard_fab2(sch_1):smb_pirom_cpu0_scl"
				( attribute "CDS_PHYS_NET_NAME" "SMB_PIROM_CPU0_SCL"
					( Origin gPackager )
				)
				( objectStatus "SMB_PIROM_CPU0_SCL" )
			)
			( signal "@baseboard_fab2_lib.baseboard_fab2(sch_1):smb_pirom_cpu0_sda"
				( attribute "CDS_PHYS_NET_NAME" "SMB_PIROM_CPU0_SDA"
					( Origin gPackager )
				)
				( objectStatus "SMB_PIROM_CPU0_SDA" )
			)
			( signal "@baseboard_fab2_lib.baseboard_fab2(sch_1):svid_alert0_cpu0_n"
				( attribute "CDS_PHYS_NET_NAME" "SVID_ALERT0_CPU0_N"
					( Origin gPackager )
				)
				( objectStatus "SVID_ALERT0_CPU0_N" )
			)
			( signal "@baseboard_fab2_lib.baseboard_fab2(sch_1):svid_alert0_cpu0_r_n"
				( attribute "CDS_PHYS_NET_NAME" "SVID_ALERT0_CPU0_R_N"
					( Origin gPackager )
				)
				( objectStatus "SVID_ALERT0_CPU0_R_N" )
			)
			( signal "@baseboard_fab2_lib.baseboard_fab2(sch_1):svid_alert1_cpu0_n"
				( attribute "CDS_PHYS_NET_NAME" "SVID_ALERT1_CPU0_N"
					( Origin gPackager )
				)
				( objectStatus "SVID_ALERT1_CPU0_N" )
			)
			( signal "@baseboard_fab2_lib.baseboard_fab2(sch_1):svid_alert1_cpu0_r_n"
				( attribute "CDS_PHYS_NET_NAME" "SVID_ALERT1_CPU0_R_N"
					( Origin gPackager )
				)
				( objectStatus "SVID_ALERT1_CPU0_R_N" )
			)
			( signal "@baseboard_fab2_lib.baseboard_fab2(sch_1):svid_clk0_cpu0"
				( attribute "CDS_PHYS_NET_NAME" "SVID_CLK0_CPU0"
					( Origin gPackager )
				)
				( objectStatus "SVID_CLK0_CPU0" )
			)
			( signal "@baseboard_fab2_lib.baseboard_fab2(sch_1):svid_clk0_cpu0_r"
				( attribute "CDS_PHYS_NET_NAME" "SVID_CLK0_CPU0_R"
					( Origin gPackager )
				)
				( objectStatus "SVID_CLK0_CPU0_R" )
			)
			( signal "@baseboard_fab2_lib.baseboard_fab2(sch_1):svid_clk1_cpu0"
				( attribute "CDS_PHYS_NET_NAME" "SVID_CLK1_CPU0"
					( Origin gPackager )
				)
				( objectStatus "SVID_CLK1_CPU0" )
			)
			( signal "@baseboard_fab2_lib.baseboard_fab2(sch_1):svid_clk1_cpu0_r"
				( attribute "CDS_PHYS_NET_NAME" "SVID_CLK1_CPU0_R"
					( Origin gPackager )
				)
				( objectStatus "SVID_CLK1_CPU0_R" )
			)
			( signal "@baseboard_fab2_lib.baseboard_fab2(sch_1):svid_dio0_cpu0"
				( attribute "CDS_PHYS_NET_NAME" "SVID_DIO0_CPU0"
					( Origin gPackager )
				)
				( objectStatus "SVID_DIO0_CPU0" )
			)
			( signal "@baseboard_fab2_lib.baseboard_fab2(sch_1):svid_dio0_cpu0_r"
				( attribute "CDS_PHYS_NET_NAME" "SVID_DIO0_CPU0_R"
					( Origin gPackager )
				)
				( objectStatus "SVID_DIO0_CPU0_R" )
			)
			( signal "@baseboard_fab2_lib.baseboard_fab2(sch_1):svid_dio1_cpu0"
				( attribute "CDS_PHYS_NET_NAME" "SVID_DIO1_CPU0"
					( Origin gPackager )
				)
				( objectStatus "SVID_DIO1_CPU0" )
			)
			( signal "@baseboard_fab2_lib.baseboard_fab2(sch_1):svid_dio1_cpu0_r"
				( attribute "CDS_PHYS_NET_NAME" "SVID_DIO1_CPU0_R"
					( Origin gPackager )
				)
				( objectStatus "SVID_DIO1_CPU0_R" )
			)
			( signal "@baseboard_fab2_lib.baseboard_fab2(sch_1):tp_cpu0_pe_hp_scl"
				( attribute "CDS_PHYS_NET_NAME" "TP_CPU0_PE_HP_SCL"
					( Origin gPackager )
				)
				( objectStatus "TP_CPU0_PE_HP_SCL" )
			)
			( signal "@baseboard_fab2_lib.baseboard_fab2(sch_1):tp_cpu0_pe_hp_sda"
				( attribute "CDS_PHYS_NET_NAME" "TP_CPU0_PE_HP_SDA"
					( Origin gPackager )
				)
				( objectStatus "TP_CPU0_PE_HP_SDA" )
			)
			( signal "@baseboard_fab2_lib.baseboard_fab2(sch_1):tp_cpu0_procdis_g_n"
				( attribute "CDS_PHYS_NET_NAME" "TP_CPU0_PROCDIS_G_N"
					( Origin gPackager )
				)
				( objectStatus "TP_CPU0_PROCDIS_G_N" )
			)
			( signal "@baseboard_fab2_lib.baseboard_fab2(sch_1):tp_cpu0_socket_id_2"
				( attribute "CDS_PHYS_NET_NAME" "TP_CPU0_SOCKET_ID_2"
					( Origin gPackager )
				)
				( objectStatus "TP_CPU0_SOCKET_ID_2" )
			)
			( signal "@baseboard_fab2_lib.baseboard_fab2(sch_1):tp_nmi_cpu0"
				( attribute "CDS_PHYS_NET_NAME" "TP_NMI_CPU0"
					( Origin gPackager )
				)
				( objectStatus "TP_NMI_CPU0" )
			)
			( signal "@baseboard_fab2_lib.baseboard_fab2(sch_1):tp_xdp_cpu0_obsdata_a0_mbp2_n"
				( attribute "CDS_PHYS_NET_NAME" "TP_XDP_CPU0_OBSDATA_A0_MBP2_N"
					( Origin gPackager )
				)
				( objectStatus "TP_XDP_CPU0_OBSDATA_A0_MBP2_N" )
			)
			( signal "@baseboard_fab2_lib.baseboard_fab2(sch_1):tp_xdp_cpu0_obsdata_a1_mbp3_n"
				( attribute "CDS_PHYS_NET_NAME" "TP_XDP_CPU0_OBSDATA_A1_MBP3_N"
					( Origin gPackager )
				)
				( objectStatus "TP_XDP_CPU0_OBSDATA_A1_MBP3_N" )
			)
			( signal "@baseboard_fab2_lib.baseboard_fab2(sch_1):tp_xdp_cpu0_obsdata_a2_mbp4_n"
				( attribute "CDS_PHYS_NET_NAME" "TP_XDP_CPU0_OBSDATA_A2_MBP4_N"
					( Origin gPackager )
				)
				( objectStatus "TP_XDP_CPU0_OBSDATA_A2_MBP4_N" )
			)
			( signal "@baseboard_fab2_lib.baseboard_fab2(sch_1):tp_xdp_cpu0_obsdata_a3_mbp5_n"
				( attribute "CDS_PHYS_NET_NAME" "TP_XDP_CPU0_OBSDATA_A3_MBP5_N"
					( Origin gPackager )
				)
				( objectStatus "TP_XDP_CPU0_OBSDATA_A3_MBP5_N" )
			)
			( signal "@baseboard_fab2_lib.baseboard_fab2(sch_1):xdp_cpu0_tdo"
				( attribute "CDS_PHYS_NET_NAME" "XDP_CPU0_TDO"
					( Origin gPackager )
				)
				( objectStatus "XDP_CPU0_TDO" )
			)
			( signal "@baseboard_fab2_lib.baseboard_fab2(sch_1):xdp_cpu_mbp0_n"
				( attribute "CDS_PHYS_NET_NAME" "XDP_CPU_MBP0_N"
					( Origin gPackager )
				)
				( objectStatus "XDP_CPU_MBP0_N" )
			)
			( signal "@baseboard_fab2_lib.baseboard_fab2(sch_1):xdp_cpu_mbp1_n"
				( attribute "CDS_PHYS_NET_NAME" "XDP_CPU_MBP1_N"
					( Origin gPackager )
				)
				( objectStatus "XDP_CPU_MBP1_N" )
			)
			( signal "@baseboard_fab2_lib.baseboard_fab2(sch_1):xdp_cpu_obsfn_b0_mbp6_n"
				( attribute "CDS_PHYS_NET_NAME" "XDP_CPU_OBSFN_B0_MBP6_N"
					( Origin gPackager )
				)
				( objectStatus "XDP_CPU_OBSFN_B0_MBP6_N" )
			)
			( signal "@baseboard_fab2_lib.baseboard_fab2(sch_1):xdp_cpu_obsfn_b1_mbp7_n"
				( attribute "CDS_PHYS_NET_NAME" "XDP_CPU_OBSFN_B1_MBP7_N"
					( Origin gPackager )
				)
				( objectStatus "XDP_CPU_OBSFN_B1_MBP7_N" )
			)
			( signal "@baseboard_fab2_lib.baseboard_fab2(sch_1):xdp_cpu_prdy_n"
				( attribute "CDS_PHYS_NET_NAME" "XDP_CPU_PRDY_N"
					( Origin gPackager )
				)
				( objectStatus "XDP_CPU_PRDY_N" )
			)
			( signal "@baseboard_fab2_lib.baseboard_fab2(sch_1):xdp_cpu_preq_n"
				( attribute "CDS_PHYS_NET_NAME" "XDP_CPU_PREQ_N"
					( Origin gPackager )
				)
				( objectStatus "XDP_CPU_PREQ_N" )
			)
			( signal "@baseboard_fab2_lib.baseboard_fab2(sch_1):xdp_cpu_tck0"
				( attribute "CDS_PHYS_NET_NAME" "XDP_CPU_TCK0"
					( Origin gPackager )
				)
				( objectStatus "XDP_CPU_TCK0" )
			)
			( signal "@baseboard_fab2_lib.baseboard_fab2(sch_1):xdp_cpu_tdi"
				( attribute "CDS_PHYS_NET_NAME" "XDP_CPU_TDI"
					( Origin gPackager )
				)
				( objectStatus "XDP_CPU_TDI" )
			)
			( signal "@baseboard_fab2_lib.baseboard_fab2(sch_1):xdp_cpu_tms"
				( attribute "CDS_PHYS_NET_NAME" "XDP_CPU_TMS"
					( Origin gPackager )
				)
				( objectStatus "XDP_CPU_TMS" )
			)
			( signal "@baseboard_fab2_lib.baseboard_fab2(sch_1):xdp_cpu_trst_n"
				( attribute "CDS_PHYS_NET_NAME" "XDP_CPU_TRST_N"
					( Origin gPackager )
				)
				( objectStatus "XDP_CPU_TRST_N" )
			)
			( signal "@baseboard_fab2_lib.baseboard_fab2(sch_1):clk_100m_cpu0_rc_refclk0_dn"
				( attribute "CDS_PHYS_NET_NAME" "CLK_100M_CPU0_RC_REFCLK0_DN"
					( Origin gPackager )
				)
				( objectStatus "CLK_100M_CPU0_RC_REFCLK0_DN" )
			)
			( signal "@baseboard_fab2_lib.baseboard_fab2(sch_1):clk_100m_cpu0_rc_refclk0_dp"
				( attribute "CDS_PHYS_NET_NAME" "CLK_100M_CPU0_RC_REFCLK0_DP"
					( Origin gPackager )
				)
				( objectStatus "CLK_100M_CPU0_RC_REFCLK0_DP" )
			)
			( signal "@baseboard_fab2_lib.baseboard_fab2(sch_1):clk_322m_osc_cpu0_rc_dn"
				( attribute "CDS_PHYS_NET_NAME" "CLK_322M_OSC_CPU0_RC_DN"
					( Origin gPackager )
				)
				( objectStatus "CLK_322M_OSC_CPU0_RC_DN" )
			)
			( signal "@baseboard_fab2_lib.baseboard_fab2(sch_1):clk_322m_osc_cpu0_rc_dp"
				( attribute "CDS_PHYS_NET_NAME" "CLK_322M_OSC_CPU0_RC_DP"
					( Origin gPackager )
				)
				( objectStatus "CLK_322M_OSC_CPU0_RC_DP" )
			)
			( signal "@baseboard_fab2_lib.baseboard_fab2(sch_1):fm_cpu0_rc_error_n"
				( attribute "CDS_PHYS_NET_NAME" "FM_CPU0_RC_ERROR_N"
					( Origin gPackager )
				)
				( attribute "PHYS_NET_NAME" "FM_CPU0_RC_ERROR_N"
					( Origin gPackager )
				)
				( objectStatus "FM_CPU0_RC_ERROR_N" )
			)
			( signal "@baseboard_fab2_lib.baseboard_fab2(sch_1):h_cpu0_fivr_fault_g"
				( attribute "CDS_PHYS_NET_NAME" "H_CPU0_FIVR_FAULT_G"
					( Origin gPackager )
				)
				( objectStatus "H_CPU0_FIVR_FAULT_G" )
			)
			( signal "@baseboard_fab2_lib.baseboard_fab2(sch_1):p1v8_mcp_cpu0"
				( alias ( signalRef "@baseboard_fab2_lib.baseboard_fab2(sch_1):page22_p1v8_mcp_cpu0") )
				( alias ( signalRef "@baseboard_fab2_lib.baseboard_fab2(sch_1):page38_p1v8_mcp_cpu0") )
				( alias ( signalRef "@baseboard_fab2_lib.baseboard_fab2(sch_1):page113_p1v8_mcp_cpu0") )
				( alias ( signalRef "@baseboard_fab2_lib.baseboard_fab2(sch_1):page194_p1v8_mcp_cpu0") )
				( attribute "VOLTAGE" "+1.8V"
					( Units "uVoltage" "V" 1.000000)
					( Status sAliasFlattened )
					( Origin gFrontEnd )
				)
				( attribute "CDS_PHYS_NET_NAME" "P1V8_MCP_CPU0"
					( Origin gPackager )
				)
				( objectStatus "P1V8_MCP_CPU0" )
			)
			( signal "@baseboard_fab2_lib.baseboard_fab2(sch_1):page22_p1v8_mcp_cpu0"
				( objectFlag fObjectAlias )
				( objectStatus "page22_p1v8_mcp_cpu0" )
			)
			( signal "@baseboard_fab2_lib.baseboard_fab2(sch_1):page38_p1v8_mcp_cpu0"
				( attribute "VOLTAGE" "+1.8V"
					( Units "uVoltage" "V" 1.000000)
					( Origin gFrontEnd )
				)
				( objectFlag fObjectAlias )
				( objectStatus "page38_p1v8_mcp_cpu0" )
			)
			( signal "@baseboard_fab2_lib.baseboard_fab2(sch_1):page113_p1v8_mcp_cpu0"
				( objectFlag fObjectAlias )
				( objectStatus "page113_p1v8_mcp_cpu0" )
			)
			( signal "@baseboard_fab2_lib.baseboard_fab2(sch_1):page194_p1v8_mcp_cpu0"
				( objectFlag fObjectAlias )
				( objectStatus "page194_p1v8_mcp_cpu0" )
			)
			( signal "@baseboard_fab2_lib.baseboard_fab2(sch_1):pd_cpu0_dmimode_override"
				( attribute "CDS_PHYS_NET_NAME" "PD_CPU0_DMIMODE_OVERRIDE"
					( Origin gPackager )
				)
				( objectStatus "PD_CPU0_DMIMODE_OVERRIDE" )
			)
			( signal "@baseboard_fab2_lib.baseboard_fab2(sch_1):pd_cpu0_rsvd_test_1"
				( attribute "CDS_PHYS_NET_NAME" "PD_CPU0_RSVD_TEST_1"
					( Origin gPackager )
				)
				( objectStatus "PD_CPU0_RSVD_TEST_1" )
			)
			( signal "@baseboard_fab2_lib.baseboard_fab2(sch_1):pd_cpu0_rsvd_test_2"
				( attribute "CDS_PHYS_NET_NAME" "PD_CPU0_RSVD_TEST_2"
					( Origin gPackager )
				)
				( objectStatus "PD_CPU0_RSVD_TEST_2" )
			)
			( signal "@baseboard_fab2_lib.baseboard_fab2(sch_1):pvccmcp_cpu0"
				( alias ( signalRef "@baseboard_fab2_lib.baseboard_fab2(sch_1):page22_pvccmcp_cpu0") )
				( alias ( signalRef "@baseboard_fab2_lib.baseboard_fab2(sch_1):page29_pvccmcp_cpu0") )
				( alias ( signalRef "@baseboard_fab2_lib.baseboard_fab2(sch_1):page36_pvccmcp_cpu0") )
				( alias ( signalRef "@baseboard_fab2_lib.baseboard_fab2(sch_1):page38_pvccmcp_cpu0") )
				( alias ( signalRef "@baseboard_fab2_lib.baseboard_fab2(sch_1):page39_pvccmcp_cpu0") )
				( alias ( signalRef "@baseboard_fab2_lib.baseboard_fab2(sch_1):page42_pvccmcp_cpu0") )
				( alias ( signalRef "@baseboard_fab2_lib.baseboard_fab2(sch_1):page194_pvccmcp_cpu0") )
				( attribute "VOLTAGE" "1.2V"
					( Units "uVoltage" "V" 1.000000)
					( Status sAliasFlattened )
					( Origin gFrontEnd )
				)
				( attribute "CDS_PHYS_NET_NAME" "PVCCMCP_CPU0"
					( Origin gPackager )
				)
				( objectStatus "PVCCMCP_CPU0" )
			)
			( signal "@baseboard_fab2_lib.baseboard_fab2(sch_1):page22_pvccmcp_cpu0"
				( objectFlag fObjectAlias )
				( objectStatus "page22_pvccmcp_cpu0" )
			)
			( signal "@baseboard_fab2_lib.baseboard_fab2(sch_1):page29_pvccmcp_cpu0"
				( objectFlag fObjectAlias )
				( objectStatus "page29_pvccmcp_cpu0" )
			)
			( signal "@baseboard_fab2_lib.baseboard_fab2(sch_1):page36_pvccmcp_cpu0"
				( objectFlag fObjectAlias )
				( objectStatus "page36_pvccmcp_cpu0" )
			)
			( signal "@baseboard_fab2_lib.baseboard_fab2(sch_1):page38_pvccmcp_cpu0"
				( objectFlag fObjectAlias )
				( objectStatus "page38_pvccmcp_cpu0" )
			)
			( signal "@baseboard_fab2_lib.baseboard_fab2(sch_1):page39_pvccmcp_cpu0"
				( objectFlag fObjectAlias )
				( objectStatus "page39_pvccmcp_cpu0" )
			)
			( signal "@baseboard_fab2_lib.baseboard_fab2(sch_1):page42_pvccmcp_cpu0"
				( objectFlag fObjectAlias )
				( objectStatus "page42_pvccmcp_cpu0" )
			)
			( signal "@baseboard_fab2_lib.baseboard_fab2(sch_1):page194_pvccmcp_cpu0"
				( attribute "VOLTAGE" "1.2V"
					( Units "uVoltage" "V" 1.000000)
					( Origin gFrontEnd )
				)
				( objectFlag fObjectAlias )
				( objectStatus "page194_pvccmcp_cpu0" )
			)
			( signal "@baseboard_fab2_lib.baseboard_fab2(sch_1):tp_cpu0_rsvd_194"
				( attribute "CDS_PHYS_NET_NAME" "TP_CPU0_RSVD_194"
					( Origin gPackager )
				)
				( objectStatus "TP_CPU0_RSVD_194" )
			)
			( signal "@baseboard_fab2_lib.baseboard_fab2(sch_1):tp_cpu0_rsvd_198"
				( attribute "CDS_PHYS_NET_NAME" "TP_CPU0_RSVD_198"
					( Origin gPackager )
				)
				( objectStatus "TP_CPU0_RSVD_198" )
			)
			( signal "@baseboard_fab2_lib.baseboard_fab2(sch_1):tp_cpu0_rsvd_199"
				( attribute "CDS_PHYS_NET_NAME" "TP_CPU0_RSVD_199"
					( Origin gPackager )
				)
				( objectStatus "TP_CPU0_RSVD_199" )
			)
			( signal "@baseboard_fab2_lib.baseboard_fab2(sch_1):tp_cpu0_rsvd_204"
				( attribute "CDS_PHYS_NET_NAME" "TP_CPU0_RSVD_204"
					( Origin gPackager )
				)
				( objectStatus "TP_CPU0_RSVD_204" )
			)
			( signal "@baseboard_fab2_lib.baseboard_fab2(sch_1):tp_cpu0_rsvd_205"
				( attribute "CDS_PHYS_NET_NAME" "TP_CPU0_RSVD_205"
					( Origin gPackager )
				)
				( objectStatus "TP_CPU0_RSVD_205" )
			)
			( signal "@baseboard_fab2_lib.baseboard_fab2(sch_1):tp_cpu0_rsvd_208"
				( attribute "CDS_PHYS_NET_NAME" "TP_CPU0_RSVD_208"
					( Origin gPackager )
				)
				( objectStatus "TP_CPU0_RSVD_208" )
			)
			( signal "@baseboard_fab2_lib.baseboard_fab2(sch_1):tp_cpu0_rsvd_210"
				( attribute "CDS_PHYS_NET_NAME" "TP_CPU0_RSVD_210"
					( Origin gPackager )
				)
				( objectStatus "TP_CPU0_RSVD_210" )
			)
			( signal "@baseboard_fab2_lib.baseboard_fab2(sch_1):tp_cpu0_rsvd_211"
				( attribute "CDS_PHYS_NET_NAME" "TP_CPU0_RSVD_211"
					( Origin gPackager )
				)
				( objectStatus "TP_CPU0_RSVD_211" )
			)
			( signal "@baseboard_fab2_lib.baseboard_fab2(sch_1):tp_cpu0_rsvd_212"
				( attribute "CDS_PHYS_NET_NAME" "TP_CPU0_RSVD_212"
					( Origin gPackager )
				)
				( objectStatus "TP_CPU0_RSVD_212" )
			)
			( signal "@baseboard_fab2_lib.baseboard_fab2(sch_1):tp_cpu0_rsvd_214"
				( attribute "CDS_PHYS_NET_NAME" "TP_CPU0_RSVD_214"
					( Origin gPackager )
				)
				( objectStatus "TP_CPU0_RSVD_214" )
			)
			( signal "@baseboard_fab2_lib.baseboard_fab2(sch_1):tp_cpu0_rsvd_216"
				( attribute "CDS_PHYS_NET_NAME" "TP_CPU0_RSVD_216"
					( Origin gPackager )
				)
				( objectStatus "TP_CPU0_RSVD_216" )
			)
			( signal "@baseboard_fab2_lib.baseboard_fab2(sch_1):tp_cpu0_rsvd_217"
				( attribute "CDS_PHYS_NET_NAME" "TP_CPU0_RSVD_217"
					( Origin gPackager )
				)
				( objectStatus "TP_CPU0_RSVD_217" )
			)
			( signal "@baseboard_fab2_lib.baseboard_fab2(sch_1):tp_cpu0_rsvd_218"
				( attribute "CDS_PHYS_NET_NAME" "TP_CPU0_RSVD_218"
					( Origin gPackager )
				)
				( objectStatus "TP_CPU0_RSVD_218" )
			)
			( signal "@baseboard_fab2_lib.baseboard_fab2(sch_1):tp_cpu0_rsvd_219"
				( attribute "CDS_PHYS_NET_NAME" "TP_CPU0_RSVD_219"
					( Origin gPackager )
				)
				( objectStatus "TP_CPU0_RSVD_219" )
			)
			( signal "@baseboard_fab2_lib.baseboard_fab2(sch_1):tp_cpu0_rsvd_222"
				( attribute "CDS_PHYS_NET_NAME" "TP_CPU0_RSVD_222"
					( Origin gPackager )
				)
				( objectStatus "TP_CPU0_RSVD_222" )
			)
			( signal "@baseboard_fab2_lib.baseboard_fab2(sch_1):tp_cpu0_rsvd_223"
				( attribute "CDS_PHYS_NET_NAME" "TP_CPU0_RSVD_223"
					( Origin gPackager )
				)
				( objectStatus "TP_CPU0_RSVD_223" )
			)
			( signal "@baseboard_fab2_lib.baseboard_fab2(sch_1):tp_cpu0_rsvd_224"
				( attribute "CDS_PHYS_NET_NAME" "TP_CPU0_RSVD_224"
					( Origin gPackager )
				)
				( objectStatus "TP_CPU0_RSVD_224" )
			)
			( signal "@baseboard_fab2_lib.baseboard_fab2(sch_1):tp_cpu0_rsvd_225"
				( attribute "CDS_PHYS_NET_NAME" "TP_CPU0_RSVD_225"
					( Origin gPackager )
				)
				( objectStatus "TP_CPU0_RSVD_225" )
			)
			( signal "@baseboard_fab2_lib.baseboard_fab2(sch_1):tp_cpu0_rsvd_226"
				( attribute "CDS_PHYS_NET_NAME" "TP_CPU0_RSVD_226"
					( Origin gPackager )
				)
				( objectStatus "TP_CPU0_RSVD_226" )
			)
			( signal "@baseboard_fab2_lib.baseboard_fab2(sch_1):tp_cpu0_rsvd_227"
				( attribute "CDS_PHYS_NET_NAME" "TP_CPU0_RSVD_227"
					( Origin gPackager )
				)
				( objectStatus "TP_CPU0_RSVD_227" )
			)
			( signal "@baseboard_fab2_lib.baseboard_fab2(sch_1):tp_cpu0_rsvd_228"
				( attribute "CDS_PHYS_NET_NAME" "TP_CPU0_RSVD_228"
					( Origin gPackager )
				)
				( objectStatus "TP_CPU0_RSVD_228" )
			)
			( signal "@baseboard_fab2_lib.baseboard_fab2(sch_1):tp_cpu0_rsvd_229"
				( attribute "CDS_PHYS_NET_NAME" "TP_CPU0_RSVD_229"
					( Origin gPackager )
				)
				( objectStatus "TP_CPU0_RSVD_229" )
			)
			( signal "@baseboard_fab2_lib.baseboard_fab2(sch_1):tp_cpu0_rsvd_230"
				( attribute "CDS_PHYS_NET_NAME" "TP_CPU0_RSVD_230"
					( Origin gPackager )
				)
				( objectStatus "TP_CPU0_RSVD_230" )
			)
			( signal "@baseboard_fab2_lib.baseboard_fab2(sch_1):tp_cpu0_rsvd_231"
				( attribute "CDS_PHYS_NET_NAME" "TP_CPU0_RSVD_231"
					( Origin gPackager )
				)
				( objectStatus "TP_CPU0_RSVD_231" )
			)
			( signal "@baseboard_fab2_lib.baseboard_fab2(sch_1):tp_cpu0_rsvd_232"
				( attribute "CDS_PHYS_NET_NAME" "TP_CPU0_RSVD_232"
					( Origin gPackager )
				)
				( objectStatus "TP_CPU0_RSVD_232" )
			)
			( signal "@baseboard_fab2_lib.baseboard_fab2(sch_1):tp_cpu0_rsvd_233"
				( attribute "CDS_PHYS_NET_NAME" "TP_CPU0_RSVD_233"
					( Origin gPackager )
				)
				( objectStatus "TP_CPU0_RSVD_233" )
			)
			( signal "@baseboard_fab2_lib.baseboard_fab2(sch_1):tp_cpu0_rsvd_234"
				( attribute "CDS_PHYS_NET_NAME" "TP_CPU0_RSVD_234"
					( Origin gPackager )
				)
				( objectStatus "TP_CPU0_RSVD_234" )
			)
			( signal "@baseboard_fab2_lib.baseboard_fab2(sch_1):tp_cpu0_rsvd_235"
				( attribute "CDS_PHYS_NET_NAME" "TP_CPU0_RSVD_235"
					( Origin gPackager )
				)
				( objectStatus "TP_CPU0_RSVD_235" )
			)
			( signal "@baseboard_fab2_lib.baseboard_fab2(sch_1):tp_cpu0_rsvd_236"
				( attribute "CDS_PHYS_NET_NAME" "TP_CPU0_RSVD_236"
					( Origin gPackager )
				)
				( objectStatus "TP_CPU0_RSVD_236" )
			)
			( signal "@baseboard_fab2_lib.baseboard_fab2(sch_1):tp_cpu0_rsvd_237"
				( attribute "CDS_PHYS_NET_NAME" "TP_CPU0_RSVD_237"
					( Origin gPackager )
				)
				( objectStatus "TP_CPU0_RSVD_237" )
			)
			( signal "@baseboard_fab2_lib.baseboard_fab2(sch_1):tp_cpu0_rsvd_238"
				( attribute "CDS_PHYS_NET_NAME" "TP_CPU0_RSVD_238"
					( Origin gPackager )
				)
				( objectStatus "TP_CPU0_RSVD_238" )
			)
			( signal "@baseboard_fab2_lib.baseboard_fab2(sch_1):tp_cpu0_rsvd_239"
				( attribute "CDS_PHYS_NET_NAME" "TP_CPU0_RSVD_239"
					( Origin gPackager )
				)
				( objectStatus "TP_CPU0_RSVD_239" )
			)
			( signal "@baseboard_fab2_lib.baseboard_fab2(sch_1):tp_cpu0_rsvd_240"
				( attribute "CDS_PHYS_NET_NAME" "TP_CPU0_RSVD_240"
					( Origin gPackager )
				)
				( objectStatus "TP_CPU0_RSVD_240" )
			)
			( signal "@baseboard_fab2_lib.baseboard_fab2(sch_1):tp_cpu0_rsvd_241"
				( attribute "CDS_PHYS_NET_NAME" "TP_CPU0_RSVD_241"
					( Origin gPackager )
				)
				( objectStatus "TP_CPU0_RSVD_241" )
			)
			( signal "@baseboard_fab2_lib.baseboard_fab2(sch_1):tp_cpu0_rsvd_242"
				( attribute "CDS_PHYS_NET_NAME" "TP_CPU0_RSVD_242"
					( Origin gPackager )
				)
				( objectStatus "TP_CPU0_RSVD_242" )
			)
			( signal "@baseboard_fab2_lib.baseboard_fab2(sch_1):tp_cpu0_rsvd_243"
				( attribute "CDS_PHYS_NET_NAME" "TP_CPU0_RSVD_243"
					( Origin gPackager )
				)
				( objectStatus "TP_CPU0_RSVD_243" )
			)
			( signal "@baseboard_fab2_lib.baseboard_fab2(sch_1):tp_cpu0_rsvd_244"
				( attribute "CDS_PHYS_NET_NAME" "TP_CPU0_RSVD_244"
					( Origin gPackager )
				)
				( objectStatus "TP_CPU0_RSVD_244" )
			)
			( signal "@baseboard_fab2_lib.baseboard_fab2(sch_1):tp_cpu0_rsvd_245"
				( attribute "CDS_PHYS_NET_NAME" "TP_CPU0_RSVD_245"
					( Origin gPackager )
				)
				( objectStatus "TP_CPU0_RSVD_245" )
			)
			( signal "@baseboard_fab2_lib.baseboard_fab2(sch_1):tp_cpu0_rsvd_246"
				( attribute "CDS_PHYS_NET_NAME" "TP_CPU0_RSVD_246"
					( Origin gPackager )
				)
				( objectStatus "TP_CPU0_RSVD_246" )
			)
			( signal "@baseboard_fab2_lib.baseboard_fab2(sch_1):tp_cpu0_rsvd_247"
				( attribute "CDS_PHYS_NET_NAME" "TP_CPU0_RSVD_247"
					( Origin gPackager )
				)
				( objectStatus "TP_CPU0_RSVD_247" )
			)
			( signal "@baseboard_fab2_lib.baseboard_fab2(sch_1):tp_cpu0_rsvd_248"
				( attribute "CDS_PHYS_NET_NAME" "TP_CPU0_RSVD_248"
					( Origin gPackager )
				)
				( objectStatus "TP_CPU0_RSVD_248" )
			)
			( signal "@baseboard_fab2_lib.baseboard_fab2(sch_1):tp_cpu0_rsvd_249"
				( attribute "CDS_PHYS_NET_NAME" "TP_CPU0_RSVD_249"
					( Origin gPackager )
				)
				( objectStatus "TP_CPU0_RSVD_249" )
			)
			( signal "@baseboard_fab2_lib.baseboard_fab2(sch_1):tp_cpu0_rsvd_250"
				( attribute "CDS_PHYS_NET_NAME" "TP_CPU0_RSVD_250"
					( Origin gPackager )
				)
				( objectStatus "TP_CPU0_RSVD_250" )
			)
			( signal "@baseboard_fab2_lib.baseboard_fab2(sch_1):tp_cpu0_rsvd_251"
				( attribute "CDS_PHYS_NET_NAME" "TP_CPU0_RSVD_251"
					( Origin gPackager )
				)
				( objectStatus "TP_CPU0_RSVD_251" )
			)
			( signal "@baseboard_fab2_lib.baseboard_fab2(sch_1):tp_cpu0_rsvd_252"
				( attribute "CDS_PHYS_NET_NAME" "TP_CPU0_RSVD_252"
					( Origin gPackager )
				)
				( objectStatus "TP_CPU0_RSVD_252" )
			)
			( signal "@baseboard_fab2_lib.baseboard_fab2(sch_1):tp_cpu0_rsvd_253"
				( attribute "CDS_PHYS_NET_NAME" "TP_CPU0_RSVD_253"
					( Origin gPackager )
				)
				( objectStatus "TP_CPU0_RSVD_253" )
			)
			( signal "@baseboard_fab2_lib.baseboard_fab2(sch_1):tp_cpu0_rsvd_254"
				( attribute "CDS_PHYS_NET_NAME" "TP_CPU0_RSVD_254"
					( Origin gPackager )
				)
				( objectStatus "TP_CPU0_RSVD_254" )
			)
			( signal "@baseboard_fab2_lib.baseboard_fab2(sch_1):tp_cpu0_rsvd_256"
				( attribute "CDS_PHYS_NET_NAME" "TP_CPU0_RSVD_256"
					( Origin gPackager )
				)
				( objectStatus "TP_CPU0_RSVD_256" )
			)
			( signal "@baseboard_fab2_lib.baseboard_fab2(sch_1):tp_cpu0_rsvd_258"
				( attribute "CDS_PHYS_NET_NAME" "TP_CPU0_RSVD_258"
					( Origin gPackager )
				)
				( objectStatus "TP_CPU0_RSVD_258" )
			)
			( signal "@baseboard_fab2_lib.baseboard_fab2(sch_1):tp_cpu0_rsvd_259"
				( attribute "CDS_PHYS_NET_NAME" "TP_CPU0_RSVD_259"
					( Origin gPackager )
				)
				( objectStatus "TP_CPU0_RSVD_259" )
			)
			( signal "@baseboard_fab2_lib.baseboard_fab2(sch_1):tp_cpu0_rsvd_260"
				( attribute "CDS_PHYS_NET_NAME" "TP_CPU0_RSVD_260"
					( Origin gPackager )
				)
				( objectStatus "TP_CPU0_RSVD_260" )
			)
			( signal "@baseboard_fab2_lib.baseboard_fab2(sch_1):tp_cpu0_rsvd_261"
				( attribute "CDS_PHYS_NET_NAME" "TP_CPU0_RSVD_261"
					( Origin gPackager )
				)
				( objectStatus "TP_CPU0_RSVD_261" )
			)
			( signal "@baseboard_fab2_lib.baseboard_fab2(sch_1):tp_cpu0_rsvd_262"
				( attribute "CDS_PHYS_NET_NAME" "TP_CPU0_RSVD_262"
					( Origin gPackager )
				)
				( objectStatus "TP_CPU0_RSVD_262" )
			)
			( signal "@baseboard_fab2_lib.baseboard_fab2(sch_1):tp_cpu0_rsvd_263"
				( attribute "CDS_PHYS_NET_NAME" "TP_CPU0_RSVD_263"
					( Origin gPackager )
				)
				( objectStatus "TP_CPU0_RSVD_263" )
			)
			( signal "@baseboard_fab2_lib.baseboard_fab2(sch_1):tp_cpu0_rsvd_264"
				( attribute "CDS_PHYS_NET_NAME" "TP_CPU0_RSVD_264"
					( Origin gPackager )
				)
				( objectStatus "TP_CPU0_RSVD_264" )
			)
			( signal "@baseboard_fab2_lib.baseboard_fab2(sch_1):tp_cpu0_rsvd_265"
				( attribute "CDS_PHYS_NET_NAME" "TP_CPU0_RSVD_265"
					( Origin gPackager )
				)
				( objectStatus "TP_CPU0_RSVD_265" )
			)
			( signal "@baseboard_fab2_lib.baseboard_fab2(sch_1):tp_cpu0_rsvd_266"
				( attribute "CDS_PHYS_NET_NAME" "TP_CPU0_RSVD_266"
					( Origin gPackager )
				)
				( objectStatus "TP_CPU0_RSVD_266" )
			)
			( signal "@baseboard_fab2_lib.baseboard_fab2(sch_1):tp_cpu0_rsvd_267"
				( attribute "CDS_PHYS_NET_NAME" "TP_CPU0_RSVD_267"
					( Origin gPackager )
				)
				( objectStatus "TP_CPU0_RSVD_267" )
			)
			( signal "@baseboard_fab2_lib.baseboard_fab2(sch_1):tp_cpu0_rsvd_268"
				( attribute "CDS_PHYS_NET_NAME" "TP_CPU0_RSVD_268"
					( Origin gPackager )
				)
				( objectStatus "TP_CPU0_RSVD_268" )
			)
			( signal "@baseboard_fab2_lib.baseboard_fab2(sch_1):tp_cpu0_rsvd_269"
				( attribute "CDS_PHYS_NET_NAME" "TP_CPU0_RSVD_269"
					( Origin gPackager )
				)
				( objectStatus "TP_CPU0_RSVD_269" )
			)
			( signal "@baseboard_fab2_lib.baseboard_fab2(sch_1):tp_cpu0_rsvd_270"
				( attribute "CDS_PHYS_NET_NAME" "TP_CPU0_RSVD_270"
					( Origin gPackager )
				)
				( objectStatus "TP_CPU0_RSVD_270" )
			)
			( signal "@baseboard_fab2_lib.baseboard_fab2(sch_1):tp_cpu0_rsvd_271"
				( attribute "CDS_PHYS_NET_NAME" "TP_CPU0_RSVD_271"
					( Origin gPackager )
				)
				( objectStatus "TP_CPU0_RSVD_271" )
			)
			( signal "@baseboard_fab2_lib.baseboard_fab2(sch_1):tp_cpu0_rsvd_272"
				( attribute "CDS_PHYS_NET_NAME" "TP_CPU0_RSVD_272"
					( Origin gPackager )
				)
				( objectStatus "TP_CPU0_RSVD_272" )
			)
			( signal "@baseboard_fab2_lib.baseboard_fab2(sch_1):tp_cpu0_rsvd_273"
				( attribute "CDS_PHYS_NET_NAME" "TP_CPU0_RSVD_273"
					( Origin gPackager )
				)
				( objectStatus "TP_CPU0_RSVD_273" )
			)
			( signal "@baseboard_fab2_lib.baseboard_fab2(sch_1):tp_cpu0_rsvd_274"
				( attribute "CDS_PHYS_NET_NAME" "TP_CPU0_RSVD_274"
					( Origin gPackager )
				)
				( objectStatus "TP_CPU0_RSVD_274" )
			)
			( signal "@baseboard_fab2_lib.baseboard_fab2(sch_1):tp_cpu0_rsvd_275"
				( attribute "CDS_PHYS_NET_NAME" "TP_CPU0_RSVD_275"
					( Origin gPackager )
				)
				( objectStatus "TP_CPU0_RSVD_275" )
			)
			( signal "@baseboard_fab2_lib.baseboard_fab2(sch_1):tp_cpu0_rsvd_276"
				( attribute "CDS_PHYS_NET_NAME" "TP_CPU0_RSVD_276"
					( Origin gPackager )
				)
				( objectStatus "TP_CPU0_RSVD_276" )
			)
			( signal "@baseboard_fab2_lib.baseboard_fab2(sch_1):tp_cpu0_rsvd_277"
				( attribute "CDS_PHYS_NET_NAME" "TP_CPU0_RSVD_277"
					( Origin gPackager )
				)
				( objectStatus "TP_CPU0_RSVD_277" )
			)
			( signal "@baseboard_fab2_lib.baseboard_fab2(sch_1):tp_cpu0_rsvd_278"
				( attribute "CDS_PHYS_NET_NAME" "TP_CPU0_RSVD_278"
					( Origin gPackager )
				)
				( objectStatus "TP_CPU0_RSVD_278" )
			)
			( signal "@baseboard_fab2_lib.baseboard_fab2(sch_1):tp_cpu0_rsvd_279"
				( attribute "CDS_PHYS_NET_NAME" "TP_CPU0_RSVD_279"
					( Origin gPackager )
				)
				( objectStatus "TP_CPU0_RSVD_279" )
			)
			( signal "@baseboard_fab2_lib.baseboard_fab2(sch_1):tp_cpu0_rsvd_280"
				( attribute "CDS_PHYS_NET_NAME" "TP_CPU0_RSVD_280"
					( Origin gPackager )
				)
				( objectStatus "TP_CPU0_RSVD_280" )
			)
			( signal "@baseboard_fab2_lib.baseboard_fab2(sch_1):tp_cpu0_rsvd_281"
				( attribute "CDS_PHYS_NET_NAME" "TP_CPU0_RSVD_281"
					( Origin gPackager )
				)
				( objectStatus "TP_CPU0_RSVD_281" )
			)
			( signal "@baseboard_fab2_lib.baseboard_fab2(sch_1):tp_cpu0_rsvd_282"
				( attribute "CDS_PHYS_NET_NAME" "TP_CPU0_RSVD_282"
					( Origin gPackager )
				)
				( objectStatus "TP_CPU0_RSVD_282" )
			)
			( signal "@baseboard_fab2_lib.baseboard_fab2(sch_1):tp_cpu0_rsvd_283"
				( attribute "CDS_PHYS_NET_NAME" "TP_CPU0_RSVD_283"
					( Origin gPackager )
				)
				( objectStatus "TP_CPU0_RSVD_283" )
			)
			( signal "@baseboard_fab2_lib.baseboard_fab2(sch_1):tp_cpu0_rsvd_284"
				( attribute "CDS_PHYS_NET_NAME" "TP_CPU0_RSVD_284"
					( Origin gPackager )
				)
				( objectStatus "TP_CPU0_RSVD_284" )
			)
			( signal "@baseboard_fab2_lib.baseboard_fab2(sch_1):tp_cpu0_rsvd_285"
				( attribute "CDS_PHYS_NET_NAME" "TP_CPU0_RSVD_285"
					( Origin gPackager )
				)
				( objectStatus "TP_CPU0_RSVD_285" )
			)
			( signal "@baseboard_fab2_lib.baseboard_fab2(sch_1):tp_cpu0_rsvd_286"
				( attribute "CDS_PHYS_NET_NAME" "TP_CPU0_RSVD_286"
					( Origin gPackager )
				)
				( objectStatus "TP_CPU0_RSVD_286" )
			)
			( signal "@baseboard_fab2_lib.baseboard_fab2(sch_1):tp_cpu0_rsvd_287"
				( attribute "CDS_PHYS_NET_NAME" "TP_CPU0_RSVD_287"
					( Origin gPackager )
				)
				( objectStatus "TP_CPU0_RSVD_287" )
			)
			( signal "@baseboard_fab2_lib.baseboard_fab2(sch_1):tp_cpu0_rsvd_288"
				( attribute "CDS_PHYS_NET_NAME" "TP_CPU0_RSVD_288"
					( Origin gPackager )
				)
				( objectStatus "TP_CPU0_RSVD_288" )
			)
			( signal "@baseboard_fab2_lib.baseboard_fab2(sch_1):tp_cpu0_rsvd_289"
				( attribute "CDS_PHYS_NET_NAME" "TP_CPU0_RSVD_289"
					( Origin gPackager )
				)
				( objectStatus "TP_CPU0_RSVD_289" )
			)
			( signal "@baseboard_fab2_lib.baseboard_fab2(sch_1):tp_cpu0_rsvd_290"
				( attribute "CDS_PHYS_NET_NAME" "TP_CPU0_RSVD_290"
					( Origin gPackager )
				)
				( objectStatus "TP_CPU0_RSVD_290" )
			)
			( signal "@baseboard_fab2_lib.baseboard_fab2(sch_1):tp_cpu0_rsvd_291"
				( attribute "CDS_PHYS_NET_NAME" "TP_CPU0_RSVD_291"
					( Origin gPackager )
				)
				( objectStatus "TP_CPU0_RSVD_291" )
			)
			( signal "@baseboard_fab2_lib.baseboard_fab2(sch_1):tp_cpu0_rsvd_292"
				( attribute "CDS_PHYS_NET_NAME" "TP_CPU0_RSVD_292"
					( Origin gPackager )
				)
				( objectStatus "TP_CPU0_RSVD_292" )
			)
			( signal "@baseboard_fab2_lib.baseboard_fab2(sch_1):tp_cpu0_rsvd_293"
				( attribute "CDS_PHYS_NET_NAME" "TP_CPU0_RSVD_293"
					( Origin gPackager )
				)
				( objectStatus "TP_CPU0_RSVD_293" )
			)
			( signal "@baseboard_fab2_lib.baseboard_fab2(sch_1):tp_cpu0_rsvd_298"
				( attribute "CDS_PHYS_NET_NAME" "TP_CPU0_RSVD_298"
					( Origin gPackager )
				)
				( objectStatus "TP_CPU0_RSVD_298" )
			)
			( signal "@baseboard_fab2_lib.baseboard_fab2(sch_1):tp_cpu0_rsvd_299"
				( attribute "CDS_PHYS_NET_NAME" "TP_CPU0_RSVD_299"
					( Origin gPackager )
				)
				( objectStatus "TP_CPU0_RSVD_299" )
			)
			( signal "@baseboard_fab2_lib.baseboard_fab2(sch_1):tp_cpu0_rsvd_300"
				( attribute "CDS_PHYS_NET_NAME" "TP_CPU0_RSVD_300"
					( Origin gPackager )
				)
				( objectStatus "TP_CPU0_RSVD_300" )
			)
			( signal "@baseboard_fab2_lib.baseboard_fab2(sch_1):tp_cpu0_rsvd_303"
				( attribute "CDS_PHYS_NET_NAME" "TP_CPU0_RSVD_303"
					( Origin gPackager )
				)
				( objectStatus "TP_CPU0_RSVD_303" )
			)
			( signal "@baseboard_fab2_lib.baseboard_fab2(sch_1):tp_cpu0_rsvd_304"
				( attribute "CDS_PHYS_NET_NAME" "TP_CPU0_RSVD_304"
					( Origin gPackager )
				)
				( objectStatus "TP_CPU0_RSVD_304" )
			)
			( signal "@baseboard_fab2_lib.baseboard_fab2(sch_1):tp_cpu0_rsvd_test_11"
				( attribute "CDS_PHYS_NET_NAME" "TP_CPU0_RSVD_TEST_11"
					( Origin gPackager )
				)
				( objectStatus "TP_CPU0_RSVD_TEST_11" )
			)
			( signal "@baseboard_fab2_lib.baseboard_fab2(sch_1):tp_cpu0_rsvd_test_3"
				( attribute "CDS_PHYS_NET_NAME" "TP_CPU0_RSVD_TEST_3"
					( Origin gPackager )
				)
				( objectStatus "TP_CPU0_RSVD_TEST_3" )
			)
			( signal "@baseboard_fab2_lib.baseboard_fab2(sch_1):tp_cpu0_rsvd_test_4"
				( attribute "CDS_PHYS_NET_NAME" "TP_CPU0_RSVD_TEST_4"
					( Origin gPackager )
				)
				( objectStatus "TP_CPU0_RSVD_TEST_4" )
			)
			( signal "@baseboard_fab2_lib.baseboard_fab2(sch_1):tp_cpu0_rsvd_test_5"
				( attribute "CDS_PHYS_NET_NAME" "TP_CPU0_RSVD_TEST_5"
					( Origin gPackager )
				)
				( objectStatus "TP_CPU0_RSVD_TEST_5" )
			)
			( signal "@baseboard_fab2_lib.baseboard_fab2(sch_1):vsense_p1v8mcp_cpu0_skt_vrtn"
				( attribute "CDS_PHYS_NET_NAME" "VSENSE_P1V8MCP_CPU0_SKT_VRTN"
					( Origin gPackager )
				)
				( objectStatus "VSENSE_P1V8MCP_CPU0_SKT_VRTN" )
			)
			( signal "@baseboard_fab2_lib.baseboard_fab2(sch_1):vsense_p1v8mcp_cpu0_skt_vsen"
				( attribute "CDS_PHYS_NET_NAME" "VSENSE_P1V8MCP_CPU0_SKT_VSEN"
					( Origin gPackager )
				)
				( objectStatus "VSENSE_P1V8MCP_CPU0_SKT_VSEN" )
			)
			( signal "@baseboard_fab2_lib.baseboard_fab2(sch_1):xdp_cpu_pwr_debug_n"
				( attribute "CDS_PHYS_NET_NAME" "XDP_CPU_PWR_DEBUG_N"
					( Origin gPackager )
				)
				( objectStatus "XDP_CPU_PWR_DEBUG_N" )
			)
			( signal "@baseboard_fab2_lib.baseboard_fab2(sch_1):xdp_present_n"
				( attribute "CDS_PHYS_NET_NAME" "XDP_PRESENT_N"
					( Origin gPackager )
				)
				( objectStatus "XDP_PRESENT_N" )
			)
			( signal "@baseboard_fab2_lib.baseboard_fab2(sch_1):m_a_act_n"
				( attribute "CDS_PHYS_NET_NAME" "M_A_ACT_N"
					( Origin gPackager )
				)
				( objectStatus "M_A_ACT_N" )
			)
			( signal "@baseboard_fab2_lib.baseboard_fab2(sch_1):m_a_alert_n"
				( attribute "CDS_PHYS_NET_NAME" "M_A_ALERT_N"
					( Origin gPackager )
				)
				( objectStatus "M_A_ALERT_N" )
			)
			( signal "@baseboard_fab2_lib.baseboard_fab2(sch_1):m_a_ba(0)"
				( attribute "CDS_PHYS_NET_NAME" "M_A_BA<0>"
					( Origin gPackager )
				)
				( attribute "PNN" "M_A_BA<0>"
					( Origin gPackager )
				)
				( objectStatus "M_A_BA<0>" )
			)
			( signal "@baseboard_fab2_lib.baseboard_fab2(sch_1):m_a_ba(1)"
				( attribute "CDS_PHYS_NET_NAME" "M_A_BA<1>"
					( Origin gPackager )
				)
				( attribute "PNN" "M_A_BA<1>"
					( Origin gPackager )
				)
				( objectStatus "M_A_BA<1>" )
			)
			( signal "@baseboard_fab2_lib.baseboard_fab2(sch_1):m_a_bg(0)"
				( attribute "CDS_PHYS_NET_NAME" "M_A_BG<0>"
					( Origin gPackager )
				)
				( attribute "PNN" "M_A_BG<0>"
					( Origin gPackager )
				)
				( objectStatus "M_A_BG<0>" )
			)
			( signal "@baseboard_fab2_lib.baseboard_fab2(sch_1):m_a_bg(1)"
				( attribute "CDS_PHYS_NET_NAME" "M_A_BG<1>"
					( Origin gPackager )
				)
				( attribute "PNN" "M_A_BG<1>"
					( Origin gPackager )
				)
				( objectStatus "M_A_BG<1>" )
			)
			( signal "@baseboard_fab2_lib.baseboard_fab2(sch_1):m_a_c(2)"
				( attribute "CDS_PHYS_NET_NAME" "M_A_C<2>"
					( Origin gPackager )
				)
				( attribute "PNN" "M_A_C<2>"
					( Origin gPackager )
				)
				( objectStatus "M_A_C<2>" )
			)
			( signal "@baseboard_fab2_lib.baseboard_fab2(sch_1):m_a_cke(0)"
				( attribute "CDS_PHYS_NET_NAME" "M_A_CKE<0>"
					( Origin gPackager )
				)
				( attribute "PNN" "M_A_CKE<0>"
					( Origin gPackager )
				)
				( objectStatus "M_A_CKE<0>" )
			)
			( signal "@baseboard_fab2_lib.baseboard_fab2(sch_1):m_a_cke(1)"
				( attribute "CDS_PHYS_NET_NAME" "M_A_CKE<1>"
					( Origin gPackager )
				)
				( attribute "PNN" "M_A_CKE<1>"
					( Origin gPackager )
				)
				( objectStatus "M_A_CKE<1>" )
			)
			( signal "@baseboard_fab2_lib.baseboard_fab2(sch_1):m_a_cke(2)"
				( attribute "CDS_PHYS_NET_NAME" "M_A_CKE<2>"
					( Origin gPackager )
				)
				( attribute "PNN" "M_A_CKE<2>"
					( Origin gPackager )
				)
				( objectStatus "M_A_CKE<2>" )
			)
			( signal "@baseboard_fab2_lib.baseboard_fab2(sch_1):m_a_cke(3)"
				( attribute "CDS_PHYS_NET_NAME" "M_A_CKE<3>"
					( Origin gPackager )
				)
				( attribute "PNN" "M_A_CKE<3>"
					( Origin gPackager )
				)
				( objectStatus "M_A_CKE<3>" )
			)
			( signal "@baseboard_fab2_lib.baseboard_fab2(sch_1):m_a_clk_dn(0)"
				( attribute "CDS_PHYS_NET_NAME" "M_A_CLK_DN<0>"
					( Origin gPackager )
				)
				( attribute "PNN" "M_A_CLK_DN<0>"
					( Origin gPackager )
				)
				( objectStatus "M_A_CLK_DN<0>" )
			)
			( signal "@baseboard_fab2_lib.baseboard_fab2(sch_1):m_a_clk_dn(1)"
				( attribute "CDS_PHYS_NET_NAME" "M_A_CLK_DN<1>"
					( Origin gPackager )
				)
				( attribute "PNN" "M_A_CLK_DN<1>"
					( Origin gPackager )
				)
				( objectStatus "M_A_CLK_DN<1>" )
			)
			( signal "@baseboard_fab2_lib.baseboard_fab2(sch_1):m_a_clk_dn(2)"
				( attribute "CDS_PHYS_NET_NAME" "M_A_CLK_DN<2>"
					( Origin gPackager )
				)
				( attribute "PNN" "M_A_CLK_DN<2>"
					( Origin gPackager )
				)
				( objectStatus "M_A_CLK_DN<2>" )
			)
			( signal "@baseboard_fab2_lib.baseboard_fab2(sch_1):m_a_clk_dn(3)"
				( attribute "CDS_PHYS_NET_NAME" "M_A_CLK_DN<3>"
					( Origin gPackager )
				)
				( attribute "PNN" "M_A_CLK_DN<3>"
					( Origin gPackager )
				)
				( objectStatus "M_A_CLK_DN<3>" )
			)
			( signal "@baseboard_fab2_lib.baseboard_fab2(sch_1):m_a_clk_dp(0)"
				( attribute "CDS_PHYS_NET_NAME" "M_A_CLK_DP<0>"
					( Origin gPackager )
				)
				( attribute "PNN" "M_A_CLK_DP<0>"
					( Origin gPackager )
				)
				( objectStatus "M_A_CLK_DP<0>" )
			)
			( signal "@baseboard_fab2_lib.baseboard_fab2(sch_1):m_a_clk_dp(1)"
				( attribute "CDS_PHYS_NET_NAME" "M_A_CLK_DP<1>"
					( Origin gPackager )
				)
				( attribute "PNN" "M_A_CLK_DP<1>"
					( Origin gPackager )
				)
				( objectStatus "M_A_CLK_DP<1>" )
			)
			( signal "@baseboard_fab2_lib.baseboard_fab2(sch_1):m_a_clk_dp(2)"
				( attribute "CDS_PHYS_NET_NAME" "M_A_CLK_DP<2>"
					( Origin gPackager )
				)
				( attribute "PNN" "M_A_CLK_DP<2>"
					( Origin gPackager )
				)
				( objectStatus "M_A_CLK_DP<2>" )
			)
			( signal "@baseboard_fab2_lib.baseboard_fab2(sch_1):m_a_clk_dp(3)"
				( attribute "CDS_PHYS_NET_NAME" "M_A_CLK_DP<3>"
					( Origin gPackager )
				)
				( attribute "PNN" "M_A_CLK_DP<3>"
					( Origin gPackager )
				)
				( objectStatus "M_A_CLK_DP<3>" )
			)
			( signal "@baseboard_fab2_lib.baseboard_fab2(sch_1):m_a_cs_n(0)"
				( attribute "CDS_PHYS_NET_NAME" "M_A_CS_N<0>"
					( Origin gPackager )
				)
				( attribute "PNN" "M_A_CS_N<0>"
					( Origin gPackager )
				)
				( objectStatus "M_A_CS_N<0>" )
			)
			( signal "@baseboard_fab2_lib.baseboard_fab2(sch_1):m_a_cs_n(1)"
				( attribute "CDS_PHYS_NET_NAME" "M_A_CS_N<1>"
					( Origin gPackager )
				)
				( attribute "PNN" "M_A_CS_N<1>"
					( Origin gPackager )
				)
				( objectStatus "M_A_CS_N<1>" )
			)
			( signal "@baseboard_fab2_lib.baseboard_fab2(sch_1):m_a_cs_n(2)"
				( attribute "CDS_PHYS_NET_NAME" "M_A_CS_N<2>"
					( Origin gPackager )
				)
				( attribute "PNN" "M_A_CS_N<2>"
					( Origin gPackager )
				)
				( objectStatus "M_A_CS_N<2>" )
			)
			( signal "@baseboard_fab2_lib.baseboard_fab2(sch_1):m_a_cs_n(3)"
				( attribute "CDS_PHYS_NET_NAME" "M_A_CS_N<3>"
					( Origin gPackager )
				)
				( attribute "PNN" "M_A_CS_N<3>"
					( Origin gPackager )
				)
				( objectStatus "M_A_CS_N<3>" )
			)
			( signal "@baseboard_fab2_lib.baseboard_fab2(sch_1):m_a_cs_n(4)"
				( attribute "CDS_PHYS_NET_NAME" "M_A_CS_N<4>"
					( Origin gPackager )
				)
				( attribute "PNN" "M_A_CS_N<4>"
					( Origin gPackager )
				)
				( objectStatus "M_A_CS_N<4>" )
			)
			( signal "@baseboard_fab2_lib.baseboard_fab2(sch_1):m_a_cs_n(5)"
				( attribute "CDS_PHYS_NET_NAME" "M_A_CS_N<5>"
					( Origin gPackager )
				)
				( attribute "PNN" "M_A_CS_N<5>"
					( Origin gPackager )
				)
				( objectStatus "M_A_CS_N<5>" )
			)
			( signal "@baseboard_fab2_lib.baseboard_fab2(sch_1):m_a_cs_n(6)"
				( attribute "CDS_PHYS_NET_NAME" "M_A_CS_N<6>"
					( Origin gPackager )
				)
				( attribute "PNN" "M_A_CS_N<6>"
					( Origin gPackager )
				)
				( objectStatus "M_A_CS_N<6>" )
			)
			( signal "@baseboard_fab2_lib.baseboard_fab2(sch_1):m_a_cs_n(7)"
				( attribute "CDS_PHYS_NET_NAME" "M_A_CS_N<7>"
					( Origin gPackager )
				)
				( attribute "PNN" "M_A_CS_N<7>"
					( Origin gPackager )
				)
				( objectStatus "M_A_CS_N<7>" )
			)
			( signal "@baseboard_fab2_lib.baseboard_fab2(sch_1):m_a_dq(0)"
				( attribute "CDS_PHYS_NET_NAME" "M_A_DQ<0>"
					( Origin gPackager )
				)
				( attribute "PNN" "M_A_DQ<0>"
					( Origin gPackager )
				)
				( objectStatus "M_A_DQ<0>" )
			)
			( signal "@baseboard_fab2_lib.baseboard_fab2(sch_1):m_a_dq(1)"
				( attribute "CDS_PHYS_NET_NAME" "M_A_DQ<1>"
					( Origin gPackager )
				)
				( attribute "PNN" "M_A_DQ<1>"
					( Origin gPackager )
				)
				( objectStatus "M_A_DQ<1>" )
			)
			( signal "@baseboard_fab2_lib.baseboard_fab2(sch_1):m_a_dq(2)"
				( attribute "CDS_PHYS_NET_NAME" "M_A_DQ<2>"
					( Origin gPackager )
				)
				( attribute "PNN" "M_A_DQ<2>"
					( Origin gPackager )
				)
				( objectStatus "M_A_DQ<2>" )
			)
			( signal "@baseboard_fab2_lib.baseboard_fab2(sch_1):m_a_dq(3)"
				( attribute "CDS_PHYS_NET_NAME" "M_A_DQ<3>"
					( Origin gPackager )
				)
				( attribute "PNN" "M_A_DQ<3>"
					( Origin gPackager )
				)
				( objectStatus "M_A_DQ<3>" )
			)
			( signal "@baseboard_fab2_lib.baseboard_fab2(sch_1):m_a_dq(4)"
				( attribute "CDS_PHYS_NET_NAME" "M_A_DQ<4>"
					( Origin gPackager )
				)
				( attribute "PNN" "M_A_DQ<4>"
					( Origin gPackager )
				)
				( objectStatus "M_A_DQ<4>" )
			)
			( signal "@baseboard_fab2_lib.baseboard_fab2(sch_1):m_a_dq(5)"
				( attribute "CDS_PHYS_NET_NAME" "M_A_DQ<5>"
					( Origin gPackager )
				)
				( attribute "PNN" "M_A_DQ<5>"
					( Origin gPackager )
				)
				( objectStatus "M_A_DQ<5>" )
			)
			( signal "@baseboard_fab2_lib.baseboard_fab2(sch_1):m_a_dq(6)"
				( attribute "CDS_PHYS_NET_NAME" "M_A_DQ<6>"
					( Origin gPackager )
				)
				( attribute "PNN" "M_A_DQ<6>"
					( Origin gPackager )
				)
				( objectStatus "M_A_DQ<6>" )
			)
			( signal "@baseboard_fab2_lib.baseboard_fab2(sch_1):m_a_dq(7)"
				( attribute "CDS_PHYS_NET_NAME" "M_A_DQ<7>"
					( Origin gPackager )
				)
				( attribute "PNN" "M_A_DQ<7>"
					( Origin gPackager )
				)
				( objectStatus "M_A_DQ<7>" )
			)
			( signal "@baseboard_fab2_lib.baseboard_fab2(sch_1):m_a_dq(8)"
				( attribute "CDS_PHYS_NET_NAME" "M_A_DQ<8>"
					( Origin gPackager )
				)
				( attribute "PNN" "M_A_DQ<8>"
					( Origin gPackager )
				)
				( objectStatus "M_A_DQ<8>" )
			)
			( signal "@baseboard_fab2_lib.baseboard_fab2(sch_1):m_a_dq(9)"
				( attribute "CDS_PHYS_NET_NAME" "M_A_DQ<9>"
					( Origin gPackager )
				)
				( attribute "PNN" "M_A_DQ<9>"
					( Origin gPackager )
				)
				( objectStatus "M_A_DQ<9>" )
			)
			( signal "@baseboard_fab2_lib.baseboard_fab2(sch_1):m_a_dq(10)"
				( attribute "CDS_PHYS_NET_NAME" "M_A_DQ<10>"
					( Origin gPackager )
				)
				( attribute "PNN" "M_A_DQ<10>"
					( Origin gPackager )
				)
				( objectStatus "M_A_DQ<10>" )
			)
			( signal "@baseboard_fab2_lib.baseboard_fab2(sch_1):m_a_dq(11)"
				( attribute "CDS_PHYS_NET_NAME" "M_A_DQ<11>"
					( Origin gPackager )
				)
				( attribute "PNN" "M_A_DQ<11>"
					( Origin gPackager )
				)
				( objectStatus "M_A_DQ<11>" )
			)
			( signal "@baseboard_fab2_lib.baseboard_fab2(sch_1):m_a_dq(12)"
				( attribute "CDS_PHYS_NET_NAME" "M_A_DQ<12>"
					( Origin gPackager )
				)
				( attribute "PNN" "M_A_DQ<12>"
					( Origin gPackager )
				)
				( objectStatus "M_A_DQ<12>" )
			)
			( signal "@baseboard_fab2_lib.baseboard_fab2(sch_1):m_a_dq(13)"
				( attribute "CDS_PHYS_NET_NAME" "M_A_DQ<13>"
					( Origin gPackager )
				)
				( attribute "PNN" "M_A_DQ<13>"
					( Origin gPackager )
				)
				( objectStatus "M_A_DQ<13>" )
			)
			( signal "@baseboard_fab2_lib.baseboard_fab2(sch_1):m_a_dq(14)"
				( attribute "CDS_PHYS_NET_NAME" "M_A_DQ<14>"
					( Origin gPackager )
				)
				( attribute "PNN" "M_A_DQ<14>"
					( Origin gPackager )
				)
				( objectStatus "M_A_DQ<14>" )
			)
			( signal "@baseboard_fab2_lib.baseboard_fab2(sch_1):m_a_dq(15)"
				( attribute "CDS_PHYS_NET_NAME" "M_A_DQ<15>"
					( Origin gPackager )
				)
				( attribute "PNN" "M_A_DQ<15>"
					( Origin gPackager )
				)
				( objectStatus "M_A_DQ<15>" )
			)
			( signal "@baseboard_fab2_lib.baseboard_fab2(sch_1):m_a_dq(16)"
				( attribute "CDS_PHYS_NET_NAME" "M_A_DQ<16>"
					( Origin gPackager )
				)
				( attribute "PNN" "M_A_DQ<16>"
					( Origin gPackager )
				)
				( objectStatus "M_A_DQ<16>" )
			)
			( signal "@baseboard_fab2_lib.baseboard_fab2(sch_1):m_a_dq(17)"
				( attribute "CDS_PHYS_NET_NAME" "M_A_DQ<17>"
					( Origin gPackager )
				)
				( attribute "PNN" "M_A_DQ<17>"
					( Origin gPackager )
				)
				( objectStatus "M_A_DQ<17>" )
			)
			( signal "@baseboard_fab2_lib.baseboard_fab2(sch_1):m_a_dq(18)"
				( attribute "CDS_PHYS_NET_NAME" "M_A_DQ<18>"
					( Origin gPackager )
				)
				( attribute "PNN" "M_A_DQ<18>"
					( Origin gPackager )
				)
				( objectStatus "M_A_DQ<18>" )
			)
			( signal "@baseboard_fab2_lib.baseboard_fab2(sch_1):m_a_dq(19)"
				( attribute "CDS_PHYS_NET_NAME" "M_A_DQ<19>"
					( Origin gPackager )
				)
				( attribute "PNN" "M_A_DQ<19>"
					( Origin gPackager )
				)
				( objectStatus "M_A_DQ<19>" )
			)
			( signal "@baseboard_fab2_lib.baseboard_fab2(sch_1):m_a_dq(20)"
				( attribute "CDS_PHYS_NET_NAME" "M_A_DQ<20>"
					( Origin gPackager )
				)
				( attribute "PNN" "M_A_DQ<20>"
					( Origin gPackager )
				)
				( objectStatus "M_A_DQ<20>" )
			)
			( signal "@baseboard_fab2_lib.baseboard_fab2(sch_1):m_a_dq(21)"
				( attribute "CDS_PHYS_NET_NAME" "M_A_DQ<21>"
					( Origin gPackager )
				)
				( attribute "PNN" "M_A_DQ<21>"
					( Origin gPackager )
				)
				( objectStatus "M_A_DQ<21>" )
			)
			( signal "@baseboard_fab2_lib.baseboard_fab2(sch_1):m_a_dq(22)"
				( attribute "CDS_PHYS_NET_NAME" "M_A_DQ<22>"
					( Origin gPackager )
				)
				( attribute "PNN" "M_A_DQ<22>"
					( Origin gPackager )
				)
				( objectStatus "M_A_DQ<22>" )
			)
			( signal "@baseboard_fab2_lib.baseboard_fab2(sch_1):m_a_dq(23)"
				( attribute "CDS_PHYS_NET_NAME" "M_A_DQ<23>"
					( Origin gPackager )
				)
				( attribute "PNN" "M_A_DQ<23>"
					( Origin gPackager )
				)
				( objectStatus "M_A_DQ<23>" )
			)
			( signal "@baseboard_fab2_lib.baseboard_fab2(sch_1):m_a_dq(24)"
				( attribute "CDS_PHYS_NET_NAME" "M_A_DQ<24>"
					( Origin gPackager )
				)
				( attribute "PNN" "M_A_DQ<24>"
					( Origin gPackager )
				)
				( objectStatus "M_A_DQ<24>" )
			)
			( signal "@baseboard_fab2_lib.baseboard_fab2(sch_1):m_a_dq(25)"
				( attribute "CDS_PHYS_NET_NAME" "M_A_DQ<25>"
					( Origin gPackager )
				)
				( attribute "PNN" "M_A_DQ<25>"
					( Origin gPackager )
				)
				( objectStatus "M_A_DQ<25>" )
			)
			( signal "@baseboard_fab2_lib.baseboard_fab2(sch_1):m_a_dq(26)"
				( attribute "CDS_PHYS_NET_NAME" "M_A_DQ<26>"
					( Origin gPackager )
				)
				( attribute "PNN" "M_A_DQ<26>"
					( Origin gPackager )
				)
				( objectStatus "M_A_DQ<26>" )
			)
			( signal "@baseboard_fab2_lib.baseboard_fab2(sch_1):m_a_dq(27)"
				( attribute "CDS_PHYS_NET_NAME" "M_A_DQ<27>"
					( Origin gPackager )
				)
				( attribute "PNN" "M_A_DQ<27>"
					( Origin gPackager )
				)
				( objectStatus "M_A_DQ<27>" )
			)
			( signal "@baseboard_fab2_lib.baseboard_fab2(sch_1):m_a_dq(28)"
				( attribute "CDS_PHYS_NET_NAME" "M_A_DQ<28>"
					( Origin gPackager )
				)
				( attribute "PNN" "M_A_DQ<28>"
					( Origin gPackager )
				)
				( objectStatus "M_A_DQ<28>" )
			)
			( signal "@baseboard_fab2_lib.baseboard_fab2(sch_1):m_a_dq(29)"
				( attribute "CDS_PHYS_NET_NAME" "M_A_DQ<29>"
					( Origin gPackager )
				)
				( attribute "PNN" "M_A_DQ<29>"
					( Origin gPackager )
				)
				( objectStatus "M_A_DQ<29>" )
			)
			( signal "@baseboard_fab2_lib.baseboard_fab2(sch_1):m_a_dq(30)"
				( attribute "CDS_PHYS_NET_NAME" "M_A_DQ<30>"
					( Origin gPackager )
				)
				( attribute "PNN" "M_A_DQ<30>"
					( Origin gPackager )
				)
				( objectStatus "M_A_DQ<30>" )
			)
			( signal "@baseboard_fab2_lib.baseboard_fab2(sch_1):m_a_dq(31)"
				( attribute "CDS_PHYS_NET_NAME" "M_A_DQ<31>"
					( Origin gPackager )
				)
				( attribute "PNN" "M_A_DQ<31>"
					( Origin gPackager )
				)
				( objectStatus "M_A_DQ<31>" )
			)
			( signal "@baseboard_fab2_lib.baseboard_fab2(sch_1):m_a_dq(32)"
				( attribute "CDS_PHYS_NET_NAME" "M_A_DQ<32>"
					( Origin gPackager )
				)
				( attribute "PNN" "M_A_DQ<32>"
					( Origin gPackager )
				)
				( objectStatus "M_A_DQ<32>" )
			)
			( signal "@baseboard_fab2_lib.baseboard_fab2(sch_1):m_a_dq(33)"
				( attribute "CDS_PHYS_NET_NAME" "M_A_DQ<33>"
					( Origin gPackager )
				)
				( attribute "PNN" "M_A_DQ<33>"
					( Origin gPackager )
				)
				( objectStatus "M_A_DQ<33>" )
			)
			( signal "@baseboard_fab2_lib.baseboard_fab2(sch_1):m_a_dq(34)"
				( attribute "CDS_PHYS_NET_NAME" "M_A_DQ<34>"
					( Origin gPackager )
				)
				( attribute "PNN" "M_A_DQ<34>"
					( Origin gPackager )
				)
				( objectStatus "M_A_DQ<34>" )
			)
			( signal "@baseboard_fab2_lib.baseboard_fab2(sch_1):m_a_dq(35)"
				( attribute "CDS_PHYS_NET_NAME" "M_A_DQ<35>"
					( Origin gPackager )
				)
				( attribute "PNN" "M_A_DQ<35>"
					( Origin gPackager )
				)
				( objectStatus "M_A_DQ<35>" )
			)
			( signal "@baseboard_fab2_lib.baseboard_fab2(sch_1):m_a_dq(36)"
				( attribute "CDS_PHYS_NET_NAME" "M_A_DQ<36>"
					( Origin gPackager )
				)
				( attribute "PNN" "M_A_DQ<36>"
					( Origin gPackager )
				)
				( objectStatus "M_A_DQ<36>" )
			)
			( signal "@baseboard_fab2_lib.baseboard_fab2(sch_1):m_a_dq(37)"
				( attribute "CDS_PHYS_NET_NAME" "M_A_DQ<37>"
					( Origin gPackager )
				)
				( attribute "PNN" "M_A_DQ<37>"
					( Origin gPackager )
				)
				( objectStatus "M_A_DQ<37>" )
			)
			( signal "@baseboard_fab2_lib.baseboard_fab2(sch_1):m_a_dq(38)"
				( attribute "CDS_PHYS_NET_NAME" "M_A_DQ<38>"
					( Origin gPackager )
				)
				( attribute "PNN" "M_A_DQ<38>"
					( Origin gPackager )
				)
				( objectStatus "M_A_DQ<38>" )
			)
			( signal "@baseboard_fab2_lib.baseboard_fab2(sch_1):m_a_dq(39)"
				( attribute "CDS_PHYS_NET_NAME" "M_A_DQ<39>"
					( Origin gPackager )
				)
				( attribute "PNN" "M_A_DQ<39>"
					( Origin gPackager )
				)
				( objectStatus "M_A_DQ<39>" )
			)
			( signal "@baseboard_fab2_lib.baseboard_fab2(sch_1):m_a_dq(40)"
				( attribute "CDS_PHYS_NET_NAME" "M_A_DQ<40>"
					( Origin gPackager )
				)
				( attribute "PNN" "M_A_DQ<40>"
					( Origin gPackager )
				)
				( objectStatus "M_A_DQ<40>" )
			)
			( signal "@baseboard_fab2_lib.baseboard_fab2(sch_1):m_a_dq(41)"
				( attribute "CDS_PHYS_NET_NAME" "M_A_DQ<41>"
					( Origin gPackager )
				)
				( attribute "PNN" "M_A_DQ<41>"
					( Origin gPackager )
				)
				( objectStatus "M_A_DQ<41>" )
			)
			( signal "@baseboard_fab2_lib.baseboard_fab2(sch_1):m_a_dq(42)"
				( attribute "CDS_PHYS_NET_NAME" "M_A_DQ<42>"
					( Origin gPackager )
				)
				( attribute "PNN" "M_A_DQ<42>"
					( Origin gPackager )
				)
				( objectStatus "M_A_DQ<42>" )
			)
			( signal "@baseboard_fab2_lib.baseboard_fab2(sch_1):m_a_dq(43)"
				( attribute "CDS_PHYS_NET_NAME" "M_A_DQ<43>"
					( Origin gPackager )
				)
				( attribute "PNN" "M_A_DQ<43>"
					( Origin gPackager )
				)
				( objectStatus "M_A_DQ<43>" )
			)
			( signal "@baseboard_fab2_lib.baseboard_fab2(sch_1):m_a_dq(44)"
				( attribute "CDS_PHYS_NET_NAME" "M_A_DQ<44>"
					( Origin gPackager )
				)
				( attribute "PNN" "M_A_DQ<44>"
					( Origin gPackager )
				)
				( objectStatus "M_A_DQ<44>" )
			)
			( signal "@baseboard_fab2_lib.baseboard_fab2(sch_1):m_a_dq(45)"
				( attribute "CDS_PHYS_NET_NAME" "M_A_DQ<45>"
					( Origin gPackager )
				)
				( attribute "PNN" "M_A_DQ<45>"
					( Origin gPackager )
				)
				( objectStatus "M_A_DQ<45>" )
			)
			( signal "@baseboard_fab2_lib.baseboard_fab2(sch_1):m_a_dq(46)"
				( attribute "CDS_PHYS_NET_NAME" "M_A_DQ<46>"
					( Origin gPackager )
				)
				( attribute "PNN" "M_A_DQ<46>"
					( Origin gPackager )
				)
				( objectStatus "M_A_DQ<46>" )
			)
			( signal "@baseboard_fab2_lib.baseboard_fab2(sch_1):m_a_dq(47)"
				( attribute "CDS_PHYS_NET_NAME" "M_A_DQ<47>"
					( Origin gPackager )
				)
				( attribute "PNN" "M_A_DQ<47>"
					( Origin gPackager )
				)
				( objectStatus "M_A_DQ<47>" )
			)
			( signal "@baseboard_fab2_lib.baseboard_fab2(sch_1):m_a_dq(48)"
				( attribute "CDS_PHYS_NET_NAME" "M_A_DQ<48>"
					( Origin gPackager )
				)
				( attribute "PNN" "M_A_DQ<48>"
					( Origin gPackager )
				)
				( objectStatus "M_A_DQ<48>" )
			)
			( signal "@baseboard_fab2_lib.baseboard_fab2(sch_1):m_a_dq(49)"
				( attribute "CDS_PHYS_NET_NAME" "M_A_DQ<49>"
					( Origin gPackager )
				)
				( attribute "PNN" "M_A_DQ<49>"
					( Origin gPackager )
				)
				( objectStatus "M_A_DQ<49>" )
			)
			( signal "@baseboard_fab2_lib.baseboard_fab2(sch_1):m_a_dq(50)"
				( attribute "CDS_PHYS_NET_NAME" "M_A_DQ<50>"
					( Origin gPackager )
				)
				( attribute "PNN" "M_A_DQ<50>"
					( Origin gPackager )
				)
				( objectStatus "M_A_DQ<50>" )
			)
			( signal "@baseboard_fab2_lib.baseboard_fab2(sch_1):m_a_dq(51)"
				( attribute "CDS_PHYS_NET_NAME" "M_A_DQ<51>"
					( Origin gPackager )
				)
				( attribute "PNN" "M_A_DQ<51>"
					( Origin gPackager )
				)
				( objectStatus "M_A_DQ<51>" )
			)
			( signal "@baseboard_fab2_lib.baseboard_fab2(sch_1):m_a_dq(52)"
				( attribute "CDS_PHYS_NET_NAME" "M_A_DQ<52>"
					( Origin gPackager )
				)
				( attribute "PNN" "M_A_DQ<52>"
					( Origin gPackager )
				)
				( objectStatus "M_A_DQ<52>" )
			)
			( signal "@baseboard_fab2_lib.baseboard_fab2(sch_1):m_a_dq(53)"
				( attribute "CDS_PHYS_NET_NAME" "M_A_DQ<53>"
					( Origin gPackager )
				)
				( attribute "PNN" "M_A_DQ<53>"
					( Origin gPackager )
				)
				( objectStatus "M_A_DQ<53>" )
			)
			( signal "@baseboard_fab2_lib.baseboard_fab2(sch_1):m_a_dq(54)"
				( attribute "CDS_PHYS_NET_NAME" "M_A_DQ<54>"
					( Origin gPackager )
				)
				( attribute "PNN" "M_A_DQ<54>"
					( Origin gPackager )
				)
				( objectStatus "M_A_DQ<54>" )
			)
			( signal "@baseboard_fab2_lib.baseboard_fab2(sch_1):m_a_dq(55)"
				( attribute "CDS_PHYS_NET_NAME" "M_A_DQ<55>"
					( Origin gPackager )
				)
				( attribute "PNN" "M_A_DQ<55>"
					( Origin gPackager )
				)
				( objectStatus "M_A_DQ<55>" )
			)
			( signal "@baseboard_fab2_lib.baseboard_fab2(sch_1):m_a_dq(56)"
				( attribute "CDS_PHYS_NET_NAME" "M_A_DQ<56>"
					( Origin gPackager )
				)
				( attribute "PNN" "M_A_DQ<56>"
					( Origin gPackager )
				)
				( objectStatus "M_A_DQ<56>" )
			)
			( signal "@baseboard_fab2_lib.baseboard_fab2(sch_1):m_a_dq(57)"
				( attribute "CDS_PHYS_NET_NAME" "M_A_DQ<57>"
					( Origin gPackager )
				)
				( attribute "PNN" "M_A_DQ<57>"
					( Origin gPackager )
				)
				( objectStatus "M_A_DQ<57>" )
			)
			( signal "@baseboard_fab2_lib.baseboard_fab2(sch_1):m_a_dq(58)"
				( attribute "CDS_PHYS_NET_NAME" "M_A_DQ<58>"
					( Origin gPackager )
				)
				( attribute "PNN" "M_A_DQ<58>"
					( Origin gPackager )
				)
				( objectStatus "M_A_DQ<58>" )
			)
			( signal "@baseboard_fab2_lib.baseboard_fab2(sch_1):m_a_dq(59)"
				( attribute "CDS_PHYS_NET_NAME" "M_A_DQ<59>"
					( Origin gPackager )
				)
				( attribute "PNN" "M_A_DQ<59>"
					( Origin gPackager )
				)
				( objectStatus "M_A_DQ<59>" )
			)
			( signal "@baseboard_fab2_lib.baseboard_fab2(sch_1):m_a_dq(60)"
				( attribute "CDS_PHYS_NET_NAME" "M_A_DQ<60>"
					( Origin gPackager )
				)
				( attribute "PNN" "M_A_DQ<60>"
					( Origin gPackager )
				)
				( objectStatus "M_A_DQ<60>" )
			)
			( signal "@baseboard_fab2_lib.baseboard_fab2(sch_1):m_a_dq(61)"
				( attribute "CDS_PHYS_NET_NAME" "M_A_DQ<61>"
					( Origin gPackager )
				)
				( attribute "PNN" "M_A_DQ<61>"
					( Origin gPackager )
				)
				( objectStatus "M_A_DQ<61>" )
			)
			( signal "@baseboard_fab2_lib.baseboard_fab2(sch_1):m_a_dq(62)"
				( attribute "CDS_PHYS_NET_NAME" "M_A_DQ<62>"
					( Origin gPackager )
				)
				( attribute "PNN" "M_A_DQ<62>"
					( Origin gPackager )
				)
				( objectStatus "M_A_DQ<62>" )
			)
			( signal "@baseboard_fab2_lib.baseboard_fab2(sch_1):m_a_dq(63)"
				( attribute "CDS_PHYS_NET_NAME" "M_A_DQ<63>"
					( Origin gPackager )
				)
				( attribute "PNN" "M_A_DQ<63>"
					( Origin gPackager )
				)
				( objectStatus "M_A_DQ<63>" )
			)
			( signal "@baseboard_fab2_lib.baseboard_fab2(sch_1):m_a_dqs_dn(0)"
				( attribute "CDS_PHYS_NET_NAME" "M_A_DQS_DN<0>"
					( Origin gPackager )
				)
				( attribute "PNN" "M_A_DQS_DN<0>"
					( Origin gPackager )
				)
				( objectStatus "M_A_DQS_DN<0>" )
			)
			( signal "@baseboard_fab2_lib.baseboard_fab2(sch_1):m_a_dqs_dn(1)"
				( attribute "CDS_PHYS_NET_NAME" "M_A_DQS_DN<1>"
					( Origin gPackager )
				)
				( attribute "PNN" "M_A_DQS_DN<1>"
					( Origin gPackager )
				)
				( objectStatus "M_A_DQS_DN<1>" )
			)
			( signal "@baseboard_fab2_lib.baseboard_fab2(sch_1):m_a_dqs_dn(2)"
				( attribute "CDS_PHYS_NET_NAME" "M_A_DQS_DN<2>"
					( Origin gPackager )
				)
				( attribute "PNN" "M_A_DQS_DN<2>"
					( Origin gPackager )
				)
				( objectStatus "M_A_DQS_DN<2>" )
			)
			( signal "@baseboard_fab2_lib.baseboard_fab2(sch_1):m_a_dqs_dn(3)"
				( attribute "CDS_PHYS_NET_NAME" "M_A_DQS_DN<3>"
					( Origin gPackager )
				)
				( attribute "PNN" "M_A_DQS_DN<3>"
					( Origin gPackager )
				)
				( objectStatus "M_A_DQS_DN<3>" )
			)
			( signal "@baseboard_fab2_lib.baseboard_fab2(sch_1):m_a_dqs_dn(4)"
				( attribute "CDS_PHYS_NET_NAME" "M_A_DQS_DN<4>"
					( Origin gPackager )
				)
				( attribute "PNN" "M_A_DQS_DN<4>"
					( Origin gPackager )
				)
				( objectStatus "M_A_DQS_DN<4>" )
			)
			( signal "@baseboard_fab2_lib.baseboard_fab2(sch_1):m_a_dqs_dn(5)"
				( attribute "CDS_PHYS_NET_NAME" "M_A_DQS_DN<5>"
					( Origin gPackager )
				)
				( attribute "PNN" "M_A_DQS_DN<5>"
					( Origin gPackager )
				)
				( objectStatus "M_A_DQS_DN<5>" )
			)
			( signal "@baseboard_fab2_lib.baseboard_fab2(sch_1):m_a_dqs_dn(6)"
				( attribute "CDS_PHYS_NET_NAME" "M_A_DQS_DN<6>"
					( Origin gPackager )
				)
				( attribute "PNN" "M_A_DQS_DN<6>"
					( Origin gPackager )
				)
				( objectStatus "M_A_DQS_DN<6>" )
			)
			( signal "@baseboard_fab2_lib.baseboard_fab2(sch_1):m_a_dqs_dn(7)"
				( attribute "CDS_PHYS_NET_NAME" "M_A_DQS_DN<7>"
					( Origin gPackager )
				)
				( attribute "PNN" "M_A_DQS_DN<7>"
					( Origin gPackager )
				)
				( objectStatus "M_A_DQS_DN<7>" )
			)
			( signal "@baseboard_fab2_lib.baseboard_fab2(sch_1):m_a_dqs_dn(8)"
				( attribute "CDS_PHYS_NET_NAME" "M_A_DQS_DN<8>"
					( Origin gPackager )
				)
				( attribute "PNN" "M_A_DQS_DN<8>"
					( Origin gPackager )
				)
				( objectStatus "M_A_DQS_DN<8>" )
			)
			( signal "@baseboard_fab2_lib.baseboard_fab2(sch_1):m_a_dqs_dn(9)"
				( attribute "CDS_PHYS_NET_NAME" "M_A_DQS_DN<9>"
					( Origin gPackager )
				)
				( attribute "PNN" "M_A_DQS_DN<9>"
					( Origin gPackager )
				)
				( objectStatus "M_A_DQS_DN<9>" )
			)
			( signal "@baseboard_fab2_lib.baseboard_fab2(sch_1):m_a_dqs_dn(10)"
				( attribute "CDS_PHYS_NET_NAME" "M_A_DQS_DN<10>"
					( Origin gPackager )
				)
				( attribute "PNN" "M_A_DQS_DN<10>"
					( Origin gPackager )
				)
				( objectStatus "M_A_DQS_DN<10>" )
			)
			( signal "@baseboard_fab2_lib.baseboard_fab2(sch_1):m_a_dqs_dn(11)"
				( attribute "CDS_PHYS_NET_NAME" "M_A_DQS_DN<11>"
					( Origin gPackager )
				)
				( attribute "PNN" "M_A_DQS_DN<11>"
					( Origin gPackager )
				)
				( objectStatus "M_A_DQS_DN<11>" )
			)
			( signal "@baseboard_fab2_lib.baseboard_fab2(sch_1):m_a_dqs_dn(12)"
				( attribute "CDS_PHYS_NET_NAME" "M_A_DQS_DN<12>"
					( Origin gPackager )
				)
				( attribute "PNN" "M_A_DQS_DN<12>"
					( Origin gPackager )
				)
				( objectStatus "M_A_DQS_DN<12>" )
			)
			( signal "@baseboard_fab2_lib.baseboard_fab2(sch_1):m_a_dqs_dn(13)"
				( attribute "CDS_PHYS_NET_NAME" "M_A_DQS_DN<13>"
					( Origin gPackager )
				)
				( attribute "PNN" "M_A_DQS_DN<13>"
					( Origin gPackager )
				)
				( objectStatus "M_A_DQS_DN<13>" )
			)
			( signal "@baseboard_fab2_lib.baseboard_fab2(sch_1):m_a_dqs_dn(14)"
				( attribute "CDS_PHYS_NET_NAME" "M_A_DQS_DN<14>"
					( Origin gPackager )
				)
				( attribute "PNN" "M_A_DQS_DN<14>"
					( Origin gPackager )
				)
				( objectStatus "M_A_DQS_DN<14>" )
			)
			( signal "@baseboard_fab2_lib.baseboard_fab2(sch_1):m_a_dqs_dn(15)"
				( attribute "CDS_PHYS_NET_NAME" "M_A_DQS_DN<15>"
					( Origin gPackager )
				)
				( attribute "PNN" "M_A_DQS_DN<15>"
					( Origin gPackager )
				)
				( objectStatus "M_A_DQS_DN<15>" )
			)
			( signal "@baseboard_fab2_lib.baseboard_fab2(sch_1):m_a_dqs_dn(16)"
				( attribute "CDS_PHYS_NET_NAME" "M_A_DQS_DN<16>"
					( Origin gPackager )
				)
				( attribute "PNN" "M_A_DQS_DN<16>"
					( Origin gPackager )
				)
				( objectStatus "M_A_DQS_DN<16>" )
			)
			( signal "@baseboard_fab2_lib.baseboard_fab2(sch_1):m_a_dqs_dn(17)"
				( attribute "CDS_PHYS_NET_NAME" "M_A_DQS_DN<17>"
					( Origin gPackager )
				)
				( attribute "PNN" "M_A_DQS_DN<17>"
					( Origin gPackager )
				)
				( objectStatus "M_A_DQS_DN<17>" )
			)
			( signal "@baseboard_fab2_lib.baseboard_fab2(sch_1):m_a_dqs_dp(0)"
				( attribute "CDS_PHYS_NET_NAME" "M_A_DQS_DP<0>"
					( Origin gPackager )
				)
				( attribute "PNN" "M_A_DQS_DP<0>"
					( Origin gPackager )
				)
				( objectStatus "M_A_DQS_DP<0>" )
			)
			( signal "@baseboard_fab2_lib.baseboard_fab2(sch_1):m_a_dqs_dp(1)"
				( attribute "CDS_PHYS_NET_NAME" "M_A_DQS_DP<1>"
					( Origin gPackager )
				)
				( attribute "PNN" "M_A_DQS_DP<1>"
					( Origin gPackager )
				)
				( objectStatus "M_A_DQS_DP<1>" )
			)
			( signal "@baseboard_fab2_lib.baseboard_fab2(sch_1):m_a_dqs_dp(2)"
				( attribute "CDS_PHYS_NET_NAME" "M_A_DQS_DP<2>"
					( Origin gPackager )
				)
				( attribute "PNN" "M_A_DQS_DP<2>"
					( Origin gPackager )
				)
				( objectStatus "M_A_DQS_DP<2>" )
			)
			( signal "@baseboard_fab2_lib.baseboard_fab2(sch_1):m_a_dqs_dp(3)"
				( attribute "CDS_PHYS_NET_NAME" "M_A_DQS_DP<3>"
					( Origin gPackager )
				)
				( attribute "PNN" "M_A_DQS_DP<3>"
					( Origin gPackager )
				)
				( objectStatus "M_A_DQS_DP<3>" )
			)
			( signal "@baseboard_fab2_lib.baseboard_fab2(sch_1):m_a_dqs_dp(4)"
				( attribute "CDS_PHYS_NET_NAME" "M_A_DQS_DP<4>"
					( Origin gPackager )
				)
				( attribute "PNN" "M_A_DQS_DP<4>"
					( Origin gPackager )
				)
				( objectStatus "M_A_DQS_DP<4>" )
			)
			( signal "@baseboard_fab2_lib.baseboard_fab2(sch_1):m_a_dqs_dp(5)"
				( attribute "CDS_PHYS_NET_NAME" "M_A_DQS_DP<5>"
					( Origin gPackager )
				)
				( attribute "PNN" "M_A_DQS_DP<5>"
					( Origin gPackager )
				)
				( objectStatus "M_A_DQS_DP<5>" )
			)
			( signal "@baseboard_fab2_lib.baseboard_fab2(sch_1):m_a_dqs_dp(6)"
				( attribute "CDS_PHYS_NET_NAME" "M_A_DQS_DP<6>"
					( Origin gPackager )
				)
				( attribute "PNN" "M_A_DQS_DP<6>"
					( Origin gPackager )
				)
				( objectStatus "M_A_DQS_DP<6>" )
			)
			( signal "@baseboard_fab2_lib.baseboard_fab2(sch_1):m_a_dqs_dp(7)"
				( attribute "CDS_PHYS_NET_NAME" "M_A_DQS_DP<7>"
					( Origin gPackager )
				)
				( attribute "PNN" "M_A_DQS_DP<7>"
					( Origin gPackager )
				)
				( objectStatus "M_A_DQS_DP<7>" )
			)
			( signal "@baseboard_fab2_lib.baseboard_fab2(sch_1):m_a_dqs_dp(8)"
				( attribute "CDS_PHYS_NET_NAME" "M_A_DQS_DP<8>"
					( Origin gPackager )
				)
				( attribute "PNN" "M_A_DQS_DP<8>"
					( Origin gPackager )
				)
				( objectStatus "M_A_DQS_DP<8>" )
			)
			( signal "@baseboard_fab2_lib.baseboard_fab2(sch_1):m_a_dqs_dp(9)"
				( attribute "CDS_PHYS_NET_NAME" "M_A_DQS_DP<9>"
					( Origin gPackager )
				)
				( attribute "PNN" "M_A_DQS_DP<9>"
					( Origin gPackager )
				)
				( objectStatus "M_A_DQS_DP<9>" )
			)
			( signal "@baseboard_fab2_lib.baseboard_fab2(sch_1):m_a_dqs_dp(10)"
				( attribute "CDS_PHYS_NET_NAME" "M_A_DQS_DP<10>"
					( Origin gPackager )
				)
				( attribute "PNN" "M_A_DQS_DP<10>"
					( Origin gPackager )
				)
				( objectStatus "M_A_DQS_DP<10>" )
			)
			( signal "@baseboard_fab2_lib.baseboard_fab2(sch_1):m_a_dqs_dp(11)"
				( attribute "CDS_PHYS_NET_NAME" "M_A_DQS_DP<11>"
					( Origin gPackager )
				)
				( attribute "PNN" "M_A_DQS_DP<11>"
					( Origin gPackager )
				)
				( objectStatus "M_A_DQS_DP<11>" )
			)
			( signal "@baseboard_fab2_lib.baseboard_fab2(sch_1):m_a_dqs_dp(12)"
				( attribute "CDS_PHYS_NET_NAME" "M_A_DQS_DP<12>"
					( Origin gPackager )
				)
				( attribute "PNN" "M_A_DQS_DP<12>"
					( Origin gPackager )
				)
				( objectStatus "M_A_DQS_DP<12>" )
			)
			( signal "@baseboard_fab2_lib.baseboard_fab2(sch_1):m_a_dqs_dp(13)"
				( attribute "CDS_PHYS_NET_NAME" "M_A_DQS_DP<13>"
					( Origin gPackager )
				)
				( attribute "PNN" "M_A_DQS_DP<13>"
					( Origin gPackager )
				)
				( objectStatus "M_A_DQS_DP<13>" )
			)
			( signal "@baseboard_fab2_lib.baseboard_fab2(sch_1):m_a_dqs_dp(14)"
				( attribute "CDS_PHYS_NET_NAME" "M_A_DQS_DP<14>"
					( Origin gPackager )
				)
				( attribute "PNN" "M_A_DQS_DP<14>"
					( Origin gPackager )
				)
				( objectStatus "M_A_DQS_DP<14>" )
			)
			( signal "@baseboard_fab2_lib.baseboard_fab2(sch_1):m_a_dqs_dp(15)"
				( attribute "CDS_PHYS_NET_NAME" "M_A_DQS_DP<15>"
					( Origin gPackager )
				)
				( attribute "PNN" "M_A_DQS_DP<15>"
					( Origin gPackager )
				)
				( objectStatus "M_A_DQS_DP<15>" )
			)
			( signal "@baseboard_fab2_lib.baseboard_fab2(sch_1):m_a_dqs_dp(16)"
				( attribute "CDS_PHYS_NET_NAME" "M_A_DQS_DP<16>"
					( Origin gPackager )
				)
				( attribute "PNN" "M_A_DQS_DP<16>"
					( Origin gPackager )
				)
				( objectStatus "M_A_DQS_DP<16>" )
			)
			( signal "@baseboard_fab2_lib.baseboard_fab2(sch_1):m_a_dqs_dp(17)"
				( attribute "CDS_PHYS_NET_NAME" "M_A_DQS_DP<17>"
					( Origin gPackager )
				)
				( attribute "PNN" "M_A_DQS_DP<17>"
					( Origin gPackager )
				)
				( objectStatus "M_A_DQS_DP<17>" )
			)
			( signal "@baseboard_fab2_lib.baseboard_fab2(sch_1):m_a_ecc(0)"
				( attribute "CDS_PHYS_NET_NAME" "M_A_ECC<0>"
					( Origin gPackager )
				)
				( attribute "PNN" "M_A_ECC<0>"
					( Origin gPackager )
				)
				( objectStatus "M_A_ECC<0>" )
			)
			( signal "@baseboard_fab2_lib.baseboard_fab2(sch_1):m_a_ecc(1)"
				( attribute "CDS_PHYS_NET_NAME" "M_A_ECC<1>"
					( Origin gPackager )
				)
				( attribute "PNN" "M_A_ECC<1>"
					( Origin gPackager )
				)
				( objectStatus "M_A_ECC<1>" )
			)
			( signal "@baseboard_fab2_lib.baseboard_fab2(sch_1):m_a_ecc(2)"
				( attribute "CDS_PHYS_NET_NAME" "M_A_ECC<2>"
					( Origin gPackager )
				)
				( attribute "PNN" "M_A_ECC<2>"
					( Origin gPackager )
				)
				( objectStatus "M_A_ECC<2>" )
			)
			( signal "@baseboard_fab2_lib.baseboard_fab2(sch_1):m_a_ecc(3)"
				( attribute "CDS_PHYS_NET_NAME" "M_A_ECC<3>"
					( Origin gPackager )
				)
				( attribute "PNN" "M_A_ECC<3>"
					( Origin gPackager )
				)
				( objectStatus "M_A_ECC<3>" )
			)
			( signal "@baseboard_fab2_lib.baseboard_fab2(sch_1):m_a_ecc(4)"
				( attribute "CDS_PHYS_NET_NAME" "M_A_ECC<4>"
					( Origin gPackager )
				)
				( attribute "PNN" "M_A_ECC<4>"
					( Origin gPackager )
				)
				( objectStatus "M_A_ECC<4>" )
			)
			( signal "@baseboard_fab2_lib.baseboard_fab2(sch_1):m_a_ecc(5)"
				( attribute "CDS_PHYS_NET_NAME" "M_A_ECC<5>"
					( Origin gPackager )
				)
				( attribute "PNN" "M_A_ECC<5>"
					( Origin gPackager )
				)
				( objectStatus "M_A_ECC<5>" )
			)
			( signal "@baseboard_fab2_lib.baseboard_fab2(sch_1):m_a_ecc(6)"
				( attribute "CDS_PHYS_NET_NAME" "M_A_ECC<6>"
					( Origin gPackager )
				)
				( attribute "PNN" "M_A_ECC<6>"
					( Origin gPackager )
				)
				( objectStatus "M_A_ECC<6>" )
			)
			( signal "@baseboard_fab2_lib.baseboard_fab2(sch_1):m_a_ecc(7)"
				( attribute "CDS_PHYS_NET_NAME" "M_A_ECC<7>"
					( Origin gPackager )
				)
				( attribute "PNN" "M_A_ECC<7>"
					( Origin gPackager )
				)
				( objectStatus "M_A_ECC<7>" )
			)
			( signal "@baseboard_fab2_lib.baseboard_fab2(sch_1):m_a_ma(0)"
				( attribute "CDS_PHYS_NET_NAME" "M_A_MA<0>"
					( Origin gPackager )
				)
				( attribute "PNN" "M_A_MA<0>"
					( Origin gPackager )
				)
				( objectStatus "M_A_MA<0>" )
			)
			( signal "@baseboard_fab2_lib.baseboard_fab2(sch_1):m_a_ma(1)"
				( attribute "CDS_PHYS_NET_NAME" "M_A_MA<1>"
					( Origin gPackager )
				)
				( attribute "PNN" "M_A_MA<1>"
					( Origin gPackager )
				)
				( objectStatus "M_A_MA<1>" )
			)
			( signal "@baseboard_fab2_lib.baseboard_fab2(sch_1):m_a_ma(2)"
				( attribute "CDS_PHYS_NET_NAME" "M_A_MA<2>"
					( Origin gPackager )
				)
				( attribute "PNN" "M_A_MA<2>"
					( Origin gPackager )
				)
				( objectStatus "M_A_MA<2>" )
			)
			( signal "@baseboard_fab2_lib.baseboard_fab2(sch_1):m_a_ma(3)"
				( attribute "CDS_PHYS_NET_NAME" "M_A_MA<3>"
					( Origin gPackager )
				)
				( attribute "PNN" "M_A_MA<3>"
					( Origin gPackager )
				)
				( objectStatus "M_A_MA<3>" )
			)
			( signal "@baseboard_fab2_lib.baseboard_fab2(sch_1):m_a_ma(4)"
				( attribute "CDS_PHYS_NET_NAME" "M_A_MA<4>"
					( Origin gPackager )
				)
				( attribute "PNN" "M_A_MA<4>"
					( Origin gPackager )
				)
				( objectStatus "M_A_MA<4>" )
			)
			( signal "@baseboard_fab2_lib.baseboard_fab2(sch_1):m_a_ma(5)"
				( attribute "CDS_PHYS_NET_NAME" "M_A_MA<5>"
					( Origin gPackager )
				)
				( attribute "PNN" "M_A_MA<5>"
					( Origin gPackager )
				)
				( objectStatus "M_A_MA<5>" )
			)
			( signal "@baseboard_fab2_lib.baseboard_fab2(sch_1):m_a_ma(6)"
				( attribute "CDS_PHYS_NET_NAME" "M_A_MA<6>"
					( Origin gPackager )
				)
				( attribute "PNN" "M_A_MA<6>"
					( Origin gPackager )
				)
				( objectStatus "M_A_MA<6>" )
			)
			( signal "@baseboard_fab2_lib.baseboard_fab2(sch_1):m_a_ma(7)"
				( attribute "CDS_PHYS_NET_NAME" "M_A_MA<7>"
					( Origin gPackager )
				)
				( attribute "PNN" "M_A_MA<7>"
					( Origin gPackager )
				)
				( objectStatus "M_A_MA<7>" )
			)
			( signal "@baseboard_fab2_lib.baseboard_fab2(sch_1):m_a_ma(8)"
				( attribute "CDS_PHYS_NET_NAME" "M_A_MA<8>"
					( Origin gPackager )
				)
				( attribute "PNN" "M_A_MA<8>"
					( Origin gPackager )
				)
				( objectStatus "M_A_MA<8>" )
			)
			( signal "@baseboard_fab2_lib.baseboard_fab2(sch_1):m_a_ma(9)"
				( attribute "CDS_PHYS_NET_NAME" "M_A_MA<9>"
					( Origin gPackager )
				)
				( attribute "PNN" "M_A_MA<9>"
					( Origin gPackager )
				)
				( objectStatus "M_A_MA<9>" )
			)
			( signal "@baseboard_fab2_lib.baseboard_fab2(sch_1):m_a_ma(10)"
				( attribute "CDS_PHYS_NET_NAME" "M_A_MA<10>"
					( Origin gPackager )
				)
				( attribute "PNN" "M_A_MA<10>"
					( Origin gPackager )
				)
				( objectStatus "M_A_MA<10>" )
			)
			( signal "@baseboard_fab2_lib.baseboard_fab2(sch_1):m_a_ma(11)"
				( attribute "CDS_PHYS_NET_NAME" "M_A_MA<11>"
					( Origin gPackager )
				)
				( attribute "PNN" "M_A_MA<11>"
					( Origin gPackager )
				)
				( objectStatus "M_A_MA<11>" )
			)
			( signal "@baseboard_fab2_lib.baseboard_fab2(sch_1):m_a_ma(12)"
				( attribute "CDS_PHYS_NET_NAME" "M_A_MA<12>"
					( Origin gPackager )
				)
				( attribute "PNN" "M_A_MA<12>"
					( Origin gPackager )
				)
				( objectStatus "M_A_MA<12>" )
			)
			( signal "@baseboard_fab2_lib.baseboard_fab2(sch_1):m_a_ma(13)"
				( attribute "CDS_PHYS_NET_NAME" "M_A_MA<13>"
					( Origin gPackager )
				)
				( attribute "PNN" "M_A_MA<13>"
					( Origin gPackager )
				)
				( objectStatus "M_A_MA<13>" )
			)
			( signal "@baseboard_fab2_lib.baseboard_fab2(sch_1):m_a_ma(14)"
				( attribute "CDS_PHYS_NET_NAME" "M_A_MA<14>"
					( Origin gPackager )
				)
				( attribute "PNN" "M_A_MA<14>"
					( Origin gPackager )
				)
				( objectStatus "M_A_MA<14>" )
			)
			( signal "@baseboard_fab2_lib.baseboard_fab2(sch_1):m_a_ma(15)"
				( attribute "CDS_PHYS_NET_NAME" "M_A_MA<15>"
					( Origin gPackager )
				)
				( attribute "PNN" "M_A_MA<15>"
					( Origin gPackager )
				)
				( objectStatus "M_A_MA<15>" )
			)
			( signal "@baseboard_fab2_lib.baseboard_fab2(sch_1):m_a_ma(16)"
				( attribute "CDS_PHYS_NET_NAME" "M_A_MA<16>"
					( Origin gPackager )
				)
				( attribute "PNN" "M_A_MA<16>"
					( Origin gPackager )
				)
				( objectStatus "M_A_MA<16>" )
			)
			( signal "@baseboard_fab2_lib.baseboard_fab2(sch_1):m_a_ma(17)"
				( attribute "CDS_PHYS_NET_NAME" "M_A_MA<17>"
					( Origin gPackager )
				)
				( attribute "PNN" "M_A_MA<17>"
					( Origin gPackager )
				)
				( objectStatus "M_A_MA<17>" )
			)
			( signal "@baseboard_fab2_lib.baseboard_fab2(sch_1):m_a_odt(0)"
				( attribute "CDS_PHYS_NET_NAME" "M_A_ODT<0>"
					( Origin gPackager )
				)
				( attribute "PNN" "M_A_ODT<0>"
					( Origin gPackager )
				)
				( objectStatus "M_A_ODT<0>" )
			)
			( signal "@baseboard_fab2_lib.baseboard_fab2(sch_1):m_a_odt(1)"
				( attribute "CDS_PHYS_NET_NAME" "M_A_ODT<1>"
					( Origin gPackager )
				)
				( attribute "PNN" "M_A_ODT<1>"
					( Origin gPackager )
				)
				( objectStatus "M_A_ODT<1>" )
			)
			( signal "@baseboard_fab2_lib.baseboard_fab2(sch_1):m_a_odt(2)"
				( attribute "CDS_PHYS_NET_NAME" "M_A_ODT<2>"
					( Origin gPackager )
				)
				( attribute "PNN" "M_A_ODT<2>"
					( Origin gPackager )
				)
				( objectStatus "M_A_ODT<2>" )
			)
			( signal "@baseboard_fab2_lib.baseboard_fab2(sch_1):m_a_odt(3)"
				( attribute "CDS_PHYS_NET_NAME" "M_A_ODT<3>"
					( Origin gPackager )
				)
				( attribute "PNN" "M_A_ODT<3>"
					( Origin gPackager )
				)
				( objectStatus "M_A_ODT<3>" )
			)
			( signal "@baseboard_fab2_lib.baseboard_fab2(sch_1):m_a_par"
				( attribute "CDS_PHYS_NET_NAME" "M_A_PAR"
					( Origin gPackager )
				)
				( objectStatus "M_A_PAR" )
			)
			( signal "@baseboard_fab2_lib.baseboard_fab2(sch_1):m_b_act_n"
				( attribute "CDS_PHYS_NET_NAME" "M_B_ACT_N"
					( Origin gPackager )
				)
				( objectStatus "M_B_ACT_N" )
			)
			( signal "@baseboard_fab2_lib.baseboard_fab2(sch_1):m_b_alert_n"
				( attribute "CDS_PHYS_NET_NAME" "M_B_ALERT_N"
					( Origin gPackager )
				)
				( objectStatus "M_B_ALERT_N" )
			)
			( signal "@baseboard_fab2_lib.baseboard_fab2(sch_1):m_b_ba(0)"
				( attribute "CDS_PHYS_NET_NAME" "M_B_BA<0>"
					( Origin gPackager )
				)
				( attribute "PNN" "M_B_BA<0>"
					( Origin gPackager )
				)
				( objectStatus "M_B_BA<0>" )
			)
			( signal "@baseboard_fab2_lib.baseboard_fab2(sch_1):m_b_ba(1)"
				( attribute "CDS_PHYS_NET_NAME" "M_B_BA<1>"
					( Origin gPackager )
				)
				( attribute "PNN" "M_B_BA<1>"
					( Origin gPackager )
				)
				( objectStatus "M_B_BA<1>" )
			)
			( signal "@baseboard_fab2_lib.baseboard_fab2(sch_1):m_b_bg(0)"
				( attribute "CDS_PHYS_NET_NAME" "M_B_BG<0>"
					( Origin gPackager )
				)
				( attribute "PNN" "M_B_BG<0>"
					( Origin gPackager )
				)
				( objectStatus "M_B_BG<0>" )
			)
			( signal "@baseboard_fab2_lib.baseboard_fab2(sch_1):m_b_bg(1)"
				( attribute "CDS_PHYS_NET_NAME" "M_B_BG<1>"
					( Origin gPackager )
				)
				( attribute "PNN" "M_B_BG<1>"
					( Origin gPackager )
				)
				( objectStatus "M_B_BG<1>" )
			)
			( signal "@baseboard_fab2_lib.baseboard_fab2(sch_1):m_b_c(2)"
				( attribute "CDS_PHYS_NET_NAME" "M_B_C<2>"
					( Origin gPackager )
				)
				( attribute "PNN" "M_B_C<2>"
					( Origin gPackager )
				)
				( objectStatus "M_B_C<2>" )
			)
			( signal "@baseboard_fab2_lib.baseboard_fab2(sch_1):m_b_cke(0)"
				( attribute "CDS_PHYS_NET_NAME" "M_B_CKE<0>"
					( Origin gPackager )
				)
				( attribute "PNN" "M_B_CKE<0>"
					( Origin gPackager )
				)
				( objectStatus "M_B_CKE<0>" )
			)
			( signal "@baseboard_fab2_lib.baseboard_fab2(sch_1):m_b_cke(1)"
				( attribute "CDS_PHYS_NET_NAME" "M_B_CKE<1>"
					( Origin gPackager )
				)
				( attribute "PNN" "M_B_CKE<1>"
					( Origin gPackager )
				)
				( objectStatus "M_B_CKE<1>" )
			)
			( signal "@baseboard_fab2_lib.baseboard_fab2(sch_1):m_b_cke(2)"
				( attribute "CDS_PHYS_NET_NAME" "M_B_CKE<2>"
					( Origin gPackager )
				)
				( attribute "PNN" "M_B_CKE<2>"
					( Origin gPackager )
				)
				( objectStatus "M_B_CKE<2>" )
			)
			( signal "@baseboard_fab2_lib.baseboard_fab2(sch_1):m_b_cke(3)"
				( attribute "CDS_PHYS_NET_NAME" "M_B_CKE<3>"
					( Origin gPackager )
				)
				( attribute "PNN" "M_B_CKE<3>"
					( Origin gPackager )
				)
				( objectStatus "M_B_CKE<3>" )
			)
			( signal "@baseboard_fab2_lib.baseboard_fab2(sch_1):m_b_clk_dn(0)"
				( attribute "CDS_PHYS_NET_NAME" "M_B_CLK_DN<0>"
					( Origin gPackager )
				)
				( attribute "PNN" "M_B_CLK_DN<0>"
					( Origin gPackager )
				)
				( objectStatus "M_B_CLK_DN<0>" )
			)
			( signal "@baseboard_fab2_lib.baseboard_fab2(sch_1):m_b_clk_dn(1)"
				( attribute "CDS_PHYS_NET_NAME" "M_B_CLK_DN<1>"
					( Origin gPackager )
				)
				( attribute "PNN" "M_B_CLK_DN<1>"
					( Origin gPackager )
				)
				( objectStatus "M_B_CLK_DN<1>" )
			)
			( signal "@baseboard_fab2_lib.baseboard_fab2(sch_1):m_b_clk_dn(2)"
				( attribute "CDS_PHYS_NET_NAME" "M_B_CLK_DN<2>"
					( Origin gPackager )
				)
				( attribute "PNN" "M_B_CLK_DN<2>"
					( Origin gPackager )
				)
				( objectStatus "M_B_CLK_DN<2>" )
			)
			( signal "@baseboard_fab2_lib.baseboard_fab2(sch_1):m_b_clk_dn(3)"
				( attribute "CDS_PHYS_NET_NAME" "M_B_CLK_DN<3>"
					( Origin gPackager )
				)
				( attribute "PNN" "M_B_CLK_DN<3>"
					( Origin gPackager )
				)
				( objectStatus "M_B_CLK_DN<3>" )
			)
			( signal "@baseboard_fab2_lib.baseboard_fab2(sch_1):m_b_clk_dp(0)"
				( attribute "CDS_PHYS_NET_NAME" "M_B_CLK_DP<0>"
					( Origin gPackager )
				)
				( attribute "PNN" "M_B_CLK_DP<0>"
					( Origin gPackager )
				)
				( objectStatus "M_B_CLK_DP<0>" )
			)
			( signal "@baseboard_fab2_lib.baseboard_fab2(sch_1):m_b_clk_dp(1)"
				( attribute "CDS_PHYS_NET_NAME" "M_B_CLK_DP<1>"
					( Origin gPackager )
				)
				( attribute "PNN" "M_B_CLK_DP<1>"
					( Origin gPackager )
				)
				( objectStatus "M_B_CLK_DP<1>" )
			)
			( signal "@baseboard_fab2_lib.baseboard_fab2(sch_1):m_b_clk_dp(2)"
				( attribute "CDS_PHYS_NET_NAME" "M_B_CLK_DP<2>"
					( Origin gPackager )
				)
				( attribute "PNN" "M_B_CLK_DP<2>"
					( Origin gPackager )
				)
				( objectStatus "M_B_CLK_DP<2>" )
			)
			( signal "@baseboard_fab2_lib.baseboard_fab2(sch_1):m_b_clk_dp(3)"
				( attribute "CDS_PHYS_NET_NAME" "M_B_CLK_DP<3>"
					( Origin gPackager )
				)
				( attribute "PNN" "M_B_CLK_DP<3>"
					( Origin gPackager )
				)
				( objectStatus "M_B_CLK_DP<3>" )
			)
			( signal "@baseboard_fab2_lib.baseboard_fab2(sch_1):m_b_cs_n(0)"
				( attribute "CDS_PHYS_NET_NAME" "M_B_CS_N<0>"
					( Origin gPackager )
				)
				( attribute "PNN" "M_B_CS_N<0>"
					( Origin gPackager )
				)
				( objectStatus "M_B_CS_N<0>" )
			)
			( signal "@baseboard_fab2_lib.baseboard_fab2(sch_1):m_b_cs_n(1)"
				( attribute "CDS_PHYS_NET_NAME" "M_B_CS_N<1>"
					( Origin gPackager )
				)
				( attribute "PNN" "M_B_CS_N<1>"
					( Origin gPackager )
				)
				( objectStatus "M_B_CS_N<1>" )
			)
			( signal "@baseboard_fab2_lib.baseboard_fab2(sch_1):m_b_cs_n(2)"
				( attribute "CDS_PHYS_NET_NAME" "M_B_CS_N<2>"
					( Origin gPackager )
				)
				( attribute "PNN" "M_B_CS_N<2>"
					( Origin gPackager )
				)
				( objectStatus "M_B_CS_N<2>" )
			)
			( signal "@baseboard_fab2_lib.baseboard_fab2(sch_1):m_b_cs_n(3)"
				( attribute "CDS_PHYS_NET_NAME" "M_B_CS_N<3>"
					( Origin gPackager )
				)
				( attribute "PNN" "M_B_CS_N<3>"
					( Origin gPackager )
				)
				( objectStatus "M_B_CS_N<3>" )
			)
			( signal "@baseboard_fab2_lib.baseboard_fab2(sch_1):m_b_cs_n(4)"
				( attribute "CDS_PHYS_NET_NAME" "M_B_CS_N<4>"
					( Origin gPackager )
				)
				( attribute "PNN" "M_B_CS_N<4>"
					( Origin gPackager )
				)
				( objectStatus "M_B_CS_N<4>" )
			)
			( signal "@baseboard_fab2_lib.baseboard_fab2(sch_1):m_b_cs_n(5)"
				( attribute "CDS_PHYS_NET_NAME" "M_B_CS_N<5>"
					( Origin gPackager )
				)
				( attribute "PNN" "M_B_CS_N<5>"
					( Origin gPackager )
				)
				( objectStatus "M_B_CS_N<5>" )
			)
			( signal "@baseboard_fab2_lib.baseboard_fab2(sch_1):m_b_cs_n(6)"
				( attribute "CDS_PHYS_NET_NAME" "M_B_CS_N<6>"
					( Origin gPackager )
				)
				( attribute "PNN" "M_B_CS_N<6>"
					( Origin gPackager )
				)
				( objectStatus "M_B_CS_N<6>" )
			)
			( signal "@baseboard_fab2_lib.baseboard_fab2(sch_1):m_b_cs_n(7)"
				( attribute "CDS_PHYS_NET_NAME" "M_B_CS_N<7>"
					( Origin gPackager )
				)
				( attribute "PNN" "M_B_CS_N<7>"
					( Origin gPackager )
				)
				( objectStatus "M_B_CS_N<7>" )
			)
			( signal "@baseboard_fab2_lib.baseboard_fab2(sch_1):m_b_dq(0)"
				( attribute "CDS_PHYS_NET_NAME" "M_B_DQ<0>"
					( Origin gPackager )
				)
				( attribute "PNN" "M_B_DQ<0>"
					( Origin gPackager )
				)
				( objectStatus "M_B_DQ<0>" )
			)
			( signal "@baseboard_fab2_lib.baseboard_fab2(sch_1):m_b_dq(1)"
				( attribute "CDS_PHYS_NET_NAME" "M_B_DQ<1>"
					( Origin gPackager )
				)
				( attribute "PNN" "M_B_DQ<1>"
					( Origin gPackager )
				)
				( objectStatus "M_B_DQ<1>" )
			)
			( signal "@baseboard_fab2_lib.baseboard_fab2(sch_1):m_b_dq(2)"
				( attribute "CDS_PHYS_NET_NAME" "M_B_DQ<2>"
					( Origin gPackager )
				)
				( attribute "PNN" "M_B_DQ<2>"
					( Origin gPackager )
				)
				( objectStatus "M_B_DQ<2>" )
			)
			( signal "@baseboard_fab2_lib.baseboard_fab2(sch_1):m_b_dq(3)"
				( attribute "CDS_PHYS_NET_NAME" "M_B_DQ<3>"
					( Origin gPackager )
				)
				( attribute "PNN" "M_B_DQ<3>"
					( Origin gPackager )
				)
				( objectStatus "M_B_DQ<3>" )
			)
			( signal "@baseboard_fab2_lib.baseboard_fab2(sch_1):m_b_dq(4)"
				( attribute "CDS_PHYS_NET_NAME" "M_B_DQ<4>"
					( Origin gPackager )
				)
				( attribute "PNN" "M_B_DQ<4>"
					( Origin gPackager )
				)
				( objectStatus "M_B_DQ<4>" )
			)
			( signal "@baseboard_fab2_lib.baseboard_fab2(sch_1):m_b_dq(5)"
				( attribute "CDS_PHYS_NET_NAME" "M_B_DQ<5>"
					( Origin gPackager )
				)
				( attribute "PNN" "M_B_DQ<5>"
					( Origin gPackager )
				)
				( objectStatus "M_B_DQ<5>" )
			)
			( signal "@baseboard_fab2_lib.baseboard_fab2(sch_1):m_b_dq(6)"
				( attribute "CDS_PHYS_NET_NAME" "M_B_DQ<6>"
					( Origin gPackager )
				)
				( attribute "PNN" "M_B_DQ<6>"
					( Origin gPackager )
				)
				( objectStatus "M_B_DQ<6>" )
			)
			( signal "@baseboard_fab2_lib.baseboard_fab2(sch_1):m_b_dq(7)"
				( attribute "CDS_PHYS_NET_NAME" "M_B_DQ<7>"
					( Origin gPackager )
				)
				( attribute "PNN" "M_B_DQ<7>"
					( Origin gPackager )
				)
				( objectStatus "M_B_DQ<7>" )
			)
			( signal "@baseboard_fab2_lib.baseboard_fab2(sch_1):m_b_dq(8)"
				( attribute "CDS_PHYS_NET_NAME" "M_B_DQ<8>"
					( Origin gPackager )
				)
				( attribute "PNN" "M_B_DQ<8>"
					( Origin gPackager )
				)
				( objectStatus "M_B_DQ<8>" )
			)
			( signal "@baseboard_fab2_lib.baseboard_fab2(sch_1):m_b_dq(9)"
				( attribute "CDS_PHYS_NET_NAME" "M_B_DQ<9>"
					( Origin gPackager )
				)
				( attribute "PNN" "M_B_DQ<9>"
					( Origin gPackager )
				)
				( objectStatus "M_B_DQ<9>" )
			)
			( signal "@baseboard_fab2_lib.baseboard_fab2(sch_1):m_b_dq(10)"
				( attribute "CDS_PHYS_NET_NAME" "M_B_DQ<10>"
					( Origin gPackager )
				)
				( attribute "PNN" "M_B_DQ<10>"
					( Origin gPackager )
				)
				( objectStatus "M_B_DQ<10>" )
			)
			( signal "@baseboard_fab2_lib.baseboard_fab2(sch_1):m_b_dq(11)"
				( attribute "CDS_PHYS_NET_NAME" "M_B_DQ<11>"
					( Origin gPackager )
				)
				( attribute "PNN" "M_B_DQ<11>"
					( Origin gPackager )
				)
				( objectStatus "M_B_DQ<11>" )
			)
			( signal "@baseboard_fab2_lib.baseboard_fab2(sch_1):m_b_dq(12)"
				( attribute "CDS_PHYS_NET_NAME" "M_B_DQ<12>"
					( Origin gPackager )
				)
				( attribute "PNN" "M_B_DQ<12>"
					( Origin gPackager )
				)
				( objectStatus "M_B_DQ<12>" )
			)
			( signal "@baseboard_fab2_lib.baseboard_fab2(sch_1):m_b_dq(13)"
				( attribute "CDS_PHYS_NET_NAME" "M_B_DQ<13>"
					( Origin gPackager )
				)
				( attribute "PNN" "M_B_DQ<13>"
					( Origin gPackager )
				)
				( objectStatus "M_B_DQ<13>" )
			)
			( signal "@baseboard_fab2_lib.baseboard_fab2(sch_1):m_b_dq(14)"
				( attribute "CDS_PHYS_NET_NAME" "M_B_DQ<14>"
					( Origin gPackager )
				)
				( attribute "PNN" "M_B_DQ<14>"
					( Origin gPackager )
				)
				( objectStatus "M_B_DQ<14>" )
			)
			( signal "@baseboard_fab2_lib.baseboard_fab2(sch_1):m_b_dq(15)"
				( attribute "CDS_PHYS_NET_NAME" "M_B_DQ<15>"
					( Origin gPackager )
				)
				( attribute "PNN" "M_B_DQ<15>"
					( Origin gPackager )
				)
				( objectStatus "M_B_DQ<15>" )
			)
			( signal "@baseboard_fab2_lib.baseboard_fab2(sch_1):m_b_dq(16)"
				( attribute "CDS_PHYS_NET_NAME" "M_B_DQ<16>"
					( Origin gPackager )
				)
				( attribute "PNN" "M_B_DQ<16>"
					( Origin gPackager )
				)
				( objectStatus "M_B_DQ<16>" )
			)
			( signal "@baseboard_fab2_lib.baseboard_fab2(sch_1):m_b_dq(17)"
				( attribute "CDS_PHYS_NET_NAME" "M_B_DQ<17>"
					( Origin gPackager )
				)
				( attribute "PNN" "M_B_DQ<17>"
					( Origin gPackager )
				)
				( objectStatus "M_B_DQ<17>" )
			)
			( signal "@baseboard_fab2_lib.baseboard_fab2(sch_1):m_b_dq(18)"
				( attribute "CDS_PHYS_NET_NAME" "M_B_DQ<18>"
					( Origin gPackager )
				)
				( attribute "PNN" "M_B_DQ<18>"
					( Origin gPackager )
				)
				( objectStatus "M_B_DQ<18>" )
			)
			( signal "@baseboard_fab2_lib.baseboard_fab2(sch_1):m_b_dq(19)"
				( attribute "CDS_PHYS_NET_NAME" "M_B_DQ<19>"
					( Origin gPackager )
				)
				( attribute "PNN" "M_B_DQ<19>"
					( Origin gPackager )
				)
				( objectStatus "M_B_DQ<19>" )
			)
			( signal "@baseboard_fab2_lib.baseboard_fab2(sch_1):m_b_dq(20)"
				( attribute "CDS_PHYS_NET_NAME" "M_B_DQ<20>"
					( Origin gPackager )
				)
				( attribute "PNN" "M_B_DQ<20>"
					( Origin gPackager )
				)
				( objectStatus "M_B_DQ<20>" )
			)
			( signal "@baseboard_fab2_lib.baseboard_fab2(sch_1):m_b_dq(21)"
				( attribute "CDS_PHYS_NET_NAME" "M_B_DQ<21>"
					( Origin gPackager )
				)
				( attribute "PNN" "M_B_DQ<21>"
					( Origin gPackager )
				)
				( objectStatus "M_B_DQ<21>" )
			)
			( signal "@baseboard_fab2_lib.baseboard_fab2(sch_1):m_b_dq(22)"
				( attribute "CDS_PHYS_NET_NAME" "M_B_DQ<22>"
					( Origin gPackager )
				)
				( attribute "PNN" "M_B_DQ<22>"
					( Origin gPackager )
				)
				( objectStatus "M_B_DQ<22>" )
			)
			( signal "@baseboard_fab2_lib.baseboard_fab2(sch_1):m_b_dq(23)"
				( attribute "CDS_PHYS_NET_NAME" "M_B_DQ<23>"
					( Origin gPackager )
				)
				( attribute "PNN" "M_B_DQ<23>"
					( Origin gPackager )
				)
				( objectStatus "M_B_DQ<23>" )
			)
			( signal "@baseboard_fab2_lib.baseboard_fab2(sch_1):m_b_dq(24)"
				( attribute "CDS_PHYS_NET_NAME" "M_B_DQ<24>"
					( Origin gPackager )
				)
				( attribute "PNN" "M_B_DQ<24>"
					( Origin gPackager )
				)
				( objectStatus "M_B_DQ<24>" )
			)
			( signal "@baseboard_fab2_lib.baseboard_fab2(sch_1):m_b_dq(25)"
				( attribute "CDS_PHYS_NET_NAME" "M_B_DQ<25>"
					( Origin gPackager )
				)
				( attribute "PNN" "M_B_DQ<25>"
					( Origin gPackager )
				)
				( objectStatus "M_B_DQ<25>" )
			)
			( signal "@baseboard_fab2_lib.baseboard_fab2(sch_1):m_b_dq(26)"
				( attribute "CDS_PHYS_NET_NAME" "M_B_DQ<26>"
					( Origin gPackager )
				)
				( attribute "PNN" "M_B_DQ<26>"
					( Origin gPackager )
				)
				( objectStatus "M_B_DQ<26>" )
			)
			( signal "@baseboard_fab2_lib.baseboard_fab2(sch_1):m_b_dq(27)"
				( attribute "CDS_PHYS_NET_NAME" "M_B_DQ<27>"
					( Origin gPackager )
				)
				( attribute "PNN" "M_B_DQ<27>"
					( Origin gPackager )
				)
				( objectStatus "M_B_DQ<27>" )
			)
			( signal "@baseboard_fab2_lib.baseboard_fab2(sch_1):m_b_dq(28)"
				( attribute "CDS_PHYS_NET_NAME" "M_B_DQ<28>"
					( Origin gPackager )
				)
				( attribute "PNN" "M_B_DQ<28>"
					( Origin gPackager )
				)
				( objectStatus "M_B_DQ<28>" )
			)
			( signal "@baseboard_fab2_lib.baseboard_fab2(sch_1):m_b_dq(29)"
				( attribute "CDS_PHYS_NET_NAME" "M_B_DQ<29>"
					( Origin gPackager )
				)
				( attribute "PNN" "M_B_DQ<29>"
					( Origin gPackager )
				)
				( objectStatus "M_B_DQ<29>" )
			)
			( signal "@baseboard_fab2_lib.baseboard_fab2(sch_1):m_b_dq(30)"
				( attribute "CDS_PHYS_NET_NAME" "M_B_DQ<30>"
					( Origin gPackager )
				)
				( attribute "PNN" "M_B_DQ<30>"
					( Origin gPackager )
				)
				( objectStatus "M_B_DQ<30>" )
			)
			( signal "@baseboard_fab2_lib.baseboard_fab2(sch_1):m_b_dq(31)"
				( attribute "CDS_PHYS_NET_NAME" "M_B_DQ<31>"
					( Origin gPackager )
				)
				( attribute "PNN" "M_B_DQ<31>"
					( Origin gPackager )
				)
				( objectStatus "M_B_DQ<31>" )
			)
			( signal "@baseboard_fab2_lib.baseboard_fab2(sch_1):m_b_dq(32)"
				( attribute "CDS_PHYS_NET_NAME" "M_B_DQ<32>"
					( Origin gPackager )
				)
				( attribute "PNN" "M_B_DQ<32>"
					( Origin gPackager )
				)
				( objectStatus "M_B_DQ<32>" )
			)
			( signal "@baseboard_fab2_lib.baseboard_fab2(sch_1):m_b_dq(33)"
				( attribute "CDS_PHYS_NET_NAME" "M_B_DQ<33>"
					( Origin gPackager )
				)
				( attribute "PNN" "M_B_DQ<33>"
					( Origin gPackager )
				)
				( objectStatus "M_B_DQ<33>" )
			)
			( signal "@baseboard_fab2_lib.baseboard_fab2(sch_1):m_b_dq(34)"
				( attribute "CDS_PHYS_NET_NAME" "M_B_DQ<34>"
					( Origin gPackager )
				)
				( attribute "PNN" "M_B_DQ<34>"
					( Origin gPackager )
				)
				( objectStatus "M_B_DQ<34>" )
			)
			( signal "@baseboard_fab2_lib.baseboard_fab2(sch_1):m_b_dq(35)"
				( attribute "CDS_PHYS_NET_NAME" "M_B_DQ<35>"
					( Origin gPackager )
				)
				( attribute "PNN" "M_B_DQ<35>"
					( Origin gPackager )
				)
				( objectStatus "M_B_DQ<35>" )
			)
			( signal "@baseboard_fab2_lib.baseboard_fab2(sch_1):m_b_dq(36)"
				( attribute "CDS_PHYS_NET_NAME" "M_B_DQ<36>"
					( Origin gPackager )
				)
				( attribute "PNN" "M_B_DQ<36>"
					( Origin gPackager )
				)
				( objectStatus "M_B_DQ<36>" )
			)
			( signal "@baseboard_fab2_lib.baseboard_fab2(sch_1):m_b_dq(37)"
				( attribute "CDS_PHYS_NET_NAME" "M_B_DQ<37>"
					( Origin gPackager )
				)
				( attribute "PNN" "M_B_DQ<37>"
					( Origin gPackager )
				)
				( objectStatus "M_B_DQ<37>" )
			)
			( signal "@baseboard_fab2_lib.baseboard_fab2(sch_1):m_b_dq(38)"
				( attribute "CDS_PHYS_NET_NAME" "M_B_DQ<38>"
					( Origin gPackager )
				)
				( attribute "PNN" "M_B_DQ<38>"
					( Origin gPackager )
				)
				( objectStatus "M_B_DQ<38>" )
			)
			( signal "@baseboard_fab2_lib.baseboard_fab2(sch_1):m_b_dq(39)"
				( attribute "CDS_PHYS_NET_NAME" "M_B_DQ<39>"
					( Origin gPackager )
				)
				( attribute "PNN" "M_B_DQ<39>"
					( Origin gPackager )
				)
				( objectStatus "M_B_DQ<39>" )
			)
			( signal "@baseboard_fab2_lib.baseboard_fab2(sch_1):m_b_dq(40)"
				( attribute "CDS_PHYS_NET_NAME" "M_B_DQ<40>"
					( Origin gPackager )
				)
				( attribute "PNN" "M_B_DQ<40>"
					( Origin gPackager )
				)
				( objectStatus "M_B_DQ<40>" )
			)
			( signal "@baseboard_fab2_lib.baseboard_fab2(sch_1):m_b_dq(41)"
				( attribute "CDS_PHYS_NET_NAME" "M_B_DQ<41>"
					( Origin gPackager )
				)
				( attribute "PNN" "M_B_DQ<41>"
					( Origin gPackager )
				)
				( objectStatus "M_B_DQ<41>" )
			)
			( signal "@baseboard_fab2_lib.baseboard_fab2(sch_1):m_b_dq(42)"
				( attribute "CDS_PHYS_NET_NAME" "M_B_DQ<42>"
					( Origin gPackager )
				)
				( attribute "PNN" "M_B_DQ<42>"
					( Origin gPackager )
				)
				( objectStatus "M_B_DQ<42>" )
			)
			( signal "@baseboard_fab2_lib.baseboard_fab2(sch_1):m_b_dq(43)"
				( attribute "CDS_PHYS_NET_NAME" "M_B_DQ<43>"
					( Origin gPackager )
				)
				( attribute "PNN" "M_B_DQ<43>"
					( Origin gPackager )
				)
				( objectStatus "M_B_DQ<43>" )
			)
			( signal "@baseboard_fab2_lib.baseboard_fab2(sch_1):m_b_dq(44)"
				( attribute "CDS_PHYS_NET_NAME" "M_B_DQ<44>"
					( Origin gPackager )
				)
				( attribute "PNN" "M_B_DQ<44>"
					( Origin gPackager )
				)
				( objectStatus "M_B_DQ<44>" )
			)
			( signal "@baseboard_fab2_lib.baseboard_fab2(sch_1):m_b_dq(45)"
				( attribute "CDS_PHYS_NET_NAME" "M_B_DQ<45>"
					( Origin gPackager )
				)
				( attribute "PNN" "M_B_DQ<45>"
					( Origin gPackager )
				)
				( objectStatus "M_B_DQ<45>" )
			)
			( signal "@baseboard_fab2_lib.baseboard_fab2(sch_1):m_b_dq(46)"
				( attribute "CDS_PHYS_NET_NAME" "M_B_DQ<46>"
					( Origin gPackager )
				)
				( attribute "PNN" "M_B_DQ<46>"
					( Origin gPackager )
				)
				( objectStatus "M_B_DQ<46>" )
			)
			( signal "@baseboard_fab2_lib.baseboard_fab2(sch_1):m_b_dq(47)"
				( attribute "CDS_PHYS_NET_NAME" "M_B_DQ<47>"
					( Origin gPackager )
				)
				( attribute "PNN" "M_B_DQ<47>"
					( Origin gPackager )
				)
				( objectStatus "M_B_DQ<47>" )
			)
			( signal "@baseboard_fab2_lib.baseboard_fab2(sch_1):m_b_dq(48)"
				( attribute "CDS_PHYS_NET_NAME" "M_B_DQ<48>"
					( Origin gPackager )
				)
				( attribute "PNN" "M_B_DQ<48>"
					( Origin gPackager )
				)
				( objectStatus "M_B_DQ<48>" )
			)
			( signal "@baseboard_fab2_lib.baseboard_fab2(sch_1):m_b_dq(49)"
				( attribute "CDS_PHYS_NET_NAME" "M_B_DQ<49>"
					( Origin gPackager )
				)
				( attribute "PNN" "M_B_DQ<49>"
					( Origin gPackager )
				)
				( objectStatus "M_B_DQ<49>" )
			)
			( signal "@baseboard_fab2_lib.baseboard_fab2(sch_1):m_b_dq(50)"
				( attribute "CDS_PHYS_NET_NAME" "M_B_DQ<50>"
					( Origin gPackager )
				)
				( attribute "PNN" "M_B_DQ<50>"
					( Origin gPackager )
				)
				( objectStatus "M_B_DQ<50>" )
			)
			( signal "@baseboard_fab2_lib.baseboard_fab2(sch_1):m_b_dq(51)"
				( attribute "CDS_PHYS_NET_NAME" "M_B_DQ<51>"
					( Origin gPackager )
				)
				( attribute "PNN" "M_B_DQ<51>"
					( Origin gPackager )
				)
				( objectStatus "M_B_DQ<51>" )
			)
			( signal "@baseboard_fab2_lib.baseboard_fab2(sch_1):m_b_dq(52)"
				( attribute "CDS_PHYS_NET_NAME" "M_B_DQ<52>"
					( Origin gPackager )
				)
				( attribute "PNN" "M_B_DQ<52>"
					( Origin gPackager )
				)
				( objectStatus "M_B_DQ<52>" )
			)
			( signal "@baseboard_fab2_lib.baseboard_fab2(sch_1):m_b_dq(53)"
				( attribute "CDS_PHYS_NET_NAME" "M_B_DQ<53>"
					( Origin gPackager )
				)
				( attribute "PNN" "M_B_DQ<53>"
					( Origin gPackager )
				)
				( objectStatus "M_B_DQ<53>" )
			)
			( signal "@baseboard_fab2_lib.baseboard_fab2(sch_1):m_b_dq(54)"
				( attribute "CDS_PHYS_NET_NAME" "M_B_DQ<54>"
					( Origin gPackager )
				)
				( attribute "PNN" "M_B_DQ<54>"
					( Origin gPackager )
				)
				( objectStatus "M_B_DQ<54>" )
			)
			( signal "@baseboard_fab2_lib.baseboard_fab2(sch_1):m_b_dq(55)"
				( attribute "CDS_PHYS_NET_NAME" "M_B_DQ<55>"
					( Origin gPackager )
				)
				( attribute "PNN" "M_B_DQ<55>"
					( Origin gPackager )
				)
				( objectStatus "M_B_DQ<55>" )
			)
			( signal "@baseboard_fab2_lib.baseboard_fab2(sch_1):m_b_dq(56)"
				( attribute "CDS_PHYS_NET_NAME" "M_B_DQ<56>"
					( Origin gPackager )
				)
				( attribute "PNN" "M_B_DQ<56>"
					( Origin gPackager )
				)
				( objectStatus "M_B_DQ<56>" )
			)
			( signal "@baseboard_fab2_lib.baseboard_fab2(sch_1):m_b_dq(57)"
				( attribute "CDS_PHYS_NET_NAME" "M_B_DQ<57>"
					( Origin gPackager )
				)
				( attribute "PNN" "M_B_DQ<57>"
					( Origin gPackager )
				)
				( objectStatus "M_B_DQ<57>" )
			)
			( signal "@baseboard_fab2_lib.baseboard_fab2(sch_1):m_b_dq(58)"
				( attribute "CDS_PHYS_NET_NAME" "M_B_DQ<58>"
					( Origin gPackager )
				)
				( attribute "PNN" "M_B_DQ<58>"
					( Origin gPackager )
				)
				( objectStatus "M_B_DQ<58>" )
			)
			( signal "@baseboard_fab2_lib.baseboard_fab2(sch_1):m_b_dq(59)"
				( attribute "CDS_PHYS_NET_NAME" "M_B_DQ<59>"
					( Origin gPackager )
				)
				( attribute "PNN" "M_B_DQ<59>"
					( Origin gPackager )
				)
				( objectStatus "M_B_DQ<59>" )
			)
			( signal "@baseboard_fab2_lib.baseboard_fab2(sch_1):m_b_dq(60)"
				( attribute "CDS_PHYS_NET_NAME" "M_B_DQ<60>"
					( Origin gPackager )
				)
				( attribute "PNN" "M_B_DQ<60>"
					( Origin gPackager )
				)
				( objectStatus "M_B_DQ<60>" )
			)
			( signal "@baseboard_fab2_lib.baseboard_fab2(sch_1):m_b_dq(61)"
				( attribute "CDS_PHYS_NET_NAME" "M_B_DQ<61>"
					( Origin gPackager )
				)
				( attribute "PNN" "M_B_DQ<61>"
					( Origin gPackager )
				)
				( objectStatus "M_B_DQ<61>" )
			)
			( signal "@baseboard_fab2_lib.baseboard_fab2(sch_1):m_b_dq(62)"
				( attribute "CDS_PHYS_NET_NAME" "M_B_DQ<62>"
					( Origin gPackager )
				)
				( attribute "PNN" "M_B_DQ<62>"
					( Origin gPackager )
				)
				( objectStatus "M_B_DQ<62>" )
			)
			( signal "@baseboard_fab2_lib.baseboard_fab2(sch_1):m_b_dq(63)"
				( attribute "CDS_PHYS_NET_NAME" "M_B_DQ<63>"
					( Origin gPackager )
				)
				( attribute "PNN" "M_B_DQ<63>"
					( Origin gPackager )
				)
				( objectStatus "M_B_DQ<63>" )
			)
			( signal "@baseboard_fab2_lib.baseboard_fab2(sch_1):m_b_dqs_dn(0)"
				( attribute "CDS_PHYS_NET_NAME" "M_B_DQS_DN<0>"
					( Origin gPackager )
				)
				( attribute "PNN" "M_B_DQS_DN<0>"
					( Origin gPackager )
				)
				( objectStatus "M_B_DQS_DN<0>" )
			)
			( signal "@baseboard_fab2_lib.baseboard_fab2(sch_1):m_b_dqs_dn(1)"
				( attribute "CDS_PHYS_NET_NAME" "M_B_DQS_DN<1>"
					( Origin gPackager )
				)
				( attribute "PNN" "M_B_DQS_DN<1>"
					( Origin gPackager )
				)
				( objectStatus "M_B_DQS_DN<1>" )
			)
			( signal "@baseboard_fab2_lib.baseboard_fab2(sch_1):m_b_dqs_dn(2)"
				( attribute "CDS_PHYS_NET_NAME" "M_B_DQS_DN<2>"
					( Origin gPackager )
				)
				( attribute "PNN" "M_B_DQS_DN<2>"
					( Origin gPackager )
				)
				( objectStatus "M_B_DQS_DN<2>" )
			)
			( signal "@baseboard_fab2_lib.baseboard_fab2(sch_1):m_b_dqs_dn(3)"
				( attribute "CDS_PHYS_NET_NAME" "M_B_DQS_DN<3>"
					( Origin gPackager )
				)
				( attribute "PNN" "M_B_DQS_DN<3>"
					( Origin gPackager )
				)
				( objectStatus "M_B_DQS_DN<3>" )
			)
			( signal "@baseboard_fab2_lib.baseboard_fab2(sch_1):m_b_dqs_dn(4)"
				( attribute "CDS_PHYS_NET_NAME" "M_B_DQS_DN<4>"
					( Origin gPackager )
				)
				( attribute "PNN" "M_B_DQS_DN<4>"
					( Origin gPackager )
				)
				( objectStatus "M_B_DQS_DN<4>" )
			)
			( signal "@baseboard_fab2_lib.baseboard_fab2(sch_1):m_b_dqs_dn(5)"
				( attribute "CDS_PHYS_NET_NAME" "M_B_DQS_DN<5>"
					( Origin gPackager )
				)
				( attribute "PNN" "M_B_DQS_DN<5>"
					( Origin gPackager )
				)
				( objectStatus "M_B_DQS_DN<5>" )
			)
			( signal "@baseboard_fab2_lib.baseboard_fab2(sch_1):m_b_dqs_dn(6)"
				( attribute "CDS_PHYS_NET_NAME" "M_B_DQS_DN<6>"
					( Origin gPackager )
				)
				( attribute "PNN" "M_B_DQS_DN<6>"
					( Origin gPackager )
				)
				( objectStatus "M_B_DQS_DN<6>" )
			)
			( signal "@baseboard_fab2_lib.baseboard_fab2(sch_1):m_b_dqs_dn(7)"
				( attribute "CDS_PHYS_NET_NAME" "M_B_DQS_DN<7>"
					( Origin gPackager )
				)
				( attribute "PNN" "M_B_DQS_DN<7>"
					( Origin gPackager )
				)
				( objectStatus "M_B_DQS_DN<7>" )
			)
			( signal "@baseboard_fab2_lib.baseboard_fab2(sch_1):m_b_dqs_dn(8)"
				( attribute "CDS_PHYS_NET_NAME" "M_B_DQS_DN<8>"
					( Origin gPackager )
				)
				( attribute "PNN" "M_B_DQS_DN<8>"
					( Origin gPackager )
				)
				( objectStatus "M_B_DQS_DN<8>" )
			)
			( signal "@baseboard_fab2_lib.baseboard_fab2(sch_1):m_b_dqs_dn(9)"
				( attribute "CDS_PHYS_NET_NAME" "M_B_DQS_DN<9>"
					( Origin gPackager )
				)
				( attribute "PNN" "M_B_DQS_DN<9>"
					( Origin gPackager )
				)
				( objectStatus "M_B_DQS_DN<9>" )
			)
			( signal "@baseboard_fab2_lib.baseboard_fab2(sch_1):m_b_dqs_dn(10)"
				( attribute "CDS_PHYS_NET_NAME" "M_B_DQS_DN<10>"
					( Origin gPackager )
				)
				( attribute "PNN" "M_B_DQS_DN<10>"
					( Origin gPackager )
				)
				( objectStatus "M_B_DQS_DN<10>" )
			)
			( signal "@baseboard_fab2_lib.baseboard_fab2(sch_1):m_b_dqs_dn(11)"
				( attribute "CDS_PHYS_NET_NAME" "M_B_DQS_DN<11>"
					( Origin gPackager )
				)
				( attribute "PNN" "M_B_DQS_DN<11>"
					( Origin gPackager )
				)
				( objectStatus "M_B_DQS_DN<11>" )
			)
			( signal "@baseboard_fab2_lib.baseboard_fab2(sch_1):m_b_dqs_dn(12)"
				( attribute "CDS_PHYS_NET_NAME" "M_B_DQS_DN<12>"
					( Origin gPackager )
				)
				( attribute "PNN" "M_B_DQS_DN<12>"
					( Origin gPackager )
				)
				( objectStatus "M_B_DQS_DN<12>" )
			)
			( signal "@baseboard_fab2_lib.baseboard_fab2(sch_1):m_b_dqs_dn(13)"
				( attribute "CDS_PHYS_NET_NAME" "M_B_DQS_DN<13>"
					( Origin gPackager )
				)
				( attribute "PNN" "M_B_DQS_DN<13>"
					( Origin gPackager )
				)
				( objectStatus "M_B_DQS_DN<13>" )
			)
			( signal "@baseboard_fab2_lib.baseboard_fab2(sch_1):m_b_dqs_dn(14)"
				( attribute "CDS_PHYS_NET_NAME" "M_B_DQS_DN<14>"
					( Origin gPackager )
				)
				( attribute "PNN" "M_B_DQS_DN<14>"
					( Origin gPackager )
				)
				( objectStatus "M_B_DQS_DN<14>" )
			)
			( signal "@baseboard_fab2_lib.baseboard_fab2(sch_1):m_b_dqs_dn(15)"
				( attribute "CDS_PHYS_NET_NAME" "M_B_DQS_DN<15>"
					( Origin gPackager )
				)
				( attribute "PNN" "M_B_DQS_DN<15>"
					( Origin gPackager )
				)
				( objectStatus "M_B_DQS_DN<15>" )
			)
			( signal "@baseboard_fab2_lib.baseboard_fab2(sch_1):m_b_dqs_dn(16)"
				( attribute "CDS_PHYS_NET_NAME" "M_B_DQS_DN<16>"
					( Origin gPackager )
				)
				( attribute "PNN" "M_B_DQS_DN<16>"
					( Origin gPackager )
				)
				( objectStatus "M_B_DQS_DN<16>" )
			)
			( signal "@baseboard_fab2_lib.baseboard_fab2(sch_1):m_b_dqs_dn(17)"
				( attribute "CDS_PHYS_NET_NAME" "M_B_DQS_DN<17>"
					( Origin gPackager )
				)
				( attribute "PNN" "M_B_DQS_DN<17>"
					( Origin gPackager )
				)
				( objectStatus "M_B_DQS_DN<17>" )
			)
			( signal "@baseboard_fab2_lib.baseboard_fab2(sch_1):m_b_dqs_dp(0)"
				( attribute "CDS_PHYS_NET_NAME" "M_B_DQS_DP<0>"
					( Origin gPackager )
				)
				( attribute "PNN" "M_B_DQS_DP<0>"
					( Origin gPackager )
				)
				( objectStatus "M_B_DQS_DP<0>" )
			)
			( signal "@baseboard_fab2_lib.baseboard_fab2(sch_1):m_b_dqs_dp(1)"
				( attribute "CDS_PHYS_NET_NAME" "M_B_DQS_DP<1>"
					( Origin gPackager )
				)
				( attribute "PNN" "M_B_DQS_DP<1>"
					( Origin gPackager )
				)
				( objectStatus "M_B_DQS_DP<1>" )
			)
			( signal "@baseboard_fab2_lib.baseboard_fab2(sch_1):m_b_dqs_dp(2)"
				( attribute "CDS_PHYS_NET_NAME" "M_B_DQS_DP<2>"
					( Origin gPackager )
				)
				( attribute "PNN" "M_B_DQS_DP<2>"
					( Origin gPackager )
				)
				( objectStatus "M_B_DQS_DP<2>" )
			)
			( signal "@baseboard_fab2_lib.baseboard_fab2(sch_1):m_b_dqs_dp(3)"
				( attribute "CDS_PHYS_NET_NAME" "M_B_DQS_DP<3>"
					( Origin gPackager )
				)
				( attribute "PNN" "M_B_DQS_DP<3>"
					( Origin gPackager )
				)
				( objectStatus "M_B_DQS_DP<3>" )
			)
			( signal "@baseboard_fab2_lib.baseboard_fab2(sch_1):m_b_dqs_dp(4)"
				( attribute "CDS_PHYS_NET_NAME" "M_B_DQS_DP<4>"
					( Origin gPackager )
				)
				( attribute "PNN" "M_B_DQS_DP<4>"
					( Origin gPackager )
				)
				( objectStatus "M_B_DQS_DP<4>" )
			)
			( signal "@baseboard_fab2_lib.baseboard_fab2(sch_1):m_b_dqs_dp(5)"
				( attribute "CDS_PHYS_NET_NAME" "M_B_DQS_DP<5>"
					( Origin gPackager )
				)
				( attribute "PNN" "M_B_DQS_DP<5>"
					( Origin gPackager )
				)
				( objectStatus "M_B_DQS_DP<5>" )
			)
			( signal "@baseboard_fab2_lib.baseboard_fab2(sch_1):m_b_dqs_dp(6)"
				( attribute "CDS_PHYS_NET_NAME" "M_B_DQS_DP<6>"
					( Origin gPackager )
				)
				( attribute "PNN" "M_B_DQS_DP<6>"
					( Origin gPackager )
				)
				( objectStatus "M_B_DQS_DP<6>" )
			)
			( signal "@baseboard_fab2_lib.baseboard_fab2(sch_1):m_b_dqs_dp(7)"
				( attribute "CDS_PHYS_NET_NAME" "M_B_DQS_DP<7>"
					( Origin gPackager )
				)
				( attribute "PNN" "M_B_DQS_DP<7>"
					( Origin gPackager )
				)
				( objectStatus "M_B_DQS_DP<7>" )
			)
			( signal "@baseboard_fab2_lib.baseboard_fab2(sch_1):m_b_dqs_dp(8)"
				( attribute "CDS_PHYS_NET_NAME" "M_B_DQS_DP<8>"
					( Origin gPackager )
				)
				( attribute "PNN" "M_B_DQS_DP<8>"
					( Origin gPackager )
				)
				( objectStatus "M_B_DQS_DP<8>" )
			)
			( signal "@baseboard_fab2_lib.baseboard_fab2(sch_1):m_b_dqs_dp(9)"
				( attribute "CDS_PHYS_NET_NAME" "M_B_DQS_DP<9>"
					( Origin gPackager )
				)
				( attribute "PNN" "M_B_DQS_DP<9>"
					( Origin gPackager )
				)
				( objectStatus "M_B_DQS_DP<9>" )
			)
			( signal "@baseboard_fab2_lib.baseboard_fab2(sch_1):m_b_dqs_dp(10)"
				( attribute "CDS_PHYS_NET_NAME" "M_B_DQS_DP<10>"
					( Origin gPackager )
				)
				( attribute "PNN" "M_B_DQS_DP<10>"
					( Origin gPackager )
				)
				( objectStatus "M_B_DQS_DP<10>" )
			)
			( signal "@baseboard_fab2_lib.baseboard_fab2(sch_1):m_b_dqs_dp(11)"
				( attribute "CDS_PHYS_NET_NAME" "M_B_DQS_DP<11>"
					( Origin gPackager )
				)
				( attribute "PNN" "M_B_DQS_DP<11>"
					( Origin gPackager )
				)
				( objectStatus "M_B_DQS_DP<11>" )
			)
			( signal "@baseboard_fab2_lib.baseboard_fab2(sch_1):m_b_dqs_dp(12)"
				( attribute "CDS_PHYS_NET_NAME" "M_B_DQS_DP<12>"
					( Origin gPackager )
				)
				( attribute "PNN" "M_B_DQS_DP<12>"
					( Origin gPackager )
				)
				( objectStatus "M_B_DQS_DP<12>" )
			)
			( signal "@baseboard_fab2_lib.baseboard_fab2(sch_1):m_b_dqs_dp(13)"
				( attribute "CDS_PHYS_NET_NAME" "M_B_DQS_DP<13>"
					( Origin gPackager )
				)
				( attribute "PNN" "M_B_DQS_DP<13>"
					( Origin gPackager )
				)
				( objectStatus "M_B_DQS_DP<13>" )
			)
			( signal "@baseboard_fab2_lib.baseboard_fab2(sch_1):m_b_dqs_dp(14)"
				( attribute "CDS_PHYS_NET_NAME" "M_B_DQS_DP<14>"
					( Origin gPackager )
				)
				( attribute "PNN" "M_B_DQS_DP<14>"
					( Origin gPackager )
				)
				( objectStatus "M_B_DQS_DP<14>" )
			)
			( signal "@baseboard_fab2_lib.baseboard_fab2(sch_1):m_b_dqs_dp(15)"
				( attribute "CDS_PHYS_NET_NAME" "M_B_DQS_DP<15>"
					( Origin gPackager )
				)
				( attribute "PNN" "M_B_DQS_DP<15>"
					( Origin gPackager )
				)
				( objectStatus "M_B_DQS_DP<15>" )
			)
			( signal "@baseboard_fab2_lib.baseboard_fab2(sch_1):m_b_dqs_dp(16)"
				( attribute "CDS_PHYS_NET_NAME" "M_B_DQS_DP<16>"
					( Origin gPackager )
				)
				( attribute "PNN" "M_B_DQS_DP<16>"
					( Origin gPackager )
				)
				( objectStatus "M_B_DQS_DP<16>" )
			)
			( signal "@baseboard_fab2_lib.baseboard_fab2(sch_1):m_b_dqs_dp(17)"
				( attribute "CDS_PHYS_NET_NAME" "M_B_DQS_DP<17>"
					( Origin gPackager )
				)
				( attribute "PNN" "M_B_DQS_DP<17>"
					( Origin gPackager )
				)
				( objectStatus "M_B_DQS_DP<17>" )
			)
			( signal "@baseboard_fab2_lib.baseboard_fab2(sch_1):m_b_ecc(0)"
				( attribute "CDS_PHYS_NET_NAME" "M_B_ECC<0>"
					( Origin gPackager )
				)
				( attribute "PNN" "M_B_ECC<0>"
					( Origin gPackager )
				)
				( objectStatus "M_B_ECC<0>" )
			)
			( signal "@baseboard_fab2_lib.baseboard_fab2(sch_1):m_b_ecc(1)"
				( attribute "CDS_PHYS_NET_NAME" "M_B_ECC<1>"
					( Origin gPackager )
				)
				( attribute "PNN" "M_B_ECC<1>"
					( Origin gPackager )
				)
				( objectStatus "M_B_ECC<1>" )
			)
			( signal "@baseboard_fab2_lib.baseboard_fab2(sch_1):m_b_ecc(2)"
				( attribute "CDS_PHYS_NET_NAME" "M_B_ECC<2>"
					( Origin gPackager )
				)
				( attribute "PNN" "M_B_ECC<2>"
					( Origin gPackager )
				)
				( objectStatus "M_B_ECC<2>" )
			)
			( signal "@baseboard_fab2_lib.baseboard_fab2(sch_1):m_b_ecc(3)"
				( attribute "CDS_PHYS_NET_NAME" "M_B_ECC<3>"
					( Origin gPackager )
				)
				( attribute "PNN" "M_B_ECC<3>"
					( Origin gPackager )
				)
				( objectStatus "M_B_ECC<3>" )
			)
			( signal "@baseboard_fab2_lib.baseboard_fab2(sch_1):m_b_ecc(4)"
				( attribute "CDS_PHYS_NET_NAME" "M_B_ECC<4>"
					( Origin gPackager )
				)
				( attribute "PNN" "M_B_ECC<4>"
					( Origin gPackager )
				)
				( objectStatus "M_B_ECC<4>" )
			)
			( signal "@baseboard_fab2_lib.baseboard_fab2(sch_1):m_b_ecc(5)"
				( attribute "CDS_PHYS_NET_NAME" "M_B_ECC<5>"
					( Origin gPackager )
				)
				( attribute "PNN" "M_B_ECC<5>"
					( Origin gPackager )
				)
				( objectStatus "M_B_ECC<5>" )
			)
			( signal "@baseboard_fab2_lib.baseboard_fab2(sch_1):m_b_ecc(6)"
				( attribute "CDS_PHYS_NET_NAME" "M_B_ECC<6>"
					( Origin gPackager )
				)
				( attribute "PNN" "M_B_ECC<6>"
					( Origin gPackager )
				)
				( objectStatus "M_B_ECC<6>" )
			)
			( signal "@baseboard_fab2_lib.baseboard_fab2(sch_1):m_b_ecc(7)"
				( attribute "CDS_PHYS_NET_NAME" "M_B_ECC<7>"
					( Origin gPackager )
				)
				( attribute "PNN" "M_B_ECC<7>"
					( Origin gPackager )
				)
				( objectStatus "M_B_ECC<7>" )
			)
			( signal "@baseboard_fab2_lib.baseboard_fab2(sch_1):m_b_ma(0)"
				( attribute "CDS_PHYS_NET_NAME" "M_B_MA<0>"
					( Origin gPackager )
				)
				( attribute "PNN" "M_B_MA<0>"
					( Origin gPackager )
				)
				( objectStatus "M_B_MA<0>" )
			)
			( signal "@baseboard_fab2_lib.baseboard_fab2(sch_1):m_b_ma(1)"
				( attribute "CDS_PHYS_NET_NAME" "M_B_MA<1>"
					( Origin gPackager )
				)
				( attribute "PNN" "M_B_MA<1>"
					( Origin gPackager )
				)
				( objectStatus "M_B_MA<1>" )
			)
			( signal "@baseboard_fab2_lib.baseboard_fab2(sch_1):m_b_ma(2)"
				( attribute "CDS_PHYS_NET_NAME" "M_B_MA<2>"
					( Origin gPackager )
				)
				( attribute "PNN" "M_B_MA<2>"
					( Origin gPackager )
				)
				( objectStatus "M_B_MA<2>" )
			)
			( signal "@baseboard_fab2_lib.baseboard_fab2(sch_1):m_b_ma(3)"
				( attribute "CDS_PHYS_NET_NAME" "M_B_MA<3>"
					( Origin gPackager )
				)
				( attribute "PNN" "M_B_MA<3>"
					( Origin gPackager )
				)
				( objectStatus "M_B_MA<3>" )
			)
			( signal "@baseboard_fab2_lib.baseboard_fab2(sch_1):m_b_ma(4)"
				( attribute "CDS_PHYS_NET_NAME" "M_B_MA<4>"
					( Origin gPackager )
				)
				( attribute "PNN" "M_B_MA<4>"
					( Origin gPackager )
				)
				( objectStatus "M_B_MA<4>" )
			)
			( signal "@baseboard_fab2_lib.baseboard_fab2(sch_1):m_b_ma(5)"
				( attribute "CDS_PHYS_NET_NAME" "M_B_MA<5>"
					( Origin gPackager )
				)
				( attribute "PNN" "M_B_MA<5>"
					( Origin gPackager )
				)
				( objectStatus "M_B_MA<5>" )
			)
			( signal "@baseboard_fab2_lib.baseboard_fab2(sch_1):m_b_ma(6)"
				( attribute "CDS_PHYS_NET_NAME" "M_B_MA<6>"
					( Origin gPackager )
				)
				( attribute "PNN" "M_B_MA<6>"
					( Origin gPackager )
				)
				( objectStatus "M_B_MA<6>" )
			)
			( signal "@baseboard_fab2_lib.baseboard_fab2(sch_1):m_b_ma(7)"
				( attribute "CDS_PHYS_NET_NAME" "M_B_MA<7>"
					( Origin gPackager )
				)
				( attribute "PNN" "M_B_MA<7>"
					( Origin gPackager )
				)
				( objectStatus "M_B_MA<7>" )
			)
			( signal "@baseboard_fab2_lib.baseboard_fab2(sch_1):m_b_ma(8)"
				( attribute "CDS_PHYS_NET_NAME" "M_B_MA<8>"
					( Origin gPackager )
				)
				( attribute "PNN" "M_B_MA<8>"
					( Origin gPackager )
				)
				( objectStatus "M_B_MA<8>" )
			)
			( signal "@baseboard_fab2_lib.baseboard_fab2(sch_1):m_b_ma(9)"
				( attribute "CDS_PHYS_NET_NAME" "M_B_MA<9>"
					( Origin gPackager )
				)
				( attribute "PNN" "M_B_MA<9>"
					( Origin gPackager )
				)
				( objectStatus "M_B_MA<9>" )
			)
			( signal "@baseboard_fab2_lib.baseboard_fab2(sch_1):m_b_ma(10)"
				( attribute "CDS_PHYS_NET_NAME" "M_B_MA<10>"
					( Origin gPackager )
				)
				( attribute "PNN" "M_B_MA<10>"
					( Origin gPackager )
				)
				( objectStatus "M_B_MA<10>" )
			)
			( signal "@baseboard_fab2_lib.baseboard_fab2(sch_1):m_b_ma(11)"
				( attribute "CDS_PHYS_NET_NAME" "M_B_MA<11>"
					( Origin gPackager )
				)
				( attribute "PNN" "M_B_MA<11>"
					( Origin gPackager )
				)
				( objectStatus "M_B_MA<11>" )
			)
			( signal "@baseboard_fab2_lib.baseboard_fab2(sch_1):m_b_ma(12)"
				( attribute "CDS_PHYS_NET_NAME" "M_B_MA<12>"
					( Origin gPackager )
				)
				( attribute "PNN" "M_B_MA<12>"
					( Origin gPackager )
				)
				( objectStatus "M_B_MA<12>" )
			)
			( signal "@baseboard_fab2_lib.baseboard_fab2(sch_1):m_b_ma(13)"
				( attribute "CDS_PHYS_NET_NAME" "M_B_MA<13>"
					( Origin gPackager )
				)
				( attribute "PNN" "M_B_MA<13>"
					( Origin gPackager )
				)
				( objectStatus "M_B_MA<13>" )
			)
			( signal "@baseboard_fab2_lib.baseboard_fab2(sch_1):m_b_ma(14)"
				( attribute "CDS_PHYS_NET_NAME" "M_B_MA<14>"
					( Origin gPackager )
				)
				( attribute "PNN" "M_B_MA<14>"
					( Origin gPackager )
				)
				( objectStatus "M_B_MA<14>" )
			)
			( signal "@baseboard_fab2_lib.baseboard_fab2(sch_1):m_b_ma(15)"
				( attribute "CDS_PHYS_NET_NAME" "M_B_MA<15>"
					( Origin gPackager )
				)
				( attribute "PNN" "M_B_MA<15>"
					( Origin gPackager )
				)
				( objectStatus "M_B_MA<15>" )
			)
			( signal "@baseboard_fab2_lib.baseboard_fab2(sch_1):m_b_ma(16)"
				( attribute "CDS_PHYS_NET_NAME" "M_B_MA<16>"
					( Origin gPackager )
				)
				( attribute "PNN" "M_B_MA<16>"
					( Origin gPackager )
				)
				( objectStatus "M_B_MA<16>" )
			)
			( signal "@baseboard_fab2_lib.baseboard_fab2(sch_1):m_b_ma(17)"
				( attribute "CDS_PHYS_NET_NAME" "M_B_MA<17>"
					( Origin gPackager )
				)
				( attribute "PNN" "M_B_MA<17>"
					( Origin gPackager )
				)
				( objectStatus "M_B_MA<17>" )
			)
			( signal "@baseboard_fab2_lib.baseboard_fab2(sch_1):m_b_odt(0)"
				( attribute "CDS_PHYS_NET_NAME" "M_B_ODT<0>"
					( Origin gPackager )
				)
				( attribute "PNN" "M_B_ODT<0>"
					( Origin gPackager )
				)
				( objectStatus "M_B_ODT<0>" )
			)
			( signal "@baseboard_fab2_lib.baseboard_fab2(sch_1):m_b_odt(1)"
				( attribute "CDS_PHYS_NET_NAME" "M_B_ODT<1>"
					( Origin gPackager )
				)
				( attribute "PNN" "M_B_ODT<1>"
					( Origin gPackager )
				)
				( objectStatus "M_B_ODT<1>" )
			)
			( signal "@baseboard_fab2_lib.baseboard_fab2(sch_1):m_b_odt(2)"
				( attribute "CDS_PHYS_NET_NAME" "M_B_ODT<2>"
					( Origin gPackager )
				)
				( attribute "PNN" "M_B_ODT<2>"
					( Origin gPackager )
				)
				( objectStatus "M_B_ODT<2>" )
			)
			( signal "@baseboard_fab2_lib.baseboard_fab2(sch_1):m_b_odt(3)"
				( attribute "CDS_PHYS_NET_NAME" "M_B_ODT<3>"
					( Origin gPackager )
				)
				( attribute "PNN" "M_B_ODT<3>"
					( Origin gPackager )
				)
				( objectStatus "M_B_ODT<3>" )
			)
			( signal "@baseboard_fab2_lib.baseboard_fab2(sch_1):m_b_par"
				( attribute "CDS_PHYS_NET_NAME" "M_B_PAR"
					( Origin gPackager )
				)
				( objectStatus "M_B_PAR" )
			)
			( signal "@baseboard_fab2_lib.baseboard_fab2(sch_1):m_c_act_n"
				( attribute "CDS_PHYS_NET_NAME" "M_C_ACT_N"
					( Origin gPackager )
				)
				( objectStatus "M_C_ACT_N" )
			)
			( signal "@baseboard_fab2_lib.baseboard_fab2(sch_1):m_c_alert_n"
				( attribute "CDS_PHYS_NET_NAME" "M_C_ALERT_N"
					( Origin gPackager )
				)
				( objectStatus "M_C_ALERT_N" )
			)
			( signal "@baseboard_fab2_lib.baseboard_fab2(sch_1):m_c_ba(0)"
				( attribute "CDS_PHYS_NET_NAME" "M_C_BA<0>"
					( Origin gPackager )
				)
				( attribute "PNN" "M_C_BA<0>"
					( Origin gPackager )
				)
				( objectStatus "M_C_BA<0>" )
			)
			( signal "@baseboard_fab2_lib.baseboard_fab2(sch_1):m_c_ba(1)"
				( attribute "CDS_PHYS_NET_NAME" "M_C_BA<1>"
					( Origin gPackager )
				)
				( attribute "PNN" "M_C_BA<1>"
					( Origin gPackager )
				)
				( objectStatus "M_C_BA<1>" )
			)
			( signal "@baseboard_fab2_lib.baseboard_fab2(sch_1):m_c_bg(0)"
				( attribute "CDS_PHYS_NET_NAME" "M_C_BG<0>"
					( Origin gPackager )
				)
				( attribute "PNN" "M_C_BG<0>"
					( Origin gPackager )
				)
				( objectStatus "M_C_BG<0>" )
			)
			( signal "@baseboard_fab2_lib.baseboard_fab2(sch_1):m_c_bg(1)"
				( attribute "CDS_PHYS_NET_NAME" "M_C_BG<1>"
					( Origin gPackager )
				)
				( attribute "PNN" "M_C_BG<1>"
					( Origin gPackager )
				)
				( objectStatus "M_C_BG<1>" )
			)
			( signal "@baseboard_fab2_lib.baseboard_fab2(sch_1):m_c_c(2)"
				( attribute "CDS_PHYS_NET_NAME" "M_C_C<2>"
					( Origin gPackager )
				)
				( attribute "PNN" "M_C_C<2>"
					( Origin gPackager )
				)
				( objectStatus "M_C_C<2>" )
			)
			( signal "@baseboard_fab2_lib.baseboard_fab2(sch_1):m_c_cke(0)"
				( attribute "CDS_PHYS_NET_NAME" "M_C_CKE<0>"
					( Origin gPackager )
				)
				( attribute "PNN" "M_C_CKE<0>"
					( Origin gPackager )
				)
				( objectStatus "M_C_CKE<0>" )
			)
			( signal "@baseboard_fab2_lib.baseboard_fab2(sch_1):m_c_cke(1)"
				( attribute "CDS_PHYS_NET_NAME" "M_C_CKE<1>"
					( Origin gPackager )
				)
				( attribute "PNN" "M_C_CKE<1>"
					( Origin gPackager )
				)
				( objectStatus "M_C_CKE<1>" )
			)
			( signal "@baseboard_fab2_lib.baseboard_fab2(sch_1):m_c_cke(2)"
				( attribute "CDS_PHYS_NET_NAME" "M_C_CKE<2>"
					( Origin gPackager )
				)
				( attribute "PNN" "M_C_CKE<2>"
					( Origin gPackager )
				)
				( objectStatus "M_C_CKE<2>" )
			)
			( signal "@baseboard_fab2_lib.baseboard_fab2(sch_1):m_c_cke(3)"
				( attribute "CDS_PHYS_NET_NAME" "M_C_CKE<3>"
					( Origin gPackager )
				)
				( attribute "PNN" "M_C_CKE<3>"
					( Origin gPackager )
				)
				( objectStatus "M_C_CKE<3>" )
			)
			( signal "@baseboard_fab2_lib.baseboard_fab2(sch_1):m_c_clk_dn(0)"
				( attribute "CDS_PHYS_NET_NAME" "M_C_CLK_DN<0>"
					( Origin gPackager )
				)
				( attribute "PNN" "M_C_CLK_DN<0>"
					( Origin gPackager )
				)
				( objectStatus "M_C_CLK_DN<0>" )
			)
			( signal "@baseboard_fab2_lib.baseboard_fab2(sch_1):m_c_clk_dn(1)"
				( attribute "CDS_PHYS_NET_NAME" "M_C_CLK_DN<1>"
					( Origin gPackager )
				)
				( attribute "PNN" "M_C_CLK_DN<1>"
					( Origin gPackager )
				)
				( objectStatus "M_C_CLK_DN<1>" )
			)
			( signal "@baseboard_fab2_lib.baseboard_fab2(sch_1):m_c_clk_dn(2)"
				( attribute "CDS_PHYS_NET_NAME" "M_C_CLK_DN<2>"
					( Origin gPackager )
				)
				( attribute "PNN" "M_C_CLK_DN<2>"
					( Origin gPackager )
				)
				( objectStatus "M_C_CLK_DN<2>" )
			)
			( signal "@baseboard_fab2_lib.baseboard_fab2(sch_1):m_c_clk_dn(3)"
				( attribute "CDS_PHYS_NET_NAME" "M_C_CLK_DN<3>"
					( Origin gPackager )
				)
				( attribute "PNN" "M_C_CLK_DN<3>"
					( Origin gPackager )
				)
				( objectStatus "M_C_CLK_DN<3>" )
			)
			( signal "@baseboard_fab2_lib.baseboard_fab2(sch_1):m_c_clk_dp(0)"
				( attribute "CDS_PHYS_NET_NAME" "M_C_CLK_DP<0>"
					( Origin gPackager )
				)
				( attribute "PNN" "M_C_CLK_DP<0>"
					( Origin gPackager )
				)
				( objectStatus "M_C_CLK_DP<0>" )
			)
			( signal "@baseboard_fab2_lib.baseboard_fab2(sch_1):m_c_clk_dp(1)"
				( attribute "CDS_PHYS_NET_NAME" "M_C_CLK_DP<1>"
					( Origin gPackager )
				)
				( attribute "PNN" "M_C_CLK_DP<1>"
					( Origin gPackager )
				)
				( objectStatus "M_C_CLK_DP<1>" )
			)
			( signal "@baseboard_fab2_lib.baseboard_fab2(sch_1):m_c_clk_dp(2)"
				( attribute "CDS_PHYS_NET_NAME" "M_C_CLK_DP<2>"
					( Origin gPackager )
				)
				( attribute "PNN" "M_C_CLK_DP<2>"
					( Origin gPackager )
				)
				( objectStatus "M_C_CLK_DP<2>" )
			)
			( signal "@baseboard_fab2_lib.baseboard_fab2(sch_1):m_c_clk_dp(3)"
				( attribute "CDS_PHYS_NET_NAME" "M_C_CLK_DP<3>"
					( Origin gPackager )
				)
				( attribute "PNN" "M_C_CLK_DP<3>"
					( Origin gPackager )
				)
				( objectStatus "M_C_CLK_DP<3>" )
			)
			( signal "@baseboard_fab2_lib.baseboard_fab2(sch_1):m_c_cs_n(0)"
				( attribute "CDS_PHYS_NET_NAME" "M_C_CS_N<0>"
					( Origin gPackager )
				)
				( attribute "PNN" "M_C_CS_N<0>"
					( Origin gPackager )
				)
				( objectStatus "M_C_CS_N<0>" )
			)
			( signal "@baseboard_fab2_lib.baseboard_fab2(sch_1):m_c_cs_n(1)"
				( attribute "CDS_PHYS_NET_NAME" "M_C_CS_N<1>"
					( Origin gPackager )
				)
				( attribute "PNN" "M_C_CS_N<1>"
					( Origin gPackager )
				)
				( objectStatus "M_C_CS_N<1>" )
			)
			( signal "@baseboard_fab2_lib.baseboard_fab2(sch_1):m_c_cs_n(2)"
				( attribute "CDS_PHYS_NET_NAME" "M_C_CS_N<2>"
					( Origin gPackager )
				)
				( attribute "PNN" "M_C_CS_N<2>"
					( Origin gPackager )
				)
				( objectStatus "M_C_CS_N<2>" )
			)
			( signal "@baseboard_fab2_lib.baseboard_fab2(sch_1):m_c_cs_n(3)"
				( attribute "CDS_PHYS_NET_NAME" "M_C_CS_N<3>"
					( Origin gPackager )
				)
				( attribute "PNN" "M_C_CS_N<3>"
					( Origin gPackager )
				)
				( objectStatus "M_C_CS_N<3>" )
			)
			( signal "@baseboard_fab2_lib.baseboard_fab2(sch_1):m_c_cs_n(4)"
				( attribute "CDS_PHYS_NET_NAME" "M_C_CS_N<4>"
					( Origin gPackager )
				)
				( attribute "PNN" "M_C_CS_N<4>"
					( Origin gPackager )
				)
				( objectStatus "M_C_CS_N<4>" )
			)
			( signal "@baseboard_fab2_lib.baseboard_fab2(sch_1):m_c_cs_n(5)"
				( attribute "CDS_PHYS_NET_NAME" "M_C_CS_N<5>"
					( Origin gPackager )
				)
				( attribute "PNN" "M_C_CS_N<5>"
					( Origin gPackager )
				)
				( objectStatus "M_C_CS_N<5>" )
			)
			( signal "@baseboard_fab2_lib.baseboard_fab2(sch_1):m_c_cs_n(6)"
				( attribute "CDS_PHYS_NET_NAME" "M_C_CS_N<6>"
					( Origin gPackager )
				)
				( attribute "PNN" "M_C_CS_N<6>"
					( Origin gPackager )
				)
				( objectStatus "M_C_CS_N<6>" )
			)
			( signal "@baseboard_fab2_lib.baseboard_fab2(sch_1):m_c_cs_n(7)"
				( attribute "CDS_PHYS_NET_NAME" "M_C_CS_N<7>"
					( Origin gPackager )
				)
				( attribute "PNN" "M_C_CS_N<7>"
					( Origin gPackager )
				)
				( objectStatus "M_C_CS_N<7>" )
			)
			( signal "@baseboard_fab2_lib.baseboard_fab2(sch_1):m_c_dq(0)"
				( attribute "CDS_PHYS_NET_NAME" "M_C_DQ<0>"
					( Origin gPackager )
				)
				( attribute "PNN" "M_C_DQ<0>"
					( Origin gPackager )
				)
				( objectStatus "M_C_DQ<0>" )
			)
			( signal "@baseboard_fab2_lib.baseboard_fab2(sch_1):m_c_dq(1)"
				( attribute "CDS_PHYS_NET_NAME" "M_C_DQ<1>"
					( Origin gPackager )
				)
				( attribute "PNN" "M_C_DQ<1>"
					( Origin gPackager )
				)
				( objectStatus "M_C_DQ<1>" )
			)
			( signal "@baseboard_fab2_lib.baseboard_fab2(sch_1):m_c_dq(2)"
				( attribute "CDS_PHYS_NET_NAME" "M_C_DQ<2>"
					( Origin gPackager )
				)
				( attribute "PNN" "M_C_DQ<2>"
					( Origin gPackager )
				)
				( objectStatus "M_C_DQ<2>" )
			)
			( signal "@baseboard_fab2_lib.baseboard_fab2(sch_1):m_c_dq(3)"
				( attribute "CDS_PHYS_NET_NAME" "M_C_DQ<3>"
					( Origin gPackager )
				)
				( attribute "PNN" "M_C_DQ<3>"
					( Origin gPackager )
				)
				( objectStatus "M_C_DQ<3>" )
			)
			( signal "@baseboard_fab2_lib.baseboard_fab2(sch_1):m_c_dq(4)"
				( attribute "CDS_PHYS_NET_NAME" "M_C_DQ<4>"
					( Origin gPackager )
				)
				( attribute "PNN" "M_C_DQ<4>"
					( Origin gPackager )
				)
				( objectStatus "M_C_DQ<4>" )
			)
			( signal "@baseboard_fab2_lib.baseboard_fab2(sch_1):m_c_dq(5)"
				( attribute "CDS_PHYS_NET_NAME" "M_C_DQ<5>"
					( Origin gPackager )
				)
				( attribute "PNN" "M_C_DQ<5>"
					( Origin gPackager )
				)
				( objectStatus "M_C_DQ<5>" )
			)
			( signal "@baseboard_fab2_lib.baseboard_fab2(sch_1):m_c_dq(6)"
				( attribute "CDS_PHYS_NET_NAME" "M_C_DQ<6>"
					( Origin gPackager )
				)
				( attribute "PNN" "M_C_DQ<6>"
					( Origin gPackager )
				)
				( objectStatus "M_C_DQ<6>" )
			)
			( signal "@baseboard_fab2_lib.baseboard_fab2(sch_1):m_c_dq(7)"
				( attribute "CDS_PHYS_NET_NAME" "M_C_DQ<7>"
					( Origin gPackager )
				)
				( attribute "PNN" "M_C_DQ<7>"
					( Origin gPackager )
				)
				( objectStatus "M_C_DQ<7>" )
			)
			( signal "@baseboard_fab2_lib.baseboard_fab2(sch_1):m_c_dq(8)"
				( attribute "CDS_PHYS_NET_NAME" "M_C_DQ<8>"
					( Origin gPackager )
				)
				( attribute "PNN" "M_C_DQ<8>"
					( Origin gPackager )
				)
				( objectStatus "M_C_DQ<8>" )
			)
			( signal "@baseboard_fab2_lib.baseboard_fab2(sch_1):m_c_dq(9)"
				( attribute "CDS_PHYS_NET_NAME" "M_C_DQ<9>"
					( Origin gPackager )
				)
				( attribute "PNN" "M_C_DQ<9>"
					( Origin gPackager )
				)
				( objectStatus "M_C_DQ<9>" )
			)
			( signal "@baseboard_fab2_lib.baseboard_fab2(sch_1):m_c_dq(10)"
				( attribute "CDS_PHYS_NET_NAME" "M_C_DQ<10>"
					( Origin gPackager )
				)
				( attribute "PNN" "M_C_DQ<10>"
					( Origin gPackager )
				)
				( objectStatus "M_C_DQ<10>" )
			)
			( signal "@baseboard_fab2_lib.baseboard_fab2(sch_1):m_c_dq(11)"
				( attribute "CDS_PHYS_NET_NAME" "M_C_DQ<11>"
					( Origin gPackager )
				)
				( attribute "PNN" "M_C_DQ<11>"
					( Origin gPackager )
				)
				( objectStatus "M_C_DQ<11>" )
			)
			( signal "@baseboard_fab2_lib.baseboard_fab2(sch_1):m_c_dq(12)"
				( attribute "CDS_PHYS_NET_NAME" "M_C_DQ<12>"
					( Origin gPackager )
				)
				( attribute "PNN" "M_C_DQ<12>"
					( Origin gPackager )
				)
				( objectStatus "M_C_DQ<12>" )
			)
			( signal "@baseboard_fab2_lib.baseboard_fab2(sch_1):m_c_dq(13)"
				( attribute "CDS_PHYS_NET_NAME" "M_C_DQ<13>"
					( Origin gPackager )
				)
				( attribute "PNN" "M_C_DQ<13>"
					( Origin gPackager )
				)
				( objectStatus "M_C_DQ<13>" )
			)
			( signal "@baseboard_fab2_lib.baseboard_fab2(sch_1):m_c_dq(14)"
				( attribute "CDS_PHYS_NET_NAME" "M_C_DQ<14>"
					( Origin gPackager )
				)
				( attribute "PNN" "M_C_DQ<14>"
					( Origin gPackager )
				)
				( objectStatus "M_C_DQ<14>" )
			)
			( signal "@baseboard_fab2_lib.baseboard_fab2(sch_1):m_c_dq(15)"
				( attribute "CDS_PHYS_NET_NAME" "M_C_DQ<15>"
					( Origin gPackager )
				)
				( attribute "PNN" "M_C_DQ<15>"
					( Origin gPackager )
				)
				( objectStatus "M_C_DQ<15>" )
			)
			( signal "@baseboard_fab2_lib.baseboard_fab2(sch_1):m_c_dq(16)"
				( attribute "CDS_PHYS_NET_NAME" "M_C_DQ<16>"
					( Origin gPackager )
				)
				( attribute "PNN" "M_C_DQ<16>"
					( Origin gPackager )
				)
				( objectStatus "M_C_DQ<16>" )
			)
			( signal "@baseboard_fab2_lib.baseboard_fab2(sch_1):m_c_dq(17)"
				( attribute "CDS_PHYS_NET_NAME" "M_C_DQ<17>"
					( Origin gPackager )
				)
				( attribute "PNN" "M_C_DQ<17>"
					( Origin gPackager )
				)
				( objectStatus "M_C_DQ<17>" )
			)
			( signal "@baseboard_fab2_lib.baseboard_fab2(sch_1):m_c_dq(18)"
				( attribute "CDS_PHYS_NET_NAME" "M_C_DQ<18>"
					( Origin gPackager )
				)
				( attribute "PNN" "M_C_DQ<18>"
					( Origin gPackager )
				)
				( objectStatus "M_C_DQ<18>" )
			)
			( signal "@baseboard_fab2_lib.baseboard_fab2(sch_1):m_c_dq(19)"
				( attribute "CDS_PHYS_NET_NAME" "M_C_DQ<19>"
					( Origin gPackager )
				)
				( attribute "PNN" "M_C_DQ<19>"
					( Origin gPackager )
				)
				( objectStatus "M_C_DQ<19>" )
			)
			( signal "@baseboard_fab2_lib.baseboard_fab2(sch_1):m_c_dq(20)"
				( attribute "CDS_PHYS_NET_NAME" "M_C_DQ<20>"
					( Origin gPackager )
				)
				( attribute "PNN" "M_C_DQ<20>"
					( Origin gPackager )
				)
				( objectStatus "M_C_DQ<20>" )
			)
			( signal "@baseboard_fab2_lib.baseboard_fab2(sch_1):m_c_dq(21)"
				( attribute "CDS_PHYS_NET_NAME" "M_C_DQ<21>"
					( Origin gPackager )
				)
				( attribute "PNN" "M_C_DQ<21>"
					( Origin gPackager )
				)
				( objectStatus "M_C_DQ<21>" )
			)
			( signal "@baseboard_fab2_lib.baseboard_fab2(sch_1):m_c_dq(22)"
				( attribute "CDS_PHYS_NET_NAME" "M_C_DQ<22>"
					( Origin gPackager )
				)
				( attribute "PNN" "M_C_DQ<22>"
					( Origin gPackager )
				)
				( objectStatus "M_C_DQ<22>" )
			)
			( signal "@baseboard_fab2_lib.baseboard_fab2(sch_1):m_c_dq(23)"
				( attribute "CDS_PHYS_NET_NAME" "M_C_DQ<23>"
					( Origin gPackager )
				)
				( attribute "PNN" "M_C_DQ<23>"
					( Origin gPackager )
				)
				( objectStatus "M_C_DQ<23>" )
			)
			( signal "@baseboard_fab2_lib.baseboard_fab2(sch_1):m_c_dq(24)"
				( attribute "CDS_PHYS_NET_NAME" "M_C_DQ<24>"
					( Origin gPackager )
				)
				( attribute "PNN" "M_C_DQ<24>"
					( Origin gPackager )
				)
				( objectStatus "M_C_DQ<24>" )
			)
			( signal "@baseboard_fab2_lib.baseboard_fab2(sch_1):m_c_dq(25)"
				( attribute "CDS_PHYS_NET_NAME" "M_C_DQ<25>"
					( Origin gPackager )
				)
				( attribute "PNN" "M_C_DQ<25>"
					( Origin gPackager )
				)
				( objectStatus "M_C_DQ<25>" )
			)
			( signal "@baseboard_fab2_lib.baseboard_fab2(sch_1):m_c_dq(26)"
				( attribute "CDS_PHYS_NET_NAME" "M_C_DQ<26>"
					( Origin gPackager )
				)
				( attribute "PNN" "M_C_DQ<26>"
					( Origin gPackager )
				)
				( objectStatus "M_C_DQ<26>" )
			)
			( signal "@baseboard_fab2_lib.baseboard_fab2(sch_1):m_c_dq(27)"
				( attribute "CDS_PHYS_NET_NAME" "M_C_DQ<27>"
					( Origin gPackager )
				)
				( attribute "PNN" "M_C_DQ<27>"
					( Origin gPackager )
				)
				( objectStatus "M_C_DQ<27>" )
			)
			( signal "@baseboard_fab2_lib.baseboard_fab2(sch_1):m_c_dq(28)"
				( attribute "CDS_PHYS_NET_NAME" "M_C_DQ<28>"
					( Origin gPackager )
				)
				( attribute "PNN" "M_C_DQ<28>"
					( Origin gPackager )
				)
				( objectStatus "M_C_DQ<28>" )
			)
			( signal "@baseboard_fab2_lib.baseboard_fab2(sch_1):m_c_dq(29)"
				( attribute "CDS_PHYS_NET_NAME" "M_C_DQ<29>"
					( Origin gPackager )
				)
				( attribute "PNN" "M_C_DQ<29>"
					( Origin gPackager )
				)
				( objectStatus "M_C_DQ<29>" )
			)
			( signal "@baseboard_fab2_lib.baseboard_fab2(sch_1):m_c_dq(30)"
				( attribute "CDS_PHYS_NET_NAME" "M_C_DQ<30>"
					( Origin gPackager )
				)
				( attribute "PNN" "M_C_DQ<30>"
					( Origin gPackager )
				)
				( objectStatus "M_C_DQ<30>" )
			)
			( signal "@baseboard_fab2_lib.baseboard_fab2(sch_1):m_c_dq(31)"
				( attribute "CDS_PHYS_NET_NAME" "M_C_DQ<31>"
					( Origin gPackager )
				)
				( attribute "PNN" "M_C_DQ<31>"
					( Origin gPackager )
				)
				( objectStatus "M_C_DQ<31>" )
			)
			( signal "@baseboard_fab2_lib.baseboard_fab2(sch_1):m_c_dq(32)"
				( attribute "CDS_PHYS_NET_NAME" "M_C_DQ<32>"
					( Origin gPackager )
				)
				( attribute "PNN" "M_C_DQ<32>"
					( Origin gPackager )
				)
				( objectStatus "M_C_DQ<32>" )
			)
			( signal "@baseboard_fab2_lib.baseboard_fab2(sch_1):m_c_dq(33)"
				( attribute "CDS_PHYS_NET_NAME" "M_C_DQ<33>"
					( Origin gPackager )
				)
				( attribute "PNN" "M_C_DQ<33>"
					( Origin gPackager )
				)
				( objectStatus "M_C_DQ<33>" )
			)
			( signal "@baseboard_fab2_lib.baseboard_fab2(sch_1):m_c_dq(34)"
				( attribute "CDS_PHYS_NET_NAME" "M_C_DQ<34>"
					( Origin gPackager )
				)
				( attribute "PNN" "M_C_DQ<34>"
					( Origin gPackager )
				)
				( objectStatus "M_C_DQ<34>" )
			)
			( signal "@baseboard_fab2_lib.baseboard_fab2(sch_1):m_c_dq(35)"
				( attribute "CDS_PHYS_NET_NAME" "M_C_DQ<35>"
					( Origin gPackager )
				)
				( attribute "PNN" "M_C_DQ<35>"
					( Origin gPackager )
				)
				( objectStatus "M_C_DQ<35>" )
			)
			( signal "@baseboard_fab2_lib.baseboard_fab2(sch_1):m_c_dq(36)"
				( attribute "CDS_PHYS_NET_NAME" "M_C_DQ<36>"
					( Origin gPackager )
				)
				( attribute "PNN" "M_C_DQ<36>"
					( Origin gPackager )
				)
				( objectStatus "M_C_DQ<36>" )
			)
			( signal "@baseboard_fab2_lib.baseboard_fab2(sch_1):m_c_dq(37)"
				( attribute "CDS_PHYS_NET_NAME" "M_C_DQ<37>"
					( Origin gPackager )
				)
				( attribute "PNN" "M_C_DQ<37>"
					( Origin gPackager )
				)
				( objectStatus "M_C_DQ<37>" )
			)
			( signal "@baseboard_fab2_lib.baseboard_fab2(sch_1):m_c_dq(38)"
				( attribute "CDS_PHYS_NET_NAME" "M_C_DQ<38>"
					( Origin gPackager )
				)
				( attribute "PNN" "M_C_DQ<38>"
					( Origin gPackager )
				)
				( objectStatus "M_C_DQ<38>" )
			)
			( signal "@baseboard_fab2_lib.baseboard_fab2(sch_1):m_c_dq(39)"
				( attribute "CDS_PHYS_NET_NAME" "M_C_DQ<39>"
					( Origin gPackager )
				)
				( attribute "PNN" "M_C_DQ<39>"
					( Origin gPackager )
				)
				( objectStatus "M_C_DQ<39>" )
			)
			( signal "@baseboard_fab2_lib.baseboard_fab2(sch_1):m_c_dq(40)"
				( attribute "CDS_PHYS_NET_NAME" "M_C_DQ<40>"
					( Origin gPackager )
				)
				( attribute "PNN" "M_C_DQ<40>"
					( Origin gPackager )
				)
				( objectStatus "M_C_DQ<40>" )
			)
			( signal "@baseboard_fab2_lib.baseboard_fab2(sch_1):m_c_dq(41)"
				( attribute "CDS_PHYS_NET_NAME" "M_C_DQ<41>"
					( Origin gPackager )
				)
				( attribute "PNN" "M_C_DQ<41>"
					( Origin gPackager )
				)
				( objectStatus "M_C_DQ<41>" )
			)
			( signal "@baseboard_fab2_lib.baseboard_fab2(sch_1):m_c_dq(42)"
				( attribute "CDS_PHYS_NET_NAME" "M_C_DQ<42>"
					( Origin gPackager )
				)
				( attribute "PNN" "M_C_DQ<42>"
					( Origin gPackager )
				)
				( objectStatus "M_C_DQ<42>" )
			)
			( signal "@baseboard_fab2_lib.baseboard_fab2(sch_1):m_c_dq(43)"
				( attribute "CDS_PHYS_NET_NAME" "M_C_DQ<43>"
					( Origin gPackager )
				)
				( attribute "PNN" "M_C_DQ<43>"
					( Origin gPackager )
				)
				( objectStatus "M_C_DQ<43>" )
			)
			( signal "@baseboard_fab2_lib.baseboard_fab2(sch_1):m_c_dq(44)"
				( attribute "CDS_PHYS_NET_NAME" "M_C_DQ<44>"
					( Origin gPackager )
				)
				( attribute "PNN" "M_C_DQ<44>"
					( Origin gPackager )
				)
				( objectStatus "M_C_DQ<44>" )
			)
			( signal "@baseboard_fab2_lib.baseboard_fab2(sch_1):m_c_dq(45)"
				( attribute "CDS_PHYS_NET_NAME" "M_C_DQ<45>"
					( Origin gPackager )
				)
				( attribute "PNN" "M_C_DQ<45>"
					( Origin gPackager )
				)
				( objectStatus "M_C_DQ<45>" )
			)
			( signal "@baseboard_fab2_lib.baseboard_fab2(sch_1):m_c_dq(46)"
				( attribute "CDS_PHYS_NET_NAME" "M_C_DQ<46>"
					( Origin gPackager )
				)
				( attribute "PNN" "M_C_DQ<46>"
					( Origin gPackager )
				)
				( objectStatus "M_C_DQ<46>" )
			)
			( signal "@baseboard_fab2_lib.baseboard_fab2(sch_1):m_c_dq(47)"
				( attribute "CDS_PHYS_NET_NAME" "M_C_DQ<47>"
					( Origin gPackager )
				)
				( attribute "PNN" "M_C_DQ<47>"
					( Origin gPackager )
				)
				( objectStatus "M_C_DQ<47>" )
			)
			( signal "@baseboard_fab2_lib.baseboard_fab2(sch_1):m_c_dq(48)"
				( attribute "CDS_PHYS_NET_NAME" "M_C_DQ<48>"
					( Origin gPackager )
				)
				( attribute "PNN" "M_C_DQ<48>"
					( Origin gPackager )
				)
				( objectStatus "M_C_DQ<48>" )
			)
			( signal "@baseboard_fab2_lib.baseboard_fab2(sch_1):m_c_dq(49)"
				( attribute "CDS_PHYS_NET_NAME" "M_C_DQ<49>"
					( Origin gPackager )
				)
				( attribute "PNN" "M_C_DQ<49>"
					( Origin gPackager )
				)
				( objectStatus "M_C_DQ<49>" )
			)
			( signal "@baseboard_fab2_lib.baseboard_fab2(sch_1):m_c_dq(50)"
				( attribute "CDS_PHYS_NET_NAME" "M_C_DQ<50>"
					( Origin gPackager )
				)
				( attribute "PNN" "M_C_DQ<50>"
					( Origin gPackager )
				)
				( objectStatus "M_C_DQ<50>" )
			)
			( signal "@baseboard_fab2_lib.baseboard_fab2(sch_1):m_c_dq(51)"
				( attribute "CDS_PHYS_NET_NAME" "M_C_DQ<51>"
					( Origin gPackager )
				)
				( attribute "PNN" "M_C_DQ<51>"
					( Origin gPackager )
				)
				( objectStatus "M_C_DQ<51>" )
			)
			( signal "@baseboard_fab2_lib.baseboard_fab2(sch_1):m_c_dq(52)"
				( attribute "CDS_PHYS_NET_NAME" "M_C_DQ<52>"
					( Origin gPackager )
				)
				( attribute "PNN" "M_C_DQ<52>"
					( Origin gPackager )
				)
				( objectStatus "M_C_DQ<52>" )
			)
			( signal "@baseboard_fab2_lib.baseboard_fab2(sch_1):m_c_dq(53)"
				( attribute "CDS_PHYS_NET_NAME" "M_C_DQ<53>"
					( Origin gPackager )
				)
				( attribute "PNN" "M_C_DQ<53>"
					( Origin gPackager )
				)
				( objectStatus "M_C_DQ<53>" )
			)
			( signal "@baseboard_fab2_lib.baseboard_fab2(sch_1):m_c_dq(54)"
				( attribute "CDS_PHYS_NET_NAME" "M_C_DQ<54>"
					( Origin gPackager )
				)
				( attribute "PNN" "M_C_DQ<54>"
					( Origin gPackager )
				)
				( objectStatus "M_C_DQ<54>" )
			)
			( signal "@baseboard_fab2_lib.baseboard_fab2(sch_1):m_c_dq(55)"
				( attribute "CDS_PHYS_NET_NAME" "M_C_DQ<55>"
					( Origin gPackager )
				)
				( attribute "PNN" "M_C_DQ<55>"
					( Origin gPackager )
				)
				( objectStatus "M_C_DQ<55>" )
			)
			( signal "@baseboard_fab2_lib.baseboard_fab2(sch_1):m_c_dq(56)"
				( attribute "CDS_PHYS_NET_NAME" "M_C_DQ<56>"
					( Origin gPackager )
				)
				( attribute "PNN" "M_C_DQ<56>"
					( Origin gPackager )
				)
				( objectStatus "M_C_DQ<56>" )
			)
			( signal "@baseboard_fab2_lib.baseboard_fab2(sch_1):m_c_dq(57)"
				( attribute "CDS_PHYS_NET_NAME" "M_C_DQ<57>"
					( Origin gPackager )
				)
				( attribute "PNN" "M_C_DQ<57>"
					( Origin gPackager )
				)
				( objectStatus "M_C_DQ<57>" )
			)
			( signal "@baseboard_fab2_lib.baseboard_fab2(sch_1):m_c_dq(58)"
				( attribute "CDS_PHYS_NET_NAME" "M_C_DQ<58>"
					( Origin gPackager )
				)
				( attribute "PNN" "M_C_DQ<58>"
					( Origin gPackager )
				)
				( objectStatus "M_C_DQ<58>" )
			)
			( signal "@baseboard_fab2_lib.baseboard_fab2(sch_1):m_c_dq(59)"
				( attribute "CDS_PHYS_NET_NAME" "M_C_DQ<59>"
					( Origin gPackager )
				)
				( attribute "PNN" "M_C_DQ<59>"
					( Origin gPackager )
				)
				( objectStatus "M_C_DQ<59>" )
			)
			( signal "@baseboard_fab2_lib.baseboard_fab2(sch_1):m_c_dq(60)"
				( attribute "CDS_PHYS_NET_NAME" "M_C_DQ<60>"
					( Origin gPackager )
				)
				( attribute "PNN" "M_C_DQ<60>"
					( Origin gPackager )
				)
				( objectStatus "M_C_DQ<60>" )
			)
			( signal "@baseboard_fab2_lib.baseboard_fab2(sch_1):m_c_dq(61)"
				( attribute "CDS_PHYS_NET_NAME" "M_C_DQ<61>"
					( Origin gPackager )
				)
				( attribute "PNN" "M_C_DQ<61>"
					( Origin gPackager )
				)
				( objectStatus "M_C_DQ<61>" )
			)
			( signal "@baseboard_fab2_lib.baseboard_fab2(sch_1):m_c_dq(62)"
				( attribute "CDS_PHYS_NET_NAME" "M_C_DQ<62>"
					( Origin gPackager )
				)
				( attribute "PNN" "M_C_DQ<62>"
					( Origin gPackager )
				)
				( objectStatus "M_C_DQ<62>" )
			)
			( signal "@baseboard_fab2_lib.baseboard_fab2(sch_1):m_c_dq(63)"
				( attribute "CDS_PHYS_NET_NAME" "M_C_DQ<63>"
					( Origin gPackager )
				)
				( attribute "PNN" "M_C_DQ<63>"
					( Origin gPackager )
				)
				( objectStatus "M_C_DQ<63>" )
			)
			( signal "@baseboard_fab2_lib.baseboard_fab2(sch_1):m_c_dqs_dn(0)"
				( attribute "CDS_PHYS_NET_NAME" "M_C_DQS_DN<0>"
					( Origin gPackager )
				)
				( attribute "PNN" "M_C_DQS_DN<0>"
					( Origin gPackager )
				)
				( objectStatus "M_C_DQS_DN<0>" )
			)
			( signal "@baseboard_fab2_lib.baseboard_fab2(sch_1):m_c_dqs_dn(1)"
				( attribute "CDS_PHYS_NET_NAME" "M_C_DQS_DN<1>"
					( Origin gPackager )
				)
				( attribute "PNN" "M_C_DQS_DN<1>"
					( Origin gPackager )
				)
				( objectStatus "M_C_DQS_DN<1>" )
			)
			( signal "@baseboard_fab2_lib.baseboard_fab2(sch_1):m_c_dqs_dn(2)"
				( attribute "CDS_PHYS_NET_NAME" "M_C_DQS_DN<2>"
					( Origin gPackager )
				)
				( attribute "PNN" "M_C_DQS_DN<2>"
					( Origin gPackager )
				)
				( objectStatus "M_C_DQS_DN<2>" )
			)
			( signal "@baseboard_fab2_lib.baseboard_fab2(sch_1):m_c_dqs_dn(3)"
				( attribute "CDS_PHYS_NET_NAME" "M_C_DQS_DN<3>"
					( Origin gPackager )
				)
				( attribute "PNN" "M_C_DQS_DN<3>"
					( Origin gPackager )
				)
				( objectStatus "M_C_DQS_DN<3>" )
			)
			( signal "@baseboard_fab2_lib.baseboard_fab2(sch_1):m_c_dqs_dn(4)"
				( attribute "CDS_PHYS_NET_NAME" "M_C_DQS_DN<4>"
					( Origin gPackager )
				)
				( attribute "PNN" "M_C_DQS_DN<4>"
					( Origin gPackager )
				)
				( objectStatus "M_C_DQS_DN<4>" )
			)
			( signal "@baseboard_fab2_lib.baseboard_fab2(sch_1):m_c_dqs_dn(5)"
				( attribute "CDS_PHYS_NET_NAME" "M_C_DQS_DN<5>"
					( Origin gPackager )
				)
				( attribute "PNN" "M_C_DQS_DN<5>"
					( Origin gPackager )
				)
				( objectStatus "M_C_DQS_DN<5>" )
			)
			( signal "@baseboard_fab2_lib.baseboard_fab2(sch_1):m_c_dqs_dn(6)"
				( attribute "CDS_PHYS_NET_NAME" "M_C_DQS_DN<6>"
					( Origin gPackager )
				)
				( attribute "PNN" "M_C_DQS_DN<6>"
					( Origin gPackager )
				)
				( objectStatus "M_C_DQS_DN<6>" )
			)
			( signal "@baseboard_fab2_lib.baseboard_fab2(sch_1):m_c_dqs_dn(7)"
				( attribute "CDS_PHYS_NET_NAME" "M_C_DQS_DN<7>"
					( Origin gPackager )
				)
				( attribute "PNN" "M_C_DQS_DN<7>"
					( Origin gPackager )
				)
				( objectStatus "M_C_DQS_DN<7>" )
			)
			( signal "@baseboard_fab2_lib.baseboard_fab2(sch_1):m_c_dqs_dn(8)"
				( attribute "CDS_PHYS_NET_NAME" "M_C_DQS_DN<8>"
					( Origin gPackager )
				)
				( attribute "PNN" "M_C_DQS_DN<8>"
					( Origin gPackager )
				)
				( objectStatus "M_C_DQS_DN<8>" )
			)
			( signal "@baseboard_fab2_lib.baseboard_fab2(sch_1):m_c_dqs_dn(9)"
				( attribute "CDS_PHYS_NET_NAME" "M_C_DQS_DN<9>"
					( Origin gPackager )
				)
				( attribute "PNN" "M_C_DQS_DN<9>"
					( Origin gPackager )
				)
				( objectStatus "M_C_DQS_DN<9>" )
			)
			( signal "@baseboard_fab2_lib.baseboard_fab2(sch_1):m_c_dqs_dn(10)"
				( attribute "CDS_PHYS_NET_NAME" "M_C_DQS_DN<10>"
					( Origin gPackager )
				)
				( attribute "PNN" "M_C_DQS_DN<10>"
					( Origin gPackager )
				)
				( objectStatus "M_C_DQS_DN<10>" )
			)
			( signal "@baseboard_fab2_lib.baseboard_fab2(sch_1):m_c_dqs_dn(11)"
				( attribute "CDS_PHYS_NET_NAME" "M_C_DQS_DN<11>"
					( Origin gPackager )
				)
				( attribute "PNN" "M_C_DQS_DN<11>"
					( Origin gPackager )
				)
				( objectStatus "M_C_DQS_DN<11>" )
			)
			( signal "@baseboard_fab2_lib.baseboard_fab2(sch_1):m_c_dqs_dn(12)"
				( attribute "CDS_PHYS_NET_NAME" "M_C_DQS_DN<12>"
					( Origin gPackager )
				)
				( attribute "PNN" "M_C_DQS_DN<12>"
					( Origin gPackager )
				)
				( objectStatus "M_C_DQS_DN<12>" )
			)
			( signal "@baseboard_fab2_lib.baseboard_fab2(sch_1):m_c_dqs_dn(13)"
				( attribute "CDS_PHYS_NET_NAME" "M_C_DQS_DN<13>"
					( Origin gPackager )
				)
				( attribute "PNN" "M_C_DQS_DN<13>"
					( Origin gPackager )
				)
				( objectStatus "M_C_DQS_DN<13>" )
			)
			( signal "@baseboard_fab2_lib.baseboard_fab2(sch_1):m_c_dqs_dn(14)"
				( attribute "CDS_PHYS_NET_NAME" "M_C_DQS_DN<14>"
					( Origin gPackager )
				)
				( attribute "PNN" "M_C_DQS_DN<14>"
					( Origin gPackager )
				)
				( objectStatus "M_C_DQS_DN<14>" )
			)
			( signal "@baseboard_fab2_lib.baseboard_fab2(sch_1):m_c_dqs_dn(15)"
				( attribute "CDS_PHYS_NET_NAME" "M_C_DQS_DN<15>"
					( Origin gPackager )
				)
				( attribute "PNN" "M_C_DQS_DN<15>"
					( Origin gPackager )
				)
				( objectStatus "M_C_DQS_DN<15>" )
			)
			( signal "@baseboard_fab2_lib.baseboard_fab2(sch_1):m_c_dqs_dn(16)"
				( attribute "CDS_PHYS_NET_NAME" "M_C_DQS_DN<16>"
					( Origin gPackager )
				)
				( attribute "PNN" "M_C_DQS_DN<16>"
					( Origin gPackager )
				)
				( objectStatus "M_C_DQS_DN<16>" )
			)
			( signal "@baseboard_fab2_lib.baseboard_fab2(sch_1):m_c_dqs_dn(17)"
				( attribute "CDS_PHYS_NET_NAME" "M_C_DQS_DN<17>"
					( Origin gPackager )
				)
				( attribute "PNN" "M_C_DQS_DN<17>"
					( Origin gPackager )
				)
				( objectStatus "M_C_DQS_DN<17>" )
			)
			( signal "@baseboard_fab2_lib.baseboard_fab2(sch_1):m_c_dqs_dp(0)"
				( attribute "CDS_PHYS_NET_NAME" "M_C_DQS_DP<0>"
					( Origin gPackager )
				)
				( attribute "PNN" "M_C_DQS_DP<0>"
					( Origin gPackager )
				)
				( objectStatus "M_C_DQS_DP<0>" )
			)
			( signal "@baseboard_fab2_lib.baseboard_fab2(sch_1):m_c_dqs_dp(1)"
				( attribute "CDS_PHYS_NET_NAME" "M_C_DQS_DP<1>"
					( Origin gPackager )
				)
				( attribute "PNN" "M_C_DQS_DP<1>"
					( Origin gPackager )
				)
				( objectStatus "M_C_DQS_DP<1>" )
			)
			( signal "@baseboard_fab2_lib.baseboard_fab2(sch_1):m_c_dqs_dp(2)"
				( attribute "CDS_PHYS_NET_NAME" "M_C_DQS_DP<2>"
					( Origin gPackager )
				)
				( attribute "PNN" "M_C_DQS_DP<2>"
					( Origin gPackager )
				)
				( objectStatus "M_C_DQS_DP<2>" )
			)
			( signal "@baseboard_fab2_lib.baseboard_fab2(sch_1):m_c_dqs_dp(3)"
				( attribute "CDS_PHYS_NET_NAME" "M_C_DQS_DP<3>"
					( Origin gPackager )
				)
				( attribute "PNN" "M_C_DQS_DP<3>"
					( Origin gPackager )
				)
				( objectStatus "M_C_DQS_DP<3>" )
			)
			( signal "@baseboard_fab2_lib.baseboard_fab2(sch_1):m_c_dqs_dp(4)"
				( attribute "CDS_PHYS_NET_NAME" "M_C_DQS_DP<4>"
					( Origin gPackager )
				)
				( attribute "PNN" "M_C_DQS_DP<4>"
					( Origin gPackager )
				)
				( objectStatus "M_C_DQS_DP<4>" )
			)
			( signal "@baseboard_fab2_lib.baseboard_fab2(sch_1):m_c_dqs_dp(5)"
				( attribute "CDS_PHYS_NET_NAME" "M_C_DQS_DP<5>"
					( Origin gPackager )
				)
				( attribute "PNN" "M_C_DQS_DP<5>"
					( Origin gPackager )
				)
				( objectStatus "M_C_DQS_DP<5>" )
			)
			( signal "@baseboard_fab2_lib.baseboard_fab2(sch_1):m_c_dqs_dp(6)"
				( attribute "CDS_PHYS_NET_NAME" "M_C_DQS_DP<6>"
					( Origin gPackager )
				)
				( attribute "PNN" "M_C_DQS_DP<6>"
					( Origin gPackager )
				)
				( objectStatus "M_C_DQS_DP<6>" )
			)
			( signal "@baseboard_fab2_lib.baseboard_fab2(sch_1):m_c_dqs_dp(7)"
				( attribute "CDS_PHYS_NET_NAME" "M_C_DQS_DP<7>"
					( Origin gPackager )
				)
				( attribute "PNN" "M_C_DQS_DP<7>"
					( Origin gPackager )
				)
				( objectStatus "M_C_DQS_DP<7>" )
			)
			( signal "@baseboard_fab2_lib.baseboard_fab2(sch_1):m_c_dqs_dp(8)"
				( attribute "CDS_PHYS_NET_NAME" "M_C_DQS_DP<8>"
					( Origin gPackager )
				)
				( attribute "PNN" "M_C_DQS_DP<8>"
					( Origin gPackager )
				)
				( objectStatus "M_C_DQS_DP<8>" )
			)
			( signal "@baseboard_fab2_lib.baseboard_fab2(sch_1):m_c_dqs_dp(9)"
				( attribute "CDS_PHYS_NET_NAME" "M_C_DQS_DP<9>"
					( Origin gPackager )
				)
				( attribute "PNN" "M_C_DQS_DP<9>"
					( Origin gPackager )
				)
				( objectStatus "M_C_DQS_DP<9>" )
			)
			( signal "@baseboard_fab2_lib.baseboard_fab2(sch_1):m_c_dqs_dp(10)"
				( attribute "CDS_PHYS_NET_NAME" "M_C_DQS_DP<10>"
					( Origin gPackager )
				)
				( attribute "PNN" "M_C_DQS_DP<10>"
					( Origin gPackager )
				)
				( objectStatus "M_C_DQS_DP<10>" )
			)
			( signal "@baseboard_fab2_lib.baseboard_fab2(sch_1):m_c_dqs_dp(11)"
				( attribute "CDS_PHYS_NET_NAME" "M_C_DQS_DP<11>"
					( Origin gPackager )
				)
				( attribute "PNN" "M_C_DQS_DP<11>"
					( Origin gPackager )
				)
				( objectStatus "M_C_DQS_DP<11>" )
			)
			( signal "@baseboard_fab2_lib.baseboard_fab2(sch_1):m_c_dqs_dp(12)"
				( attribute "CDS_PHYS_NET_NAME" "M_C_DQS_DP<12>"
					( Origin gPackager )
				)
				( attribute "PNN" "M_C_DQS_DP<12>"
					( Origin gPackager )
				)
				( objectStatus "M_C_DQS_DP<12>" )
			)
			( signal "@baseboard_fab2_lib.baseboard_fab2(sch_1):m_c_dqs_dp(13)"
				( attribute "CDS_PHYS_NET_NAME" "M_C_DQS_DP<13>"
					( Origin gPackager )
				)
				( attribute "PNN" "M_C_DQS_DP<13>"
					( Origin gPackager )
				)
				( objectStatus "M_C_DQS_DP<13>" )
			)
			( signal "@baseboard_fab2_lib.baseboard_fab2(sch_1):m_c_dqs_dp(14)"
				( attribute "CDS_PHYS_NET_NAME" "M_C_DQS_DP<14>"
					( Origin gPackager )
				)
				( attribute "PNN" "M_C_DQS_DP<14>"
					( Origin gPackager )
				)
				( objectStatus "M_C_DQS_DP<14>" )
			)
			( signal "@baseboard_fab2_lib.baseboard_fab2(sch_1):m_c_dqs_dp(15)"
				( attribute "CDS_PHYS_NET_NAME" "M_C_DQS_DP<15>"
					( Origin gPackager )
				)
				( attribute "PNN" "M_C_DQS_DP<15>"
					( Origin gPackager )
				)
				( objectStatus "M_C_DQS_DP<15>" )
			)
			( signal "@baseboard_fab2_lib.baseboard_fab2(sch_1):m_c_dqs_dp(16)"
				( attribute "CDS_PHYS_NET_NAME" "M_C_DQS_DP<16>"
					( Origin gPackager )
				)
				( attribute "PNN" "M_C_DQS_DP<16>"
					( Origin gPackager )
				)
				( objectStatus "M_C_DQS_DP<16>" )
			)
			( signal "@baseboard_fab2_lib.baseboard_fab2(sch_1):m_c_dqs_dp(17)"
				( attribute "CDS_PHYS_NET_NAME" "M_C_DQS_DP<17>"
					( Origin gPackager )
				)
				( attribute "PNN" "M_C_DQS_DP<17>"
					( Origin gPackager )
				)
				( objectStatus "M_C_DQS_DP<17>" )
			)
			( signal "@baseboard_fab2_lib.baseboard_fab2(sch_1):m_c_ecc(0)"
				( attribute "CDS_PHYS_NET_NAME" "M_C_ECC<0>"
					( Origin gPackager )
				)
				( attribute "PNN" "M_C_ECC<0>"
					( Origin gPackager )
				)
				( objectStatus "M_C_ECC<0>" )
			)
			( signal "@baseboard_fab2_lib.baseboard_fab2(sch_1):m_c_ecc(1)"
				( attribute "CDS_PHYS_NET_NAME" "M_C_ECC<1>"
					( Origin gPackager )
				)
				( attribute "PNN" "M_C_ECC<1>"
					( Origin gPackager )
				)
				( objectStatus "M_C_ECC<1>" )
			)
			( signal "@baseboard_fab2_lib.baseboard_fab2(sch_1):m_c_ecc(2)"
				( attribute "CDS_PHYS_NET_NAME" "M_C_ECC<2>"
					( Origin gPackager )
				)
				( attribute "PNN" "M_C_ECC<2>"
					( Origin gPackager )
				)
				( objectStatus "M_C_ECC<2>" )
			)
			( signal "@baseboard_fab2_lib.baseboard_fab2(sch_1):m_c_ecc(3)"
				( attribute "CDS_PHYS_NET_NAME" "M_C_ECC<3>"
					( Origin gPackager )
				)
				( attribute "PNN" "M_C_ECC<3>"
					( Origin gPackager )
				)
				( objectStatus "M_C_ECC<3>" )
			)
			( signal "@baseboard_fab2_lib.baseboard_fab2(sch_1):m_c_ecc(4)"
				( attribute "CDS_PHYS_NET_NAME" "M_C_ECC<4>"
					( Origin gPackager )
				)
				( attribute "PNN" "M_C_ECC<4>"
					( Origin gPackager )
				)
				( objectStatus "M_C_ECC<4>" )
			)
			( signal "@baseboard_fab2_lib.baseboard_fab2(sch_1):m_c_ecc(5)"
				( attribute "CDS_PHYS_NET_NAME" "M_C_ECC<5>"
					( Origin gPackager )
				)
				( attribute "PNN" "M_C_ECC<5>"
					( Origin gPackager )
				)
				( objectStatus "M_C_ECC<5>" )
			)
			( signal "@baseboard_fab2_lib.baseboard_fab2(sch_1):m_c_ecc(6)"
				( attribute "CDS_PHYS_NET_NAME" "M_C_ECC<6>"
					( Origin gPackager )
				)
				( attribute "PNN" "M_C_ECC<6>"
					( Origin gPackager )
				)
				( objectStatus "M_C_ECC<6>" )
			)
			( signal "@baseboard_fab2_lib.baseboard_fab2(sch_1):m_c_ecc(7)"
				( attribute "CDS_PHYS_NET_NAME" "M_C_ECC<7>"
					( Origin gPackager )
				)
				( attribute "PNN" "M_C_ECC<7>"
					( Origin gPackager )
				)
				( objectStatus "M_C_ECC<7>" )
			)
			( signal "@baseboard_fab2_lib.baseboard_fab2(sch_1):m_c_ma(0)"
				( attribute "CDS_PHYS_NET_NAME" "M_C_MA<0>"
					( Origin gPackager )
				)
				( attribute "PNN" "M_C_MA<0>"
					( Origin gPackager )
				)
				( objectStatus "M_C_MA<0>" )
			)
			( signal "@baseboard_fab2_lib.baseboard_fab2(sch_1):m_c_ma(1)"
				( attribute "CDS_PHYS_NET_NAME" "M_C_MA<1>"
					( Origin gPackager )
				)
				( attribute "PNN" "M_C_MA<1>"
					( Origin gPackager )
				)
				( objectStatus "M_C_MA<1>" )
			)
			( signal "@baseboard_fab2_lib.baseboard_fab2(sch_1):m_c_ma(2)"
				( attribute "CDS_PHYS_NET_NAME" "M_C_MA<2>"
					( Origin gPackager )
				)
				( attribute "PNN" "M_C_MA<2>"
					( Origin gPackager )
				)
				( objectStatus "M_C_MA<2>" )
			)
			( signal "@baseboard_fab2_lib.baseboard_fab2(sch_1):m_c_ma(3)"
				( attribute "CDS_PHYS_NET_NAME" "M_C_MA<3>"
					( Origin gPackager )
				)
				( attribute "PNN" "M_C_MA<3>"
					( Origin gPackager )
				)
				( objectStatus "M_C_MA<3>" )
			)
			( signal "@baseboard_fab2_lib.baseboard_fab2(sch_1):m_c_ma(4)"
				( attribute "CDS_PHYS_NET_NAME" "M_C_MA<4>"
					( Origin gPackager )
				)
				( attribute "PNN" "M_C_MA<4>"
					( Origin gPackager )
				)
				( objectStatus "M_C_MA<4>" )
			)
			( signal "@baseboard_fab2_lib.baseboard_fab2(sch_1):m_c_ma(5)"
				( attribute "CDS_PHYS_NET_NAME" "M_C_MA<5>"
					( Origin gPackager )
				)
				( attribute "PNN" "M_C_MA<5>"
					( Origin gPackager )
				)
				( objectStatus "M_C_MA<5>" )
			)
			( signal "@baseboard_fab2_lib.baseboard_fab2(sch_1):m_c_ma(6)"
				( attribute "CDS_PHYS_NET_NAME" "M_C_MA<6>"
					( Origin gPackager )
				)
				( attribute "PNN" "M_C_MA<6>"
					( Origin gPackager )
				)
				( objectStatus "M_C_MA<6>" )
			)
			( signal "@baseboard_fab2_lib.baseboard_fab2(sch_1):m_c_ma(7)"
				( attribute "CDS_PHYS_NET_NAME" "M_C_MA<7>"
					( Origin gPackager )
				)
				( attribute "PNN" "M_C_MA<7>"
					( Origin gPackager )
				)
				( objectStatus "M_C_MA<7>" )
			)
			( signal "@baseboard_fab2_lib.baseboard_fab2(sch_1):m_c_ma(8)"
				( attribute "CDS_PHYS_NET_NAME" "M_C_MA<8>"
					( Origin gPackager )
				)
				( attribute "PNN" "M_C_MA<8>"
					( Origin gPackager )
				)
				( objectStatus "M_C_MA<8>" )
			)
			( signal "@baseboard_fab2_lib.baseboard_fab2(sch_1):m_c_ma(9)"
				( attribute "CDS_PHYS_NET_NAME" "M_C_MA<9>"
					( Origin gPackager )
				)
				( attribute "PNN" "M_C_MA<9>"
					( Origin gPackager )
				)
				( objectStatus "M_C_MA<9>" )
			)
			( signal "@baseboard_fab2_lib.baseboard_fab2(sch_1):m_c_ma(10)"
				( attribute "CDS_PHYS_NET_NAME" "M_C_MA<10>"
					( Origin gPackager )
				)
				( attribute "PNN" "M_C_MA<10>"
					( Origin gPackager )
				)
				( objectStatus "M_C_MA<10>" )
			)
			( signal "@baseboard_fab2_lib.baseboard_fab2(sch_1):m_c_ma(11)"
				( attribute "CDS_PHYS_NET_NAME" "M_C_MA<11>"
					( Origin gPackager )
				)
				( attribute "PNN" "M_C_MA<11>"
					( Origin gPackager )
				)
				( objectStatus "M_C_MA<11>" )
			)
			( signal "@baseboard_fab2_lib.baseboard_fab2(sch_1):m_c_ma(12)"
				( attribute "CDS_PHYS_NET_NAME" "M_C_MA<12>"
					( Origin gPackager )
				)
				( attribute "PNN" "M_C_MA<12>"
					( Origin gPackager )
				)
				( objectStatus "M_C_MA<12>" )
			)
			( signal "@baseboard_fab2_lib.baseboard_fab2(sch_1):m_c_ma(13)"
				( attribute "CDS_PHYS_NET_NAME" "M_C_MA<13>"
					( Origin gPackager )
				)
				( attribute "PNN" "M_C_MA<13>"
					( Origin gPackager )
				)
				( objectStatus "M_C_MA<13>" )
			)
			( signal "@baseboard_fab2_lib.baseboard_fab2(sch_1):m_c_ma(14)"
				( attribute "CDS_PHYS_NET_NAME" "M_C_MA<14>"
					( Origin gPackager )
				)
				( attribute "PNN" "M_C_MA<14>"
					( Origin gPackager )
				)
				( objectStatus "M_C_MA<14>" )
			)
			( signal "@baseboard_fab2_lib.baseboard_fab2(sch_1):m_c_ma(15)"
				( attribute "CDS_PHYS_NET_NAME" "M_C_MA<15>"
					( Origin gPackager )
				)
				( attribute "PNN" "M_C_MA<15>"
					( Origin gPackager )
				)
				( objectStatus "M_C_MA<15>" )
			)
			( signal "@baseboard_fab2_lib.baseboard_fab2(sch_1):m_c_ma(16)"
				( attribute "CDS_PHYS_NET_NAME" "M_C_MA<16>"
					( Origin gPackager )
				)
				( attribute "PNN" "M_C_MA<16>"
					( Origin gPackager )
				)
				( objectStatus "M_C_MA<16>" )
			)
			( signal "@baseboard_fab2_lib.baseboard_fab2(sch_1):m_c_ma(17)"
				( attribute "CDS_PHYS_NET_NAME" "M_C_MA<17>"
					( Origin gPackager )
				)
				( attribute "PNN" "M_C_MA<17>"
					( Origin gPackager )
				)
				( objectStatus "M_C_MA<17>" )
			)
			( signal "@baseboard_fab2_lib.baseboard_fab2(sch_1):m_c_odt(0)"
				( attribute "CDS_PHYS_NET_NAME" "M_C_ODT<0>"
					( Origin gPackager )
				)
				( attribute "PNN" "M_C_ODT<0>"
					( Origin gPackager )
				)
				( objectStatus "M_C_ODT<0>" )
			)
			( signal "@baseboard_fab2_lib.baseboard_fab2(sch_1):m_c_odt(1)"
				( attribute "CDS_PHYS_NET_NAME" "M_C_ODT<1>"
					( Origin gPackager )
				)
				( attribute "PNN" "M_C_ODT<1>"
					( Origin gPackager )
				)
				( objectStatus "M_C_ODT<1>" )
			)
			( signal "@baseboard_fab2_lib.baseboard_fab2(sch_1):m_c_odt(2)"
				( attribute "CDS_PHYS_NET_NAME" "M_C_ODT<2>"
					( Origin gPackager )
				)
				( attribute "PNN" "M_C_ODT<2>"
					( Origin gPackager )
				)
				( objectStatus "M_C_ODT<2>" )
			)
			( signal "@baseboard_fab2_lib.baseboard_fab2(sch_1):m_c_odt(3)"
				( attribute "CDS_PHYS_NET_NAME" "M_C_ODT<3>"
					( Origin gPackager )
				)
				( attribute "PNN" "M_C_ODT<3>"
					( Origin gPackager )
				)
				( objectStatus "M_C_ODT<3>" )
			)
			( signal "@baseboard_fab2_lib.baseboard_fab2(sch_1):m_c_par"
				( attribute "CDS_PHYS_NET_NAME" "M_C_PAR"
					( Origin gPackager )
				)
				( objectStatus "M_C_PAR" )
			)
			( signal "@baseboard_fab2_lib.baseboard_fab2(sch_1):m_d_act_n"
				( attribute "CDS_PHYS_NET_NAME" "M_D_ACT_N"
					( Origin gPackager )
				)
				( objectStatus "M_D_ACT_N" )
			)
			( signal "@baseboard_fab2_lib.baseboard_fab2(sch_1):m_d_alert_n"
				( attribute "CDS_PHYS_NET_NAME" "M_D_ALERT_N"
					( Origin gPackager )
				)
				( objectStatus "M_D_ALERT_N" )
			)
			( signal "@baseboard_fab2_lib.baseboard_fab2(sch_1):m_d_ba(0)"
				( attribute "CDS_PHYS_NET_NAME" "M_D_BA<0>"
					( Origin gPackager )
				)
				( attribute "PNN" "M_D_BA<0>"
					( Origin gPackager )
				)
				( objectStatus "M_D_BA<0>" )
			)
			( signal "@baseboard_fab2_lib.baseboard_fab2(sch_1):m_d_ba(1)"
				( attribute "CDS_PHYS_NET_NAME" "M_D_BA<1>"
					( Origin gPackager )
				)
				( attribute "PNN" "M_D_BA<1>"
					( Origin gPackager )
				)
				( objectStatus "M_D_BA<1>" )
			)
			( signal "@baseboard_fab2_lib.baseboard_fab2(sch_1):m_d_bg(0)"
				( attribute "CDS_PHYS_NET_NAME" "M_D_BG<0>"
					( Origin gPackager )
				)
				( attribute "PNN" "M_D_BG<0>"
					( Origin gPackager )
				)
				( objectStatus "M_D_BG<0>" )
			)
			( signal "@baseboard_fab2_lib.baseboard_fab2(sch_1):m_d_bg(1)"
				( attribute "CDS_PHYS_NET_NAME" "M_D_BG<1>"
					( Origin gPackager )
				)
				( attribute "PNN" "M_D_BG<1>"
					( Origin gPackager )
				)
				( objectStatus "M_D_BG<1>" )
			)
			( signal "@baseboard_fab2_lib.baseboard_fab2(sch_1):m_d_c(2)"
				( attribute "CDS_PHYS_NET_NAME" "M_D_C<2>"
					( Origin gPackager )
				)
				( attribute "PNN" "M_D_C<2>"
					( Origin gPackager )
				)
				( objectStatus "M_D_C<2>" )
			)
			( signal "@baseboard_fab2_lib.baseboard_fab2(sch_1):m_d_cke(0)"
				( attribute "CDS_PHYS_NET_NAME" "M_D_CKE<0>"
					( Origin gPackager )
				)
				( attribute "PNN" "M_D_CKE<0>"
					( Origin gPackager )
				)
				( objectStatus "M_D_CKE<0>" )
			)
			( signal "@baseboard_fab2_lib.baseboard_fab2(sch_1):m_d_cke(1)"
				( attribute "CDS_PHYS_NET_NAME" "M_D_CKE<1>"
					( Origin gPackager )
				)
				( attribute "PNN" "M_D_CKE<1>"
					( Origin gPackager )
				)
				( objectStatus "M_D_CKE<1>" )
			)
			( signal "@baseboard_fab2_lib.baseboard_fab2(sch_1):m_d_cke(2)"
				( attribute "CDS_PHYS_NET_NAME" "M_D_CKE<2>"
					( Origin gPackager )
				)
				( attribute "PNN" "M_D_CKE<2>"
					( Origin gPackager )
				)
				( objectStatus "M_D_CKE<2>" )
			)
			( signal "@baseboard_fab2_lib.baseboard_fab2(sch_1):m_d_cke(3)"
				( attribute "CDS_PHYS_NET_NAME" "M_D_CKE<3>"
					( Origin gPackager )
				)
				( attribute "PNN" "M_D_CKE<3>"
					( Origin gPackager )
				)
				( objectStatus "M_D_CKE<3>" )
			)
			( signal "@baseboard_fab2_lib.baseboard_fab2(sch_1):m_d_clk_dn(0)"
				( attribute "CDS_PHYS_NET_NAME" "M_D_CLK_DN<0>"
					( Origin gPackager )
				)
				( attribute "PNN" "M_D_CLK_DN<0>"
					( Origin gPackager )
				)
				( objectStatus "M_D_CLK_DN<0>" )
			)
			( signal "@baseboard_fab2_lib.baseboard_fab2(sch_1):m_d_clk_dn(1)"
				( attribute "CDS_PHYS_NET_NAME" "M_D_CLK_DN<1>"
					( Origin gPackager )
				)
				( attribute "PNN" "M_D_CLK_DN<1>"
					( Origin gPackager )
				)
				( objectStatus "M_D_CLK_DN<1>" )
			)
			( signal "@baseboard_fab2_lib.baseboard_fab2(sch_1):m_d_clk_dn(2)"
				( attribute "CDS_PHYS_NET_NAME" "M_D_CLK_DN<2>"
					( Origin gPackager )
				)
				( attribute "PNN" "M_D_CLK_DN<2>"
					( Origin gPackager )
				)
				( objectStatus "M_D_CLK_DN<2>" )
			)
			( signal "@baseboard_fab2_lib.baseboard_fab2(sch_1):m_d_clk_dn(3)"
				( attribute "CDS_PHYS_NET_NAME" "M_D_CLK_DN<3>"
					( Origin gPackager )
				)
				( attribute "PNN" "M_D_CLK_DN<3>"
					( Origin gPackager )
				)
				( objectStatus "M_D_CLK_DN<3>" )
			)
			( signal "@baseboard_fab2_lib.baseboard_fab2(sch_1):m_d_clk_dp(0)"
				( attribute "CDS_PHYS_NET_NAME" "M_D_CLK_DP<0>"
					( Origin gPackager )
				)
				( attribute "PNN" "M_D_CLK_DP<0>"
					( Origin gPackager )
				)
				( objectStatus "M_D_CLK_DP<0>" )
			)
			( signal "@baseboard_fab2_lib.baseboard_fab2(sch_1):m_d_clk_dp(1)"
				( attribute "CDS_PHYS_NET_NAME" "M_D_CLK_DP<1>"
					( Origin gPackager )
				)
				( attribute "PNN" "M_D_CLK_DP<1>"
					( Origin gPackager )
				)
				( objectStatus "M_D_CLK_DP<1>" )
			)
			( signal "@baseboard_fab2_lib.baseboard_fab2(sch_1):m_d_clk_dp(2)"
				( attribute "CDS_PHYS_NET_NAME" "M_D_CLK_DP<2>"
					( Origin gPackager )
				)
				( attribute "PNN" "M_D_CLK_DP<2>"
					( Origin gPackager )
				)
				( objectStatus "M_D_CLK_DP<2>" )
			)
			( signal "@baseboard_fab2_lib.baseboard_fab2(sch_1):m_d_clk_dp(3)"
				( attribute "CDS_PHYS_NET_NAME" "M_D_CLK_DP<3>"
					( Origin gPackager )
				)
				( attribute "PNN" "M_D_CLK_DP<3>"
					( Origin gPackager )
				)
				( objectStatus "M_D_CLK_DP<3>" )
			)
			( signal "@baseboard_fab2_lib.baseboard_fab2(sch_1):m_d_cs_n(0)"
				( attribute "CDS_PHYS_NET_NAME" "M_D_CS_N<0>"
					( Origin gPackager )
				)
				( attribute "PNN" "M_D_CS_N<0>"
					( Origin gPackager )
				)
				( objectStatus "M_D_CS_N<0>" )
			)
			( signal "@baseboard_fab2_lib.baseboard_fab2(sch_1):m_d_cs_n(1)"
				( attribute "CDS_PHYS_NET_NAME" "M_D_CS_N<1>"
					( Origin gPackager )
				)
				( attribute "PNN" "M_D_CS_N<1>"
					( Origin gPackager )
				)
				( objectStatus "M_D_CS_N<1>" )
			)
			( signal "@baseboard_fab2_lib.baseboard_fab2(sch_1):m_d_cs_n(2)"
				( attribute "CDS_PHYS_NET_NAME" "M_D_CS_N<2>"
					( Origin gPackager )
				)
				( attribute "PNN" "M_D_CS_N<2>"
					( Origin gPackager )
				)
				( objectStatus "M_D_CS_N<2>" )
			)
			( signal "@baseboard_fab2_lib.baseboard_fab2(sch_1):m_d_cs_n(3)"
				( attribute "CDS_PHYS_NET_NAME" "M_D_CS_N<3>"
					( Origin gPackager )
				)
				( attribute "PNN" "M_D_CS_N<3>"
					( Origin gPackager )
				)
				( objectStatus "M_D_CS_N<3>" )
			)
			( signal "@baseboard_fab2_lib.baseboard_fab2(sch_1):m_d_cs_n(4)"
				( attribute "CDS_PHYS_NET_NAME" "M_D_CS_N<4>"
					( Origin gPackager )
				)
				( attribute "PNN" "M_D_CS_N<4>"
					( Origin gPackager )
				)
				( objectStatus "M_D_CS_N<4>" )
			)
			( signal "@baseboard_fab2_lib.baseboard_fab2(sch_1):m_d_cs_n(5)"
				( attribute "CDS_PHYS_NET_NAME" "M_D_CS_N<5>"
					( Origin gPackager )
				)
				( attribute "PNN" "M_D_CS_N<5>"
					( Origin gPackager )
				)
				( objectStatus "M_D_CS_N<5>" )
			)
			( signal "@baseboard_fab2_lib.baseboard_fab2(sch_1):m_d_cs_n(6)"
				( attribute "CDS_PHYS_NET_NAME" "M_D_CS_N<6>"
					( Origin gPackager )
				)
				( attribute "PNN" "M_D_CS_N<6>"
					( Origin gPackager )
				)
				( objectStatus "M_D_CS_N<6>" )
			)
			( signal "@baseboard_fab2_lib.baseboard_fab2(sch_1):m_d_cs_n(7)"
				( attribute "CDS_PHYS_NET_NAME" "M_D_CS_N<7>"
					( Origin gPackager )
				)
				( attribute "PNN" "M_D_CS_N<7>"
					( Origin gPackager )
				)
				( objectStatus "M_D_CS_N<7>" )
			)
			( signal "@baseboard_fab2_lib.baseboard_fab2(sch_1):m_d_dq(0)"
				( attribute "CDS_PHYS_NET_NAME" "M_D_DQ<0>"
					( Origin gPackager )
				)
				( attribute "PNN" "M_D_DQ<0>"
					( Origin gPackager )
				)
				( objectStatus "M_D_DQ<0>" )
			)
			( signal "@baseboard_fab2_lib.baseboard_fab2(sch_1):m_d_dq(1)"
				( attribute "CDS_PHYS_NET_NAME" "M_D_DQ<1>"
					( Origin gPackager )
				)
				( attribute "PNN" "M_D_DQ<1>"
					( Origin gPackager )
				)
				( objectStatus "M_D_DQ<1>" )
			)
			( signal "@baseboard_fab2_lib.baseboard_fab2(sch_1):m_d_dq(2)"
				( attribute "CDS_PHYS_NET_NAME" "M_D_DQ<2>"
					( Origin gPackager )
				)
				( attribute "PNN" "M_D_DQ<2>"
					( Origin gPackager )
				)
				( objectStatus "M_D_DQ<2>" )
			)
			( signal "@baseboard_fab2_lib.baseboard_fab2(sch_1):m_d_dq(3)"
				( attribute "CDS_PHYS_NET_NAME" "M_D_DQ<3>"
					( Origin gPackager )
				)
				( attribute "PNN" "M_D_DQ<3>"
					( Origin gPackager )
				)
				( objectStatus "M_D_DQ<3>" )
			)
			( signal "@baseboard_fab2_lib.baseboard_fab2(sch_1):m_d_dq(4)"
				( attribute "CDS_PHYS_NET_NAME" "M_D_DQ<4>"
					( Origin gPackager )
				)
				( attribute "PNN" "M_D_DQ<4>"
					( Origin gPackager )
				)
				( objectStatus "M_D_DQ<4>" )
			)
			( signal "@baseboard_fab2_lib.baseboard_fab2(sch_1):m_d_dq(5)"
				( attribute "CDS_PHYS_NET_NAME" "M_D_DQ<5>"
					( Origin gPackager )
				)
				( attribute "PNN" "M_D_DQ<5>"
					( Origin gPackager )
				)
				( objectStatus "M_D_DQ<5>" )
			)
			( signal "@baseboard_fab2_lib.baseboard_fab2(sch_1):m_d_dq(6)"
				( attribute "CDS_PHYS_NET_NAME" "M_D_DQ<6>"
					( Origin gPackager )
				)
				( attribute "PNN" "M_D_DQ<6>"
					( Origin gPackager )
				)
				( objectStatus "M_D_DQ<6>" )
			)
			( signal "@baseboard_fab2_lib.baseboard_fab2(sch_1):m_d_dq(7)"
				( attribute "CDS_PHYS_NET_NAME" "M_D_DQ<7>"
					( Origin gPackager )
				)
				( attribute "PNN" "M_D_DQ<7>"
					( Origin gPackager )
				)
				( objectStatus "M_D_DQ<7>" )
			)
			( signal "@baseboard_fab2_lib.baseboard_fab2(sch_1):m_d_dq(8)"
				( attribute "CDS_PHYS_NET_NAME" "M_D_DQ<8>"
					( Origin gPackager )
				)
				( attribute "PNN" "M_D_DQ<8>"
					( Origin gPackager )
				)
				( objectStatus "M_D_DQ<8>" )
			)
			( signal "@baseboard_fab2_lib.baseboard_fab2(sch_1):m_d_dq(9)"
				( attribute "CDS_PHYS_NET_NAME" "M_D_DQ<9>"
					( Origin gPackager )
				)
				( attribute "PNN" "M_D_DQ<9>"
					( Origin gPackager )
				)
				( objectStatus "M_D_DQ<9>" )
			)
			( signal "@baseboard_fab2_lib.baseboard_fab2(sch_1):m_d_dq(10)"
				( attribute "CDS_PHYS_NET_NAME" "M_D_DQ<10>"
					( Origin gPackager )
				)
				( attribute "PNN" "M_D_DQ<10>"
					( Origin gPackager )
				)
				( objectStatus "M_D_DQ<10>" )
			)
			( signal "@baseboard_fab2_lib.baseboard_fab2(sch_1):m_d_dq(11)"
				( attribute "CDS_PHYS_NET_NAME" "M_D_DQ<11>"
					( Origin gPackager )
				)
				( attribute "PNN" "M_D_DQ<11>"
					( Origin gPackager )
				)
				( objectStatus "M_D_DQ<11>" )
			)
			( signal "@baseboard_fab2_lib.baseboard_fab2(sch_1):m_d_dq(12)"
				( attribute "CDS_PHYS_NET_NAME" "M_D_DQ<12>"
					( Origin gPackager )
				)
				( attribute "PNN" "M_D_DQ<12>"
					( Origin gPackager )
				)
				( objectStatus "M_D_DQ<12>" )
			)
			( signal "@baseboard_fab2_lib.baseboard_fab2(sch_1):m_d_dq(13)"
				( attribute "CDS_PHYS_NET_NAME" "M_D_DQ<13>"
					( Origin gPackager )
				)
				( attribute "PNN" "M_D_DQ<13>"
					( Origin gPackager )
				)
				( objectStatus "M_D_DQ<13>" )
			)
			( signal "@baseboard_fab2_lib.baseboard_fab2(sch_1):m_d_dq(14)"
				( attribute "CDS_PHYS_NET_NAME" "M_D_DQ<14>"
					( Origin gPackager )
				)
				( attribute "PNN" "M_D_DQ<14>"
					( Origin gPackager )
				)
				( objectStatus "M_D_DQ<14>" )
			)
			( signal "@baseboard_fab2_lib.baseboard_fab2(sch_1):m_d_dq(15)"
				( attribute "CDS_PHYS_NET_NAME" "M_D_DQ<15>"
					( Origin gPackager )
				)
				( attribute "PNN" "M_D_DQ<15>"
					( Origin gPackager )
				)
				( objectStatus "M_D_DQ<15>" )
			)
			( signal "@baseboard_fab2_lib.baseboard_fab2(sch_1):m_d_dq(16)"
				( attribute "CDS_PHYS_NET_NAME" "M_D_DQ<16>"
					( Origin gPackager )
				)
				( attribute "PNN" "M_D_DQ<16>"
					( Origin gPackager )
				)
				( objectStatus "M_D_DQ<16>" )
			)
			( signal "@baseboard_fab2_lib.baseboard_fab2(sch_1):m_d_dq(17)"
				( attribute "CDS_PHYS_NET_NAME" "M_D_DQ<17>"
					( Origin gPackager )
				)
				( attribute "PNN" "M_D_DQ<17>"
					( Origin gPackager )
				)
				( objectStatus "M_D_DQ<17>" )
			)
			( signal "@baseboard_fab2_lib.baseboard_fab2(sch_1):m_d_dq(18)"
				( attribute "CDS_PHYS_NET_NAME" "M_D_DQ<18>"
					( Origin gPackager )
				)
				( attribute "PNN" "M_D_DQ<18>"
					( Origin gPackager )
				)
				( objectStatus "M_D_DQ<18>" )
			)
			( signal "@baseboard_fab2_lib.baseboard_fab2(sch_1):m_d_dq(19)"
				( attribute "CDS_PHYS_NET_NAME" "M_D_DQ<19>"
					( Origin gPackager )
				)
				( attribute "PNN" "M_D_DQ<19>"
					( Origin gPackager )
				)
				( objectStatus "M_D_DQ<19>" )
			)
			( signal "@baseboard_fab2_lib.baseboard_fab2(sch_1):m_d_dq(20)"
				( attribute "CDS_PHYS_NET_NAME" "M_D_DQ<20>"
					( Origin gPackager )
				)
				( attribute "PNN" "M_D_DQ<20>"
					( Origin gPackager )
				)
				( objectStatus "M_D_DQ<20>" )
			)
			( signal "@baseboard_fab2_lib.baseboard_fab2(sch_1):m_d_dq(21)"
				( attribute "CDS_PHYS_NET_NAME" "M_D_DQ<21>"
					( Origin gPackager )
				)
				( attribute "PNN" "M_D_DQ<21>"
					( Origin gPackager )
				)
				( objectStatus "M_D_DQ<21>" )
			)
			( signal "@baseboard_fab2_lib.baseboard_fab2(sch_1):m_d_dq(22)"
				( attribute "CDS_PHYS_NET_NAME" "M_D_DQ<22>"
					( Origin gPackager )
				)
				( attribute "PNN" "M_D_DQ<22>"
					( Origin gPackager )
				)
				( objectStatus "M_D_DQ<22>" )
			)
			( signal "@baseboard_fab2_lib.baseboard_fab2(sch_1):m_d_dq(23)"
				( attribute "CDS_PHYS_NET_NAME" "M_D_DQ<23>"
					( Origin gPackager )
				)
				( attribute "PNN" "M_D_DQ<23>"
					( Origin gPackager )
				)
				( objectStatus "M_D_DQ<23>" )
			)
			( signal "@baseboard_fab2_lib.baseboard_fab2(sch_1):m_d_dq(24)"
				( attribute "CDS_PHYS_NET_NAME" "M_D_DQ<24>"
					( Origin gPackager )
				)
				( attribute "PNN" "M_D_DQ<24>"
					( Origin gPackager )
				)
				( objectStatus "M_D_DQ<24>" )
			)
			( signal "@baseboard_fab2_lib.baseboard_fab2(sch_1):m_d_dq(25)"
				( attribute "CDS_PHYS_NET_NAME" "M_D_DQ<25>"
					( Origin gPackager )
				)
				( attribute "PNN" "M_D_DQ<25>"
					( Origin gPackager )
				)
				( objectStatus "M_D_DQ<25>" )
			)
			( signal "@baseboard_fab2_lib.baseboard_fab2(sch_1):m_d_dq(26)"
				( attribute "CDS_PHYS_NET_NAME" "M_D_DQ<26>"
					( Origin gPackager )
				)
				( attribute "PNN" "M_D_DQ<26>"
					( Origin gPackager )
				)
				( objectStatus "M_D_DQ<26>" )
			)
			( signal "@baseboard_fab2_lib.baseboard_fab2(sch_1):m_d_dq(27)"
				( attribute "CDS_PHYS_NET_NAME" "M_D_DQ<27>"
					( Origin gPackager )
				)
				( attribute "PNN" "M_D_DQ<27>"
					( Origin gPackager )
				)
				( objectStatus "M_D_DQ<27>" )
			)
			( signal "@baseboard_fab2_lib.baseboard_fab2(sch_1):m_d_dq(28)"
				( attribute "CDS_PHYS_NET_NAME" "M_D_DQ<28>"
					( Origin gPackager )
				)
				( attribute "PNN" "M_D_DQ<28>"
					( Origin gPackager )
				)
				( objectStatus "M_D_DQ<28>" )
			)
			( signal "@baseboard_fab2_lib.baseboard_fab2(sch_1):m_d_dq(29)"
				( attribute "CDS_PHYS_NET_NAME" "M_D_DQ<29>"
					( Origin gPackager )
				)
				( attribute "PNN" "M_D_DQ<29>"
					( Origin gPackager )
				)
				( objectStatus "M_D_DQ<29>" )
			)
			( signal "@baseboard_fab2_lib.baseboard_fab2(sch_1):m_d_dq(30)"
				( attribute "CDS_PHYS_NET_NAME" "M_D_DQ<30>"
					( Origin gPackager )
				)
				( attribute "PNN" "M_D_DQ<30>"
					( Origin gPackager )
				)
				( objectStatus "M_D_DQ<30>" )
			)
			( signal "@baseboard_fab2_lib.baseboard_fab2(sch_1):m_d_dq(31)"
				( attribute "CDS_PHYS_NET_NAME" "M_D_DQ<31>"
					( Origin gPackager )
				)
				( attribute "PNN" "M_D_DQ<31>"
					( Origin gPackager )
				)
				( objectStatus "M_D_DQ<31>" )
			)
			( signal "@baseboard_fab2_lib.baseboard_fab2(sch_1):m_d_dq(32)"
				( attribute "CDS_PHYS_NET_NAME" "M_D_DQ<32>"
					( Origin gPackager )
				)
				( attribute "PNN" "M_D_DQ<32>"
					( Origin gPackager )
				)
				( objectStatus "M_D_DQ<32>" )
			)
			( signal "@baseboard_fab2_lib.baseboard_fab2(sch_1):m_d_dq(33)"
				( attribute "CDS_PHYS_NET_NAME" "M_D_DQ<33>"
					( Origin gPackager )
				)
				( attribute "PNN" "M_D_DQ<33>"
					( Origin gPackager )
				)
				( objectStatus "M_D_DQ<33>" )
			)
			( signal "@baseboard_fab2_lib.baseboard_fab2(sch_1):m_d_dq(34)"
				( attribute "CDS_PHYS_NET_NAME" "M_D_DQ<34>"
					( Origin gPackager )
				)
				( attribute "PNN" "M_D_DQ<34>"
					( Origin gPackager )
				)
				( objectStatus "M_D_DQ<34>" )
			)
			( signal "@baseboard_fab2_lib.baseboard_fab2(sch_1):m_d_dq(35)"
				( attribute "CDS_PHYS_NET_NAME" "M_D_DQ<35>"
					( Origin gPackager )
				)
				( attribute "PNN" "M_D_DQ<35>"
					( Origin gPackager )
				)
				( objectStatus "M_D_DQ<35>" )
			)
			( signal "@baseboard_fab2_lib.baseboard_fab2(sch_1):m_d_dq(36)"
				( attribute "CDS_PHYS_NET_NAME" "M_D_DQ<36>"
					( Origin gPackager )
				)
				( attribute "PNN" "M_D_DQ<36>"
					( Origin gPackager )
				)
				( objectStatus "M_D_DQ<36>" )
			)
			( signal "@baseboard_fab2_lib.baseboard_fab2(sch_1):m_d_dq(37)"
				( attribute "CDS_PHYS_NET_NAME" "M_D_DQ<37>"
					( Origin gPackager )
				)
				( attribute "PNN" "M_D_DQ<37>"
					( Origin gPackager )
				)
				( objectStatus "M_D_DQ<37>" )
			)
			( signal "@baseboard_fab2_lib.baseboard_fab2(sch_1):m_d_dq(38)"
				( attribute "CDS_PHYS_NET_NAME" "M_D_DQ<38>"
					( Origin gPackager )
				)
				( attribute "PNN" "M_D_DQ<38>"
					( Origin gPackager )
				)
				( objectStatus "M_D_DQ<38>" )
			)
			( signal "@baseboard_fab2_lib.baseboard_fab2(sch_1):m_d_dq(39)"
				( attribute "CDS_PHYS_NET_NAME" "M_D_DQ<39>"
					( Origin gPackager )
				)
				( attribute "PNN" "M_D_DQ<39>"
					( Origin gPackager )
				)
				( objectStatus "M_D_DQ<39>" )
			)
			( signal "@baseboard_fab2_lib.baseboard_fab2(sch_1):m_d_dq(40)"
				( attribute "CDS_PHYS_NET_NAME" "M_D_DQ<40>"
					( Origin gPackager )
				)
				( attribute "PNN" "M_D_DQ<40>"
					( Origin gPackager )
				)
				( objectStatus "M_D_DQ<40>" )
			)
			( signal "@baseboard_fab2_lib.baseboard_fab2(sch_1):m_d_dq(41)"
				( attribute "CDS_PHYS_NET_NAME" "M_D_DQ<41>"
					( Origin gPackager )
				)
				( attribute "PNN" "M_D_DQ<41>"
					( Origin gPackager )
				)
				( objectStatus "M_D_DQ<41>" )
			)
			( signal "@baseboard_fab2_lib.baseboard_fab2(sch_1):m_d_dq(42)"
				( attribute "CDS_PHYS_NET_NAME" "M_D_DQ<42>"
					( Origin gPackager )
				)
				( attribute "PNN" "M_D_DQ<42>"
					( Origin gPackager )
				)
				( objectStatus "M_D_DQ<42>" )
			)
			( signal "@baseboard_fab2_lib.baseboard_fab2(sch_1):m_d_dq(43)"
				( attribute "CDS_PHYS_NET_NAME" "M_D_DQ<43>"
					( Origin gPackager )
				)
				( attribute "PNN" "M_D_DQ<43>"
					( Origin gPackager )
				)
				( objectStatus "M_D_DQ<43>" )
			)
			( signal "@baseboard_fab2_lib.baseboard_fab2(sch_1):m_d_dq(44)"
				( attribute "CDS_PHYS_NET_NAME" "M_D_DQ<44>"
					( Origin gPackager )
				)
				( attribute "PNN" "M_D_DQ<44>"
					( Origin gPackager )
				)
				( objectStatus "M_D_DQ<44>" )
			)
			( signal "@baseboard_fab2_lib.baseboard_fab2(sch_1):m_d_dq(45)"
				( attribute "CDS_PHYS_NET_NAME" "M_D_DQ<45>"
					( Origin gPackager )
				)
				( attribute "PNN" "M_D_DQ<45>"
					( Origin gPackager )
				)
				( objectStatus "M_D_DQ<45>" )
			)
			( signal "@baseboard_fab2_lib.baseboard_fab2(sch_1):m_d_dq(46)"
				( attribute "CDS_PHYS_NET_NAME" "M_D_DQ<46>"
					( Origin gPackager )
				)
				( attribute "PNN" "M_D_DQ<46>"
					( Origin gPackager )
				)
				( objectStatus "M_D_DQ<46>" )
			)
			( signal "@baseboard_fab2_lib.baseboard_fab2(sch_1):m_d_dq(47)"
				( attribute "CDS_PHYS_NET_NAME" "M_D_DQ<47>"
					( Origin gPackager )
				)
				( attribute "PNN" "M_D_DQ<47>"
					( Origin gPackager )
				)
				( objectStatus "M_D_DQ<47>" )
			)
			( signal "@baseboard_fab2_lib.baseboard_fab2(sch_1):m_d_dq(48)"
				( attribute "CDS_PHYS_NET_NAME" "M_D_DQ<48>"
					( Origin gPackager )
				)
				( attribute "PNN" "M_D_DQ<48>"
					( Origin gPackager )
				)
				( objectStatus "M_D_DQ<48>" )
			)
			( signal "@baseboard_fab2_lib.baseboard_fab2(sch_1):m_d_dq(49)"
				( attribute "CDS_PHYS_NET_NAME" "M_D_DQ<49>"
					( Origin gPackager )
				)
				( attribute "PNN" "M_D_DQ<49>"
					( Origin gPackager )
				)
				( objectStatus "M_D_DQ<49>" )
			)
			( signal "@baseboard_fab2_lib.baseboard_fab2(sch_1):m_d_dq(50)"
				( attribute "CDS_PHYS_NET_NAME" "M_D_DQ<50>"
					( Origin gPackager )
				)
				( attribute "PNN" "M_D_DQ<50>"
					( Origin gPackager )
				)
				( objectStatus "M_D_DQ<50>" )
			)
			( signal "@baseboard_fab2_lib.baseboard_fab2(sch_1):m_d_dq(51)"
				( attribute "CDS_PHYS_NET_NAME" "M_D_DQ<51>"
					( Origin gPackager )
				)
				( attribute "PNN" "M_D_DQ<51>"
					( Origin gPackager )
				)
				( objectStatus "M_D_DQ<51>" )
			)
			( signal "@baseboard_fab2_lib.baseboard_fab2(sch_1):m_d_dq(52)"
				( attribute "CDS_PHYS_NET_NAME" "M_D_DQ<52>"
					( Origin gPackager )
				)
				( attribute "PNN" "M_D_DQ<52>"
					( Origin gPackager )
				)
				( objectStatus "M_D_DQ<52>" )
			)
			( signal "@baseboard_fab2_lib.baseboard_fab2(sch_1):m_d_dq(53)"
				( attribute "CDS_PHYS_NET_NAME" "M_D_DQ<53>"
					( Origin gPackager )
				)
				( attribute "PNN" "M_D_DQ<53>"
					( Origin gPackager )
				)
				( objectStatus "M_D_DQ<53>" )
			)
			( signal "@baseboard_fab2_lib.baseboard_fab2(sch_1):m_d_dq(54)"
				( attribute "CDS_PHYS_NET_NAME" "M_D_DQ<54>"
					( Origin gPackager )
				)
				( attribute "PNN" "M_D_DQ<54>"
					( Origin gPackager )
				)
				( objectStatus "M_D_DQ<54>" )
			)
			( signal "@baseboard_fab2_lib.baseboard_fab2(sch_1):m_d_dq(55)"
				( attribute "CDS_PHYS_NET_NAME" "M_D_DQ<55>"
					( Origin gPackager )
				)
				( attribute "PNN" "M_D_DQ<55>"
					( Origin gPackager )
				)
				( objectStatus "M_D_DQ<55>" )
			)
			( signal "@baseboard_fab2_lib.baseboard_fab2(sch_1):m_d_dq(56)"
				( attribute "CDS_PHYS_NET_NAME" "M_D_DQ<56>"
					( Origin gPackager )
				)
				( attribute "PNN" "M_D_DQ<56>"
					( Origin gPackager )
				)
				( objectStatus "M_D_DQ<56>" )
			)
			( signal "@baseboard_fab2_lib.baseboard_fab2(sch_1):m_d_dq(57)"
				( attribute "CDS_PHYS_NET_NAME" "M_D_DQ<57>"
					( Origin gPackager )
				)
				( attribute "PNN" "M_D_DQ<57>"
					( Origin gPackager )
				)
				( objectStatus "M_D_DQ<57>" )
			)
			( signal "@baseboard_fab2_lib.baseboard_fab2(sch_1):m_d_dq(58)"
				( attribute "CDS_PHYS_NET_NAME" "M_D_DQ<58>"
					( Origin gPackager )
				)
				( attribute "PNN" "M_D_DQ<58>"
					( Origin gPackager )
				)
				( objectStatus "M_D_DQ<58>" )
			)
			( signal "@baseboard_fab2_lib.baseboard_fab2(sch_1):m_d_dq(59)"
				( attribute "CDS_PHYS_NET_NAME" "M_D_DQ<59>"
					( Origin gPackager )
				)
				( attribute "PNN" "M_D_DQ<59>"
					( Origin gPackager )
				)
				( objectStatus "M_D_DQ<59>" )
			)
			( signal "@baseboard_fab2_lib.baseboard_fab2(sch_1):m_d_dq(60)"
				( attribute "CDS_PHYS_NET_NAME" "M_D_DQ<60>"
					( Origin gPackager )
				)
				( attribute "PNN" "M_D_DQ<60>"
					( Origin gPackager )
				)
				( objectStatus "M_D_DQ<60>" )
			)
			( signal "@baseboard_fab2_lib.baseboard_fab2(sch_1):m_d_dq(61)"
				( attribute "CDS_PHYS_NET_NAME" "M_D_DQ<61>"
					( Origin gPackager )
				)
				( attribute "PNN" "M_D_DQ<61>"
					( Origin gPackager )
				)
				( objectStatus "M_D_DQ<61>" )
			)
			( signal "@baseboard_fab2_lib.baseboard_fab2(sch_1):m_d_dq(62)"
				( attribute "CDS_PHYS_NET_NAME" "M_D_DQ<62>"
					( Origin gPackager )
				)
				( attribute "PNN" "M_D_DQ<62>"
					( Origin gPackager )
				)
				( objectStatus "M_D_DQ<62>" )
			)
			( signal "@baseboard_fab2_lib.baseboard_fab2(sch_1):m_d_dq(63)"
				( attribute "CDS_PHYS_NET_NAME" "M_D_DQ<63>"
					( Origin gPackager )
				)
				( attribute "PNN" "M_D_DQ<63>"
					( Origin gPackager )
				)
				( objectStatus "M_D_DQ<63>" )
			)
			( signal "@baseboard_fab2_lib.baseboard_fab2(sch_1):m_d_dqs_dn(0)"
				( attribute "CDS_PHYS_NET_NAME" "M_D_DQS_DN<0>"
					( Origin gPackager )
				)
				( attribute "PNN" "M_D_DQS_DN<0>"
					( Origin gPackager )
				)
				( objectStatus "M_D_DQS_DN<0>" )
			)
			( signal "@baseboard_fab2_lib.baseboard_fab2(sch_1):m_d_dqs_dn(1)"
				( attribute "CDS_PHYS_NET_NAME" "M_D_DQS_DN<1>"
					( Origin gPackager )
				)
				( attribute "PNN" "M_D_DQS_DN<1>"
					( Origin gPackager )
				)
				( objectStatus "M_D_DQS_DN<1>" )
			)
			( signal "@baseboard_fab2_lib.baseboard_fab2(sch_1):m_d_dqs_dn(2)"
				( attribute "CDS_PHYS_NET_NAME" "M_D_DQS_DN<2>"
					( Origin gPackager )
				)
				( attribute "PNN" "M_D_DQS_DN<2>"
					( Origin gPackager )
				)
				( objectStatus "M_D_DQS_DN<2>" )
			)
			( signal "@baseboard_fab2_lib.baseboard_fab2(sch_1):m_d_dqs_dn(3)"
				( attribute "CDS_PHYS_NET_NAME" "M_D_DQS_DN<3>"
					( Origin gPackager )
				)
				( attribute "PNN" "M_D_DQS_DN<3>"
					( Origin gPackager )
				)
				( objectStatus "M_D_DQS_DN<3>" )
			)
			( signal "@baseboard_fab2_lib.baseboard_fab2(sch_1):m_d_dqs_dn(4)"
				( attribute "CDS_PHYS_NET_NAME" "M_D_DQS_DN<4>"
					( Origin gPackager )
				)
				( attribute "PNN" "M_D_DQS_DN<4>"
					( Origin gPackager )
				)
				( objectStatus "M_D_DQS_DN<4>" )
			)
			( signal "@baseboard_fab2_lib.baseboard_fab2(sch_1):m_d_dqs_dn(5)"
				( attribute "CDS_PHYS_NET_NAME" "M_D_DQS_DN<5>"
					( Origin gPackager )
				)
				( attribute "PNN" "M_D_DQS_DN<5>"
					( Origin gPackager )
				)
				( objectStatus "M_D_DQS_DN<5>" )
			)
			( signal "@baseboard_fab2_lib.baseboard_fab2(sch_1):m_d_dqs_dn(6)"
				( attribute "CDS_PHYS_NET_NAME" "M_D_DQS_DN<6>"
					( Origin gPackager )
				)
				( attribute "PNN" "M_D_DQS_DN<6>"
					( Origin gPackager )
				)
				( objectStatus "M_D_DQS_DN<6>" )
			)
			( signal "@baseboard_fab2_lib.baseboard_fab2(sch_1):m_d_dqs_dn(7)"
				( attribute "CDS_PHYS_NET_NAME" "M_D_DQS_DN<7>"
					( Origin gPackager )
				)
				( attribute "PNN" "M_D_DQS_DN<7>"
					( Origin gPackager )
				)
				( objectStatus "M_D_DQS_DN<7>" )
			)
			( signal "@baseboard_fab2_lib.baseboard_fab2(sch_1):m_d_dqs_dn(8)"
				( attribute "CDS_PHYS_NET_NAME" "M_D_DQS_DN<8>"
					( Origin gPackager )
				)
				( attribute "PNN" "M_D_DQS_DN<8>"
					( Origin gPackager )
				)
				( objectStatus "M_D_DQS_DN<8>" )
			)
			( signal "@baseboard_fab2_lib.baseboard_fab2(sch_1):m_d_dqs_dn(9)"
				( attribute "CDS_PHYS_NET_NAME" "M_D_DQS_DN<9>"
					( Origin gPackager )
				)
				( attribute "PNN" "M_D_DQS_DN<9>"
					( Origin gPackager )
				)
				( objectStatus "M_D_DQS_DN<9>" )
			)
			( signal "@baseboard_fab2_lib.baseboard_fab2(sch_1):m_d_dqs_dn(10)"
				( attribute "CDS_PHYS_NET_NAME" "M_D_DQS_DN<10>"
					( Origin gPackager )
				)
				( attribute "PNN" "M_D_DQS_DN<10>"
					( Origin gPackager )
				)
				( objectStatus "M_D_DQS_DN<10>" )
			)
			( signal "@baseboard_fab2_lib.baseboard_fab2(sch_1):m_d_dqs_dn(11)"
				( attribute "CDS_PHYS_NET_NAME" "M_D_DQS_DN<11>"
					( Origin gPackager )
				)
				( attribute "PNN" "M_D_DQS_DN<11>"
					( Origin gPackager )
				)
				( objectStatus "M_D_DQS_DN<11>" )
			)
			( signal "@baseboard_fab2_lib.baseboard_fab2(sch_1):m_d_dqs_dn(12)"
				( attribute "CDS_PHYS_NET_NAME" "M_D_DQS_DN<12>"
					( Origin gPackager )
				)
				( attribute "PNN" "M_D_DQS_DN<12>"
					( Origin gPackager )
				)
				( objectStatus "M_D_DQS_DN<12>" )
			)
			( signal "@baseboard_fab2_lib.baseboard_fab2(sch_1):m_d_dqs_dn(13)"
				( attribute "CDS_PHYS_NET_NAME" "M_D_DQS_DN<13>"
					( Origin gPackager )
				)
				( attribute "PNN" "M_D_DQS_DN<13>"
					( Origin gPackager )
				)
				( objectStatus "M_D_DQS_DN<13>" )
			)
			( signal "@baseboard_fab2_lib.baseboard_fab2(sch_1):m_d_dqs_dn(14)"
				( attribute "CDS_PHYS_NET_NAME" "M_D_DQS_DN<14>"
					( Origin gPackager )
				)
				( attribute "PNN" "M_D_DQS_DN<14>"
					( Origin gPackager )
				)
				( objectStatus "M_D_DQS_DN<14>" )
			)
			( signal "@baseboard_fab2_lib.baseboard_fab2(sch_1):m_d_dqs_dn(15)"
				( attribute "CDS_PHYS_NET_NAME" "M_D_DQS_DN<15>"
					( Origin gPackager )
				)
				( attribute "PNN" "M_D_DQS_DN<15>"
					( Origin gPackager )
				)
				( objectStatus "M_D_DQS_DN<15>" )
			)
			( signal "@baseboard_fab2_lib.baseboard_fab2(sch_1):m_d_dqs_dn(16)"
				( attribute "CDS_PHYS_NET_NAME" "M_D_DQS_DN<16>"
					( Origin gPackager )
				)
				( attribute "PNN" "M_D_DQS_DN<16>"
					( Origin gPackager )
				)
				( objectStatus "M_D_DQS_DN<16>" )
			)
			( signal "@baseboard_fab2_lib.baseboard_fab2(sch_1):m_d_dqs_dn(17)"
				( attribute "CDS_PHYS_NET_NAME" "M_D_DQS_DN<17>"
					( Origin gPackager )
				)
				( attribute "PNN" "M_D_DQS_DN<17>"
					( Origin gPackager )
				)
				( objectStatus "M_D_DQS_DN<17>" )
			)
			( signal "@baseboard_fab2_lib.baseboard_fab2(sch_1):m_d_dqs_dp(0)"
				( attribute "CDS_PHYS_NET_NAME" "M_D_DQS_DP<0>"
					( Origin gPackager )
				)
				( attribute "PNN" "M_D_DQS_DP<0>"
					( Origin gPackager )
				)
				( objectStatus "M_D_DQS_DP<0>" )
			)
			( signal "@baseboard_fab2_lib.baseboard_fab2(sch_1):m_d_dqs_dp(1)"
				( attribute "CDS_PHYS_NET_NAME" "M_D_DQS_DP<1>"
					( Origin gPackager )
				)
				( attribute "PNN" "M_D_DQS_DP<1>"
					( Origin gPackager )
				)
				( objectStatus "M_D_DQS_DP<1>" )
			)
			( signal "@baseboard_fab2_lib.baseboard_fab2(sch_1):m_d_dqs_dp(2)"
				( attribute "CDS_PHYS_NET_NAME" "M_D_DQS_DP<2>"
					( Origin gPackager )
				)
				( attribute "PNN" "M_D_DQS_DP<2>"
					( Origin gPackager )
				)
				( objectStatus "M_D_DQS_DP<2>" )
			)
			( signal "@baseboard_fab2_lib.baseboard_fab2(sch_1):m_d_dqs_dp(3)"
				( attribute "CDS_PHYS_NET_NAME" "M_D_DQS_DP<3>"
					( Origin gPackager )
				)
				( attribute "PNN" "M_D_DQS_DP<3>"
					( Origin gPackager )
				)
				( objectStatus "M_D_DQS_DP<3>" )
			)
			( signal "@baseboard_fab2_lib.baseboard_fab2(sch_1):m_d_dqs_dp(4)"
				( attribute "CDS_PHYS_NET_NAME" "M_D_DQS_DP<4>"
					( Origin gPackager )
				)
				( attribute "PNN" "M_D_DQS_DP<4>"
					( Origin gPackager )
				)
				( objectStatus "M_D_DQS_DP<4>" )
			)
			( signal "@baseboard_fab2_lib.baseboard_fab2(sch_1):m_d_dqs_dp(5)"
				( attribute "CDS_PHYS_NET_NAME" "M_D_DQS_DP<5>"
					( Origin gPackager )
				)
				( attribute "PNN" "M_D_DQS_DP<5>"
					( Origin gPackager )
				)
				( objectStatus "M_D_DQS_DP<5>" )
			)
			( signal "@baseboard_fab2_lib.baseboard_fab2(sch_1):m_d_dqs_dp(6)"
				( attribute "CDS_PHYS_NET_NAME" "M_D_DQS_DP<6>"
					( Origin gPackager )
				)
				( attribute "PNN" "M_D_DQS_DP<6>"
					( Origin gPackager )
				)
				( objectStatus "M_D_DQS_DP<6>" )
			)
			( signal "@baseboard_fab2_lib.baseboard_fab2(sch_1):m_d_dqs_dp(7)"
				( attribute "CDS_PHYS_NET_NAME" "M_D_DQS_DP<7>"
					( Origin gPackager )
				)
				( attribute "PNN" "M_D_DQS_DP<7>"
					( Origin gPackager )
				)
				( objectStatus "M_D_DQS_DP<7>" )
			)
			( signal "@baseboard_fab2_lib.baseboard_fab2(sch_1):m_d_dqs_dp(8)"
				( attribute "CDS_PHYS_NET_NAME" "M_D_DQS_DP<8>"
					( Origin gPackager )
				)
				( attribute "PNN" "M_D_DQS_DP<8>"
					( Origin gPackager )
				)
				( objectStatus "M_D_DQS_DP<8>" )
			)
			( signal "@baseboard_fab2_lib.baseboard_fab2(sch_1):m_d_dqs_dp(9)"
				( attribute "CDS_PHYS_NET_NAME" "M_D_DQS_DP<9>"
					( Origin gPackager )
				)
				( attribute "PNN" "M_D_DQS_DP<9>"
					( Origin gPackager )
				)
				( objectStatus "M_D_DQS_DP<9>" )
			)
			( signal "@baseboard_fab2_lib.baseboard_fab2(sch_1):m_d_dqs_dp(10)"
				( attribute "CDS_PHYS_NET_NAME" "M_D_DQS_DP<10>"
					( Origin gPackager )
				)
				( attribute "PNN" "M_D_DQS_DP<10>"
					( Origin gPackager )
				)
				( objectStatus "M_D_DQS_DP<10>" )
			)
			( signal "@baseboard_fab2_lib.baseboard_fab2(sch_1):m_d_dqs_dp(11)"
				( attribute "CDS_PHYS_NET_NAME" "M_D_DQS_DP<11>"
					( Origin gPackager )
				)
				( attribute "PNN" "M_D_DQS_DP<11>"
					( Origin gPackager )
				)
				( objectStatus "M_D_DQS_DP<11>" )
			)
			( signal "@baseboard_fab2_lib.baseboard_fab2(sch_1):m_d_dqs_dp(12)"
				( attribute "CDS_PHYS_NET_NAME" "M_D_DQS_DP<12>"
					( Origin gPackager )
				)
				( attribute "PNN" "M_D_DQS_DP<12>"
					( Origin gPackager )
				)
				( objectStatus "M_D_DQS_DP<12>" )
			)
			( signal "@baseboard_fab2_lib.baseboard_fab2(sch_1):m_d_dqs_dp(13)"
				( attribute "CDS_PHYS_NET_NAME" "M_D_DQS_DP<13>"
					( Origin gPackager )
				)
				( attribute "PNN" "M_D_DQS_DP<13>"
					( Origin gPackager )
				)
				( objectStatus "M_D_DQS_DP<13>" )
			)
			( signal "@baseboard_fab2_lib.baseboard_fab2(sch_1):m_d_dqs_dp(14)"
				( attribute "CDS_PHYS_NET_NAME" "M_D_DQS_DP<14>"
					( Origin gPackager )
				)
				( attribute "PNN" "M_D_DQS_DP<14>"
					( Origin gPackager )
				)
				( objectStatus "M_D_DQS_DP<14>" )
			)
			( signal "@baseboard_fab2_lib.baseboard_fab2(sch_1):m_d_dqs_dp(15)"
				( attribute "CDS_PHYS_NET_NAME" "M_D_DQS_DP<15>"
					( Origin gPackager )
				)
				( attribute "PNN" "M_D_DQS_DP<15>"
					( Origin gPackager )
				)
				( objectStatus "M_D_DQS_DP<15>" )
			)
			( signal "@baseboard_fab2_lib.baseboard_fab2(sch_1):m_d_dqs_dp(16)"
				( attribute "CDS_PHYS_NET_NAME" "M_D_DQS_DP<16>"
					( Origin gPackager )
				)
				( attribute "PNN" "M_D_DQS_DP<16>"
					( Origin gPackager )
				)
				( objectStatus "M_D_DQS_DP<16>" )
			)
			( signal "@baseboard_fab2_lib.baseboard_fab2(sch_1):m_d_dqs_dp(17)"
				( attribute "CDS_PHYS_NET_NAME" "M_D_DQS_DP<17>"
					( Origin gPackager )
				)
				( attribute "PNN" "M_D_DQS_DP<17>"
					( Origin gPackager )
				)
				( objectStatus "M_D_DQS_DP<17>" )
			)
			( signal "@baseboard_fab2_lib.baseboard_fab2(sch_1):m_d_ecc(0)"
				( attribute "CDS_PHYS_NET_NAME" "M_D_ECC<0>"
					( Origin gPackager )
				)
				( attribute "PNN" "M_D_ECC<0>"
					( Origin gPackager )
				)
				( objectStatus "M_D_ECC<0>" )
			)
			( signal "@baseboard_fab2_lib.baseboard_fab2(sch_1):m_d_ecc(1)"
				( attribute "CDS_PHYS_NET_NAME" "M_D_ECC<1>"
					( Origin gPackager )
				)
				( attribute "PNN" "M_D_ECC<1>"
					( Origin gPackager )
				)
				( objectStatus "M_D_ECC<1>" )
			)
			( signal "@baseboard_fab2_lib.baseboard_fab2(sch_1):m_d_ecc(2)"
				( attribute "CDS_PHYS_NET_NAME" "M_D_ECC<2>"
					( Origin gPackager )
				)
				( attribute "PNN" "M_D_ECC<2>"
					( Origin gPackager )
				)
				( objectStatus "M_D_ECC<2>" )
			)
			( signal "@baseboard_fab2_lib.baseboard_fab2(sch_1):m_d_ecc(3)"
				( attribute "CDS_PHYS_NET_NAME" "M_D_ECC<3>"
					( Origin gPackager )
				)
				( attribute "PNN" "M_D_ECC<3>"
					( Origin gPackager )
				)
				( objectStatus "M_D_ECC<3>" )
			)
			( signal "@baseboard_fab2_lib.baseboard_fab2(sch_1):m_d_ecc(4)"
				( attribute "CDS_PHYS_NET_NAME" "M_D_ECC<4>"
					( Origin gPackager )
				)
				( attribute "PNN" "M_D_ECC<4>"
					( Origin gPackager )
				)
				( objectStatus "M_D_ECC<4>" )
			)
			( signal "@baseboard_fab2_lib.baseboard_fab2(sch_1):m_d_ecc(5)"
				( attribute "CDS_PHYS_NET_NAME" "M_D_ECC<5>"
					( Origin gPackager )
				)
				( attribute "PNN" "M_D_ECC<5>"
					( Origin gPackager )
				)
				( objectStatus "M_D_ECC<5>" )
			)
			( signal "@baseboard_fab2_lib.baseboard_fab2(sch_1):m_d_ecc(6)"
				( attribute "CDS_PHYS_NET_NAME" "M_D_ECC<6>"
					( Origin gPackager )
				)
				( attribute "PNN" "M_D_ECC<6>"
					( Origin gPackager )
				)
				( objectStatus "M_D_ECC<6>" )
			)
			( signal "@baseboard_fab2_lib.baseboard_fab2(sch_1):m_d_ecc(7)"
				( attribute "CDS_PHYS_NET_NAME" "M_D_ECC<7>"
					( Origin gPackager )
				)
				( attribute "PNN" "M_D_ECC<7>"
					( Origin gPackager )
				)
				( objectStatus "M_D_ECC<7>" )
			)
			( signal "@baseboard_fab2_lib.baseboard_fab2(sch_1):m_d_ma(0)"
				( attribute "CDS_PHYS_NET_NAME" "M_D_MA<0>"
					( Origin gPackager )
				)
				( attribute "PNN" "M_D_MA<0>"
					( Origin gPackager )
				)
				( objectStatus "M_D_MA<0>" )
			)
			( signal "@baseboard_fab2_lib.baseboard_fab2(sch_1):m_d_ma(1)"
				( attribute "CDS_PHYS_NET_NAME" "M_D_MA<1>"
					( Origin gPackager )
				)
				( attribute "PNN" "M_D_MA<1>"
					( Origin gPackager )
				)
				( objectStatus "M_D_MA<1>" )
			)
			( signal "@baseboard_fab2_lib.baseboard_fab2(sch_1):m_d_ma(2)"
				( attribute "CDS_PHYS_NET_NAME" "M_D_MA<2>"
					( Origin gPackager )
				)
				( attribute "PNN" "M_D_MA<2>"
					( Origin gPackager )
				)
				( objectStatus "M_D_MA<2>" )
			)
			( signal "@baseboard_fab2_lib.baseboard_fab2(sch_1):m_d_ma(3)"
				( attribute "CDS_PHYS_NET_NAME" "M_D_MA<3>"
					( Origin gPackager )
				)
				( attribute "PNN" "M_D_MA<3>"
					( Origin gPackager )
				)
				( objectStatus "M_D_MA<3>" )
			)
			( signal "@baseboard_fab2_lib.baseboard_fab2(sch_1):m_d_ma(4)"
				( attribute "CDS_PHYS_NET_NAME" "M_D_MA<4>"
					( Origin gPackager )
				)
				( attribute "PNN" "M_D_MA<4>"
					( Origin gPackager )
				)
				( objectStatus "M_D_MA<4>" )
			)
			( signal "@baseboard_fab2_lib.baseboard_fab2(sch_1):m_d_ma(5)"
				( attribute "CDS_PHYS_NET_NAME" "M_D_MA<5>"
					( Origin gPackager )
				)
				( attribute "PNN" "M_D_MA<5>"
					( Origin gPackager )
				)
				( objectStatus "M_D_MA<5>" )
			)
			( signal "@baseboard_fab2_lib.baseboard_fab2(sch_1):m_d_ma(6)"
				( attribute "CDS_PHYS_NET_NAME" "M_D_MA<6>"
					( Origin gPackager )
				)
				( attribute "PNN" "M_D_MA<6>"
					( Origin gPackager )
				)
				( objectStatus "M_D_MA<6>" )
			)
			( signal "@baseboard_fab2_lib.baseboard_fab2(sch_1):m_d_ma(7)"
				( attribute "CDS_PHYS_NET_NAME" "M_D_MA<7>"
					( Origin gPackager )
				)
				( attribute "PNN" "M_D_MA<7>"
					( Origin gPackager )
				)
				( objectStatus "M_D_MA<7>" )
			)
			( signal "@baseboard_fab2_lib.baseboard_fab2(sch_1):m_d_ma(8)"
				( attribute "CDS_PHYS_NET_NAME" "M_D_MA<8>"
					( Origin gPackager )
				)
				( attribute "PNN" "M_D_MA<8>"
					( Origin gPackager )
				)
				( objectStatus "M_D_MA<8>" )
			)
			( signal "@baseboard_fab2_lib.baseboard_fab2(sch_1):m_d_ma(9)"
				( attribute "CDS_PHYS_NET_NAME" "M_D_MA<9>"
					( Origin gPackager )
				)
				( attribute "PNN" "M_D_MA<9>"
					( Origin gPackager )
				)
				( objectStatus "M_D_MA<9>" )
			)
			( signal "@baseboard_fab2_lib.baseboard_fab2(sch_1):m_d_ma(10)"
				( attribute "CDS_PHYS_NET_NAME" "M_D_MA<10>"
					( Origin gPackager )
				)
				( attribute "PNN" "M_D_MA<10>"
					( Origin gPackager )
				)
				( objectStatus "M_D_MA<10>" )
			)
			( signal "@baseboard_fab2_lib.baseboard_fab2(sch_1):m_d_ma(11)"
				( attribute "CDS_PHYS_NET_NAME" "M_D_MA<11>"
					( Origin gPackager )
				)
				( attribute "PNN" "M_D_MA<11>"
					( Origin gPackager )
				)
				( objectStatus "M_D_MA<11>" )
			)
			( signal "@baseboard_fab2_lib.baseboard_fab2(sch_1):m_d_ma(12)"
				( attribute "CDS_PHYS_NET_NAME" "M_D_MA<12>"
					( Origin gPackager )
				)
				( attribute "PNN" "M_D_MA<12>"
					( Origin gPackager )
				)
				( objectStatus "M_D_MA<12>" )
			)
			( signal "@baseboard_fab2_lib.baseboard_fab2(sch_1):m_d_ma(13)"
				( attribute "CDS_PHYS_NET_NAME" "M_D_MA<13>"
					( Origin gPackager )
				)
				( attribute "PNN" "M_D_MA<13>"
					( Origin gPackager )
				)
				( objectStatus "M_D_MA<13>" )
			)
			( signal "@baseboard_fab2_lib.baseboard_fab2(sch_1):m_d_ma(14)"
				( attribute "CDS_PHYS_NET_NAME" "M_D_MA<14>"
					( Origin gPackager )
				)
				( attribute "PNN" "M_D_MA<14>"
					( Origin gPackager )
				)
				( objectStatus "M_D_MA<14>" )
			)
			( signal "@baseboard_fab2_lib.baseboard_fab2(sch_1):m_d_ma(15)"
				( attribute "CDS_PHYS_NET_NAME" "M_D_MA<15>"
					( Origin gPackager )
				)
				( attribute "PNN" "M_D_MA<15>"
					( Origin gPackager )
				)
				( objectStatus "M_D_MA<15>" )
			)
			( signal "@baseboard_fab2_lib.baseboard_fab2(sch_1):m_d_ma(16)"
				( attribute "CDS_PHYS_NET_NAME" "M_D_MA<16>"
					( Origin gPackager )
				)
				( attribute "PNN" "M_D_MA<16>"
					( Origin gPackager )
				)
				( objectStatus "M_D_MA<16>" )
			)
			( signal "@baseboard_fab2_lib.baseboard_fab2(sch_1):m_d_ma(17)"
				( attribute "CDS_PHYS_NET_NAME" "M_D_MA<17>"
					( Origin gPackager )
				)
				( attribute "PNN" "M_D_MA<17>"
					( Origin gPackager )
				)
				( objectStatus "M_D_MA<17>" )
			)
			( signal "@baseboard_fab2_lib.baseboard_fab2(sch_1):m_d_odt(0)"
				( attribute "CDS_PHYS_NET_NAME" "M_D_ODT<0>"
					( Origin gPackager )
				)
				( attribute "PNN" "M_D_ODT<0>"
					( Origin gPackager )
				)
				( objectStatus "M_D_ODT<0>" )
			)
			( signal "@baseboard_fab2_lib.baseboard_fab2(sch_1):m_d_odt(1)"
				( attribute "CDS_PHYS_NET_NAME" "M_D_ODT<1>"
					( Origin gPackager )
				)
				( attribute "PNN" "M_D_ODT<1>"
					( Origin gPackager )
				)
				( objectStatus "M_D_ODT<1>" )
			)
			( signal "@baseboard_fab2_lib.baseboard_fab2(sch_1):m_d_odt(2)"
				( attribute "CDS_PHYS_NET_NAME" "M_D_ODT<2>"
					( Origin gPackager )
				)
				( attribute "PNN" "M_D_ODT<2>"
					( Origin gPackager )
				)
				( objectStatus "M_D_ODT<2>" )
			)
			( signal "@baseboard_fab2_lib.baseboard_fab2(sch_1):m_d_odt(3)"
				( attribute "CDS_PHYS_NET_NAME" "M_D_ODT<3>"
					( Origin gPackager )
				)
				( attribute "PNN" "M_D_ODT<3>"
					( Origin gPackager )
				)
				( objectStatus "M_D_ODT<3>" )
			)
			( signal "@baseboard_fab2_lib.baseboard_fab2(sch_1):m_d_par"
				( attribute "CDS_PHYS_NET_NAME" "M_D_PAR"
					( Origin gPackager )
				)
				( objectStatus "M_D_PAR" )
			)
			( signal "@baseboard_fab2_lib.baseboard_fab2(sch_1):m_e_act_n"
				( attribute "CDS_PHYS_NET_NAME" "M_E_ACT_N"
					( Origin gPackager )
				)
				( objectStatus "M_E_ACT_N" )
			)
			( signal "@baseboard_fab2_lib.baseboard_fab2(sch_1):m_e_alert_n"
				( attribute "CDS_PHYS_NET_NAME" "M_E_ALERT_N"
					( Origin gPackager )
				)
				( objectStatus "M_E_ALERT_N" )
			)
			( signal "@baseboard_fab2_lib.baseboard_fab2(sch_1):m_e_ba(0)"
				( attribute "CDS_PHYS_NET_NAME" "M_E_BA<0>"
					( Origin gPackager )
				)
				( attribute "PNN" "M_E_BA<0>"
					( Origin gPackager )
				)
				( objectStatus "M_E_BA<0>" )
			)
			( signal "@baseboard_fab2_lib.baseboard_fab2(sch_1):m_e_ba(1)"
				( attribute "CDS_PHYS_NET_NAME" "M_E_BA<1>"
					( Origin gPackager )
				)
				( attribute "PNN" "M_E_BA<1>"
					( Origin gPackager )
				)
				( objectStatus "M_E_BA<1>" )
			)
			( signal "@baseboard_fab2_lib.baseboard_fab2(sch_1):m_e_bg(0)"
				( attribute "CDS_PHYS_NET_NAME" "M_E_BG<0>"
					( Origin gPackager )
				)
				( attribute "PNN" "M_E_BG<0>"
					( Origin gPackager )
				)
				( objectStatus "M_E_BG<0>" )
			)
			( signal "@baseboard_fab2_lib.baseboard_fab2(sch_1):m_e_bg(1)"
				( attribute "CDS_PHYS_NET_NAME" "M_E_BG<1>"
					( Origin gPackager )
				)
				( attribute "PNN" "M_E_BG<1>"
					( Origin gPackager )
				)
				( objectStatus "M_E_BG<1>" )
			)
			( signal "@baseboard_fab2_lib.baseboard_fab2(sch_1):m_e_c(2)"
				( attribute "CDS_PHYS_NET_NAME" "M_E_C<2>"
					( Origin gPackager )
				)
				( attribute "PNN" "M_E_C<2>"
					( Origin gPackager )
				)
				( objectStatus "M_E_C<2>" )
			)
			( signal "@baseboard_fab2_lib.baseboard_fab2(sch_1):m_e_cke(0)"
				( attribute "CDS_PHYS_NET_NAME" "M_E_CKE<0>"
					( Origin gPackager )
				)
				( attribute "PNN" "M_E_CKE<0>"
					( Origin gPackager )
				)
				( objectStatus "M_E_CKE<0>" )
			)
			( signal "@baseboard_fab2_lib.baseboard_fab2(sch_1):m_e_cke(1)"
				( attribute "CDS_PHYS_NET_NAME" "M_E_CKE<1>"
					( Origin gPackager )
				)
				( attribute "PNN" "M_E_CKE<1>"
					( Origin gPackager )
				)
				( objectStatus "M_E_CKE<1>" )
			)
			( signal "@baseboard_fab2_lib.baseboard_fab2(sch_1):m_e_cke(2)"
				( attribute "CDS_PHYS_NET_NAME" "M_E_CKE<2>"
					( Origin gPackager )
				)
				( attribute "PNN" "M_E_CKE<2>"
					( Origin gPackager )
				)
				( objectStatus "M_E_CKE<2>" )
			)
			( signal "@baseboard_fab2_lib.baseboard_fab2(sch_1):m_e_cke(3)"
				( attribute "CDS_PHYS_NET_NAME" "M_E_CKE<3>"
					( Origin gPackager )
				)
				( attribute "PNN" "M_E_CKE<3>"
					( Origin gPackager )
				)
				( objectStatus "M_E_CKE<3>" )
			)
			( signal "@baseboard_fab2_lib.baseboard_fab2(sch_1):m_e_clk_dn(0)"
				( attribute "CDS_PHYS_NET_NAME" "M_E_CLK_DN<0>"
					( Origin gPackager )
				)
				( attribute "PNN" "M_E_CLK_DN<0>"
					( Origin gPackager )
				)
				( objectStatus "M_E_CLK_DN<0>" )
			)
			( signal "@baseboard_fab2_lib.baseboard_fab2(sch_1):m_e_clk_dn(1)"
				( attribute "CDS_PHYS_NET_NAME" "M_E_CLK_DN<1>"
					( Origin gPackager )
				)
				( attribute "PNN" "M_E_CLK_DN<1>"
					( Origin gPackager )
				)
				( objectStatus "M_E_CLK_DN<1>" )
			)
			( signal "@baseboard_fab2_lib.baseboard_fab2(sch_1):m_e_clk_dn(2)"
				( attribute "CDS_PHYS_NET_NAME" "M_E_CLK_DN<2>"
					( Origin gPackager )
				)
				( attribute "PNN" "M_E_CLK_DN<2>"
					( Origin gPackager )
				)
				( objectStatus "M_E_CLK_DN<2>" )
			)
			( signal "@baseboard_fab2_lib.baseboard_fab2(sch_1):m_e_clk_dn(3)"
				( attribute "CDS_PHYS_NET_NAME" "M_E_CLK_DN<3>"
					( Origin gPackager )
				)
				( attribute "PNN" "M_E_CLK_DN<3>"
					( Origin gPackager )
				)
				( objectStatus "M_E_CLK_DN<3>" )
			)
			( signal "@baseboard_fab2_lib.baseboard_fab2(sch_1):m_e_clk_dp(0)"
				( attribute "CDS_PHYS_NET_NAME" "M_E_CLK_DP<0>"
					( Origin gPackager )
				)
				( attribute "PNN" "M_E_CLK_DP<0>"
					( Origin gPackager )
				)
				( objectStatus "M_E_CLK_DP<0>" )
			)
			( signal "@baseboard_fab2_lib.baseboard_fab2(sch_1):m_e_clk_dp(1)"
				( attribute "CDS_PHYS_NET_NAME" "M_E_CLK_DP<1>"
					( Origin gPackager )
				)
				( attribute "PNN" "M_E_CLK_DP<1>"
					( Origin gPackager )
				)
				( objectStatus "M_E_CLK_DP<1>" )
			)
			( signal "@baseboard_fab2_lib.baseboard_fab2(sch_1):m_e_clk_dp(2)"
				( attribute "CDS_PHYS_NET_NAME" "M_E_CLK_DP<2>"
					( Origin gPackager )
				)
				( attribute "PNN" "M_E_CLK_DP<2>"
					( Origin gPackager )
				)
				( objectStatus "M_E_CLK_DP<2>" )
			)
			( signal "@baseboard_fab2_lib.baseboard_fab2(sch_1):m_e_clk_dp(3)"
				( attribute "CDS_PHYS_NET_NAME" "M_E_CLK_DP<3>"
					( Origin gPackager )
				)
				( attribute "PNN" "M_E_CLK_DP<3>"
					( Origin gPackager )
				)
				( objectStatus "M_E_CLK_DP<3>" )
			)
			( signal "@baseboard_fab2_lib.baseboard_fab2(sch_1):m_e_cs_n(0)"
				( attribute "CDS_PHYS_NET_NAME" "M_E_CS_N<0>"
					( Origin gPackager )
				)
				( attribute "PNN" "M_E_CS_N<0>"
					( Origin gPackager )
				)
				( objectStatus "M_E_CS_N<0>" )
			)
			( signal "@baseboard_fab2_lib.baseboard_fab2(sch_1):m_e_cs_n(1)"
				( attribute "CDS_PHYS_NET_NAME" "M_E_CS_N<1>"
					( Origin gPackager )
				)
				( attribute "PNN" "M_E_CS_N<1>"
					( Origin gPackager )
				)
				( objectStatus "M_E_CS_N<1>" )
			)
			( signal "@baseboard_fab2_lib.baseboard_fab2(sch_1):m_e_cs_n(2)"
				( attribute "CDS_PHYS_NET_NAME" "M_E_CS_N<2>"
					( Origin gPackager )
				)
				( attribute "PNN" "M_E_CS_N<2>"
					( Origin gPackager )
				)
				( objectStatus "M_E_CS_N<2>" )
			)
			( signal "@baseboard_fab2_lib.baseboard_fab2(sch_1):m_e_cs_n(3)"
				( attribute "CDS_PHYS_NET_NAME" "M_E_CS_N<3>"
					( Origin gPackager )
				)
				( attribute "PNN" "M_E_CS_N<3>"
					( Origin gPackager )
				)
				( objectStatus "M_E_CS_N<3>" )
			)
			( signal "@baseboard_fab2_lib.baseboard_fab2(sch_1):m_e_cs_n(4)"
				( attribute "CDS_PHYS_NET_NAME" "M_E_CS_N<4>"
					( Origin gPackager )
				)
				( attribute "PNN" "M_E_CS_N<4>"
					( Origin gPackager )
				)
				( objectStatus "M_E_CS_N<4>" )
			)
			( signal "@baseboard_fab2_lib.baseboard_fab2(sch_1):m_e_cs_n(5)"
				( attribute "CDS_PHYS_NET_NAME" "M_E_CS_N<5>"
					( Origin gPackager )
				)
				( attribute "PNN" "M_E_CS_N<5>"
					( Origin gPackager )
				)
				( objectStatus "M_E_CS_N<5>" )
			)
			( signal "@baseboard_fab2_lib.baseboard_fab2(sch_1):m_e_cs_n(6)"
				( attribute "CDS_PHYS_NET_NAME" "M_E_CS_N<6>"
					( Origin gPackager )
				)
				( attribute "PNN" "M_E_CS_N<6>"
					( Origin gPackager )
				)
				( objectStatus "M_E_CS_N<6>" )
			)
			( signal "@baseboard_fab2_lib.baseboard_fab2(sch_1):m_e_cs_n(7)"
				( attribute "CDS_PHYS_NET_NAME" "M_E_CS_N<7>"
					( Origin gPackager )
				)
				( attribute "PNN" "M_E_CS_N<7>"
					( Origin gPackager )
				)
				( objectStatus "M_E_CS_N<7>" )
			)
			( signal "@baseboard_fab2_lib.baseboard_fab2(sch_1):m_e_dq(0)"
				( attribute "CDS_PHYS_NET_NAME" "M_E_DQ<0>"
					( Origin gPackager )
				)
				( attribute "PNN" "M_E_DQ<0>"
					( Origin gPackager )
				)
				( objectStatus "M_E_DQ<0>" )
			)
			( signal "@baseboard_fab2_lib.baseboard_fab2(sch_1):m_e_dq(1)"
				( attribute "CDS_PHYS_NET_NAME" "M_E_DQ<1>"
					( Origin gPackager )
				)
				( attribute "PNN" "M_E_DQ<1>"
					( Origin gPackager )
				)
				( objectStatus "M_E_DQ<1>" )
			)
			( signal "@baseboard_fab2_lib.baseboard_fab2(sch_1):m_e_dq(2)"
				( attribute "CDS_PHYS_NET_NAME" "M_E_DQ<2>"
					( Origin gPackager )
				)
				( attribute "PNN" "M_E_DQ<2>"
					( Origin gPackager )
				)
				( objectStatus "M_E_DQ<2>" )
			)
			( signal "@baseboard_fab2_lib.baseboard_fab2(sch_1):m_e_dq(3)"
				( attribute "CDS_PHYS_NET_NAME" "M_E_DQ<3>"
					( Origin gPackager )
				)
				( attribute "PNN" "M_E_DQ<3>"
					( Origin gPackager )
				)
				( objectStatus "M_E_DQ<3>" )
			)
			( signal "@baseboard_fab2_lib.baseboard_fab2(sch_1):m_e_dq(4)"
				( attribute "CDS_PHYS_NET_NAME" "M_E_DQ<4>"
					( Origin gPackager )
				)
				( attribute "PNN" "M_E_DQ<4>"
					( Origin gPackager )
				)
				( objectStatus "M_E_DQ<4>" )
			)
			( signal "@baseboard_fab2_lib.baseboard_fab2(sch_1):m_e_dq(5)"
				( attribute "CDS_PHYS_NET_NAME" "M_E_DQ<5>"
					( Origin gPackager )
				)
				( attribute "PNN" "M_E_DQ<5>"
					( Origin gPackager )
				)
				( objectStatus "M_E_DQ<5>" )
			)
			( signal "@baseboard_fab2_lib.baseboard_fab2(sch_1):m_e_dq(6)"
				( attribute "CDS_PHYS_NET_NAME" "M_E_DQ<6>"
					( Origin gPackager )
				)
				( attribute "PNN" "M_E_DQ<6>"
					( Origin gPackager )
				)
				( objectStatus "M_E_DQ<6>" )
			)
			( signal "@baseboard_fab2_lib.baseboard_fab2(sch_1):m_e_dq(7)"
				( attribute "CDS_PHYS_NET_NAME" "M_E_DQ<7>"
					( Origin gPackager )
				)
				( attribute "PNN" "M_E_DQ<7>"
					( Origin gPackager )
				)
				( objectStatus "M_E_DQ<7>" )
			)
			( signal "@baseboard_fab2_lib.baseboard_fab2(sch_1):m_e_dq(8)"
				( attribute "CDS_PHYS_NET_NAME" "M_E_DQ<8>"
					( Origin gPackager )
				)
				( attribute "PNN" "M_E_DQ<8>"
					( Origin gPackager )
				)
				( objectStatus "M_E_DQ<8>" )
			)
			( signal "@baseboard_fab2_lib.baseboard_fab2(sch_1):m_e_dq(9)"
				( attribute "CDS_PHYS_NET_NAME" "M_E_DQ<9>"
					( Origin gPackager )
				)
				( attribute "PNN" "M_E_DQ<9>"
					( Origin gPackager )
				)
				( objectStatus "M_E_DQ<9>" )
			)
			( signal "@baseboard_fab2_lib.baseboard_fab2(sch_1):m_e_dq(10)"
				( attribute "CDS_PHYS_NET_NAME" "M_E_DQ<10>"
					( Origin gPackager )
				)
				( attribute "PNN" "M_E_DQ<10>"
					( Origin gPackager )
				)
				( objectStatus "M_E_DQ<10>" )
			)
			( signal "@baseboard_fab2_lib.baseboard_fab2(sch_1):m_e_dq(11)"
				( attribute "CDS_PHYS_NET_NAME" "M_E_DQ<11>"
					( Origin gPackager )
				)
				( attribute "PNN" "M_E_DQ<11>"
					( Origin gPackager )
				)
				( objectStatus "M_E_DQ<11>" )
			)
			( signal "@baseboard_fab2_lib.baseboard_fab2(sch_1):m_e_dq(12)"
				( attribute "CDS_PHYS_NET_NAME" "M_E_DQ<12>"
					( Origin gPackager )
				)
				( attribute "PNN" "M_E_DQ<12>"
					( Origin gPackager )
				)
				( objectStatus "M_E_DQ<12>" )
			)
			( signal "@baseboard_fab2_lib.baseboard_fab2(sch_1):m_e_dq(13)"
				( attribute "CDS_PHYS_NET_NAME" "M_E_DQ<13>"
					( Origin gPackager )
				)
				( attribute "PNN" "M_E_DQ<13>"
					( Origin gPackager )
				)
				( objectStatus "M_E_DQ<13>" )
			)
			( signal "@baseboard_fab2_lib.baseboard_fab2(sch_1):m_e_dq(14)"
				( attribute "CDS_PHYS_NET_NAME" "M_E_DQ<14>"
					( Origin gPackager )
				)
				( attribute "PNN" "M_E_DQ<14>"
					( Origin gPackager )
				)
				( objectStatus "M_E_DQ<14>" )
			)
			( signal "@baseboard_fab2_lib.baseboard_fab2(sch_1):m_e_dq(15)"
				( attribute "CDS_PHYS_NET_NAME" "M_E_DQ<15>"
					( Origin gPackager )
				)
				( attribute "PNN" "M_E_DQ<15>"
					( Origin gPackager )
				)
				( objectStatus "M_E_DQ<15>" )
			)
			( signal "@baseboard_fab2_lib.baseboard_fab2(sch_1):m_e_dq(16)"
				( attribute "CDS_PHYS_NET_NAME" "M_E_DQ<16>"
					( Origin gPackager )
				)
				( attribute "PNN" "M_E_DQ<16>"
					( Origin gPackager )
				)
				( objectStatus "M_E_DQ<16>" )
			)
			( signal "@baseboard_fab2_lib.baseboard_fab2(sch_1):m_e_dq(17)"
				( attribute "CDS_PHYS_NET_NAME" "M_E_DQ<17>"
					( Origin gPackager )
				)
				( attribute "PNN" "M_E_DQ<17>"
					( Origin gPackager )
				)
				( objectStatus "M_E_DQ<17>" )
			)
			( signal "@baseboard_fab2_lib.baseboard_fab2(sch_1):m_e_dq(18)"
				( attribute "CDS_PHYS_NET_NAME" "M_E_DQ<18>"
					( Origin gPackager )
				)
				( attribute "PNN" "M_E_DQ<18>"
					( Origin gPackager )
				)
				( objectStatus "M_E_DQ<18>" )
			)
			( signal "@baseboard_fab2_lib.baseboard_fab2(sch_1):m_e_dq(19)"
				( attribute "CDS_PHYS_NET_NAME" "M_E_DQ<19>"
					( Origin gPackager )
				)
				( attribute "PNN" "M_E_DQ<19>"
					( Origin gPackager )
				)
				( objectStatus "M_E_DQ<19>" )
			)
			( signal "@baseboard_fab2_lib.baseboard_fab2(sch_1):m_e_dq(20)"
				( attribute "CDS_PHYS_NET_NAME" "M_E_DQ<20>"
					( Origin gPackager )
				)
				( attribute "PNN" "M_E_DQ<20>"
					( Origin gPackager )
				)
				( objectStatus "M_E_DQ<20>" )
			)
			( signal "@baseboard_fab2_lib.baseboard_fab2(sch_1):m_e_dq(21)"
				( attribute "CDS_PHYS_NET_NAME" "M_E_DQ<21>"
					( Origin gPackager )
				)
				( attribute "PNN" "M_E_DQ<21>"
					( Origin gPackager )
				)
				( objectStatus "M_E_DQ<21>" )
			)
			( signal "@baseboard_fab2_lib.baseboard_fab2(sch_1):m_e_dq(22)"
				( attribute "CDS_PHYS_NET_NAME" "M_E_DQ<22>"
					( Origin gPackager )
				)
				( attribute "PNN" "M_E_DQ<22>"
					( Origin gPackager )
				)
				( objectStatus "M_E_DQ<22>" )
			)
			( signal "@baseboard_fab2_lib.baseboard_fab2(sch_1):m_e_dq(23)"
				( attribute "CDS_PHYS_NET_NAME" "M_E_DQ<23>"
					( Origin gPackager )
				)
				( attribute "PNN" "M_E_DQ<23>"
					( Origin gPackager )
				)
				( objectStatus "M_E_DQ<23>" )
			)
			( signal "@baseboard_fab2_lib.baseboard_fab2(sch_1):m_e_dq(24)"
				( attribute "CDS_PHYS_NET_NAME" "M_E_DQ<24>"
					( Origin gPackager )
				)
				( attribute "PNN" "M_E_DQ<24>"
					( Origin gPackager )
				)
				( objectStatus "M_E_DQ<24>" )
			)
			( signal "@baseboard_fab2_lib.baseboard_fab2(sch_1):m_e_dq(25)"
				( attribute "CDS_PHYS_NET_NAME" "M_E_DQ<25>"
					( Origin gPackager )
				)
				( attribute "PNN" "M_E_DQ<25>"
					( Origin gPackager )
				)
				( objectStatus "M_E_DQ<25>" )
			)
			( signal "@baseboard_fab2_lib.baseboard_fab2(sch_1):m_e_dq(26)"
				( attribute "CDS_PHYS_NET_NAME" "M_E_DQ<26>"
					( Origin gPackager )
				)
				( attribute "PNN" "M_E_DQ<26>"
					( Origin gPackager )
				)
				( objectStatus "M_E_DQ<26>" )
			)
			( signal "@baseboard_fab2_lib.baseboard_fab2(sch_1):m_e_dq(27)"
				( attribute "CDS_PHYS_NET_NAME" "M_E_DQ<27>"
					( Origin gPackager )
				)
				( attribute "PNN" "M_E_DQ<27>"
					( Origin gPackager )
				)
				( objectStatus "M_E_DQ<27>" )
			)
			( signal "@baseboard_fab2_lib.baseboard_fab2(sch_1):m_e_dq(28)"
				( attribute "CDS_PHYS_NET_NAME" "M_E_DQ<28>"
					( Origin gPackager )
				)
				( attribute "PNN" "M_E_DQ<28>"
					( Origin gPackager )
				)
				( objectStatus "M_E_DQ<28>" )
			)
			( signal "@baseboard_fab2_lib.baseboard_fab2(sch_1):m_e_dq(29)"
				( attribute "CDS_PHYS_NET_NAME" "M_E_DQ<29>"
					( Origin gPackager )
				)
				( attribute "PNN" "M_E_DQ<29>"
					( Origin gPackager )
				)
				( objectStatus "M_E_DQ<29>" )
			)
			( signal "@baseboard_fab2_lib.baseboard_fab2(sch_1):m_e_dq(30)"
				( attribute "CDS_PHYS_NET_NAME" "M_E_DQ<30>"
					( Origin gPackager )
				)
				( attribute "PNN" "M_E_DQ<30>"
					( Origin gPackager )
				)
				( objectStatus "M_E_DQ<30>" )
			)
			( signal "@baseboard_fab2_lib.baseboard_fab2(sch_1):m_e_dq(31)"
				( attribute "CDS_PHYS_NET_NAME" "M_E_DQ<31>"
					( Origin gPackager )
				)
				( attribute "PNN" "M_E_DQ<31>"
					( Origin gPackager )
				)
				( objectStatus "M_E_DQ<31>" )
			)
			( signal "@baseboard_fab2_lib.baseboard_fab2(sch_1):m_e_dq(32)"
				( attribute "CDS_PHYS_NET_NAME" "M_E_DQ<32>"
					( Origin gPackager )
				)
				( attribute "PNN" "M_E_DQ<32>"
					( Origin gPackager )
				)
				( objectStatus "M_E_DQ<32>" )
			)
			( signal "@baseboard_fab2_lib.baseboard_fab2(sch_1):m_e_dq(33)"
				( attribute "CDS_PHYS_NET_NAME" "M_E_DQ<33>"
					( Origin gPackager )
				)
				( attribute "PNN" "M_E_DQ<33>"
					( Origin gPackager )
				)
				( objectStatus "M_E_DQ<33>" )
			)
			( signal "@baseboard_fab2_lib.baseboard_fab2(sch_1):m_e_dq(34)"
				( attribute "CDS_PHYS_NET_NAME" "M_E_DQ<34>"
					( Origin gPackager )
				)
				( attribute "PNN" "M_E_DQ<34>"
					( Origin gPackager )
				)
				( objectStatus "M_E_DQ<34>" )
			)
			( signal "@baseboard_fab2_lib.baseboard_fab2(sch_1):m_e_dq(35)"
				( attribute "CDS_PHYS_NET_NAME" "M_E_DQ<35>"
					( Origin gPackager )
				)
				( attribute "PNN" "M_E_DQ<35>"
					( Origin gPackager )
				)
				( objectStatus "M_E_DQ<35>" )
			)
			( signal "@baseboard_fab2_lib.baseboard_fab2(sch_1):m_e_dq(36)"
				( attribute "CDS_PHYS_NET_NAME" "M_E_DQ<36>"
					( Origin gPackager )
				)
				( attribute "PNN" "M_E_DQ<36>"
					( Origin gPackager )
				)
				( objectStatus "M_E_DQ<36>" )
			)
			( signal "@baseboard_fab2_lib.baseboard_fab2(sch_1):m_e_dq(37)"
				( attribute "CDS_PHYS_NET_NAME" "M_E_DQ<37>"
					( Origin gPackager )
				)
				( attribute "PNN" "M_E_DQ<37>"
					( Origin gPackager )
				)
				( objectStatus "M_E_DQ<37>" )
			)
			( signal "@baseboard_fab2_lib.baseboard_fab2(sch_1):m_e_dq(38)"
				( attribute "CDS_PHYS_NET_NAME" "M_E_DQ<38>"
					( Origin gPackager )
				)
				( attribute "PNN" "M_E_DQ<38>"
					( Origin gPackager )
				)
				( objectStatus "M_E_DQ<38>" )
			)
			( signal "@baseboard_fab2_lib.baseboard_fab2(sch_1):m_e_dq(39)"
				( attribute "CDS_PHYS_NET_NAME" "M_E_DQ<39>"
					( Origin gPackager )
				)
				( attribute "PNN" "M_E_DQ<39>"
					( Origin gPackager )
				)
				( objectStatus "M_E_DQ<39>" )
			)
			( signal "@baseboard_fab2_lib.baseboard_fab2(sch_1):m_e_dq(40)"
				( attribute "CDS_PHYS_NET_NAME" "M_E_DQ<40>"
					( Origin gPackager )
				)
				( attribute "PNN" "M_E_DQ<40>"
					( Origin gPackager )
				)
				( objectStatus "M_E_DQ<40>" )
			)
			( signal "@baseboard_fab2_lib.baseboard_fab2(sch_1):m_e_dq(41)"
				( attribute "CDS_PHYS_NET_NAME" "M_E_DQ<41>"
					( Origin gPackager )
				)
				( attribute "PNN" "M_E_DQ<41>"
					( Origin gPackager )
				)
				( objectStatus "M_E_DQ<41>" )
			)
			( signal "@baseboard_fab2_lib.baseboard_fab2(sch_1):m_e_dq(42)"
				( attribute "CDS_PHYS_NET_NAME" "M_E_DQ<42>"
					( Origin gPackager )
				)
				( attribute "PNN" "M_E_DQ<42>"
					( Origin gPackager )
				)
				( objectStatus "M_E_DQ<42>" )
			)
			( signal "@baseboard_fab2_lib.baseboard_fab2(sch_1):m_e_dq(43)"
				( attribute "CDS_PHYS_NET_NAME" "M_E_DQ<43>"
					( Origin gPackager )
				)
				( attribute "PNN" "M_E_DQ<43>"
					( Origin gPackager )
				)
				( objectStatus "M_E_DQ<43>" )
			)
			( signal "@baseboard_fab2_lib.baseboard_fab2(sch_1):m_e_dq(44)"
				( attribute "CDS_PHYS_NET_NAME" "M_E_DQ<44>"
					( Origin gPackager )
				)
				( attribute "PNN" "M_E_DQ<44>"
					( Origin gPackager )
				)
				( objectStatus "M_E_DQ<44>" )
			)
			( signal "@baseboard_fab2_lib.baseboard_fab2(sch_1):m_e_dq(45)"
				( attribute "CDS_PHYS_NET_NAME" "M_E_DQ<45>"
					( Origin gPackager )
				)
				( attribute "PNN" "M_E_DQ<45>"
					( Origin gPackager )
				)
				( objectStatus "M_E_DQ<45>" )
			)
			( signal "@baseboard_fab2_lib.baseboard_fab2(sch_1):m_e_dq(46)"
				( attribute "CDS_PHYS_NET_NAME" "M_E_DQ<46>"
					( Origin gPackager )
				)
				( attribute "PNN" "M_E_DQ<46>"
					( Origin gPackager )
				)
				( objectStatus "M_E_DQ<46>" )
			)
			( signal "@baseboard_fab2_lib.baseboard_fab2(sch_1):m_e_dq(47)"
				( attribute "CDS_PHYS_NET_NAME" "M_E_DQ<47>"
					( Origin gPackager )
				)
				( attribute "PNN" "M_E_DQ<47>"
					( Origin gPackager )
				)
				( objectStatus "M_E_DQ<47>" )
			)
			( signal "@baseboard_fab2_lib.baseboard_fab2(sch_1):m_e_dq(48)"
				( attribute "CDS_PHYS_NET_NAME" "M_E_DQ<48>"
					( Origin gPackager )
				)
				( attribute "PNN" "M_E_DQ<48>"
					( Origin gPackager )
				)
				( objectStatus "M_E_DQ<48>" )
			)
			( signal "@baseboard_fab2_lib.baseboard_fab2(sch_1):m_e_dq(49)"
				( attribute "CDS_PHYS_NET_NAME" "M_E_DQ<49>"
					( Origin gPackager )
				)
				( attribute "PNN" "M_E_DQ<49>"
					( Origin gPackager )
				)
				( objectStatus "M_E_DQ<49>" )
			)
			( signal "@baseboard_fab2_lib.baseboard_fab2(sch_1):m_e_dq(50)"
				( attribute "CDS_PHYS_NET_NAME" "M_E_DQ<50>"
					( Origin gPackager )
				)
				( attribute "PNN" "M_E_DQ<50>"
					( Origin gPackager )
				)
				( objectStatus "M_E_DQ<50>" )
			)
			( signal "@baseboard_fab2_lib.baseboard_fab2(sch_1):m_e_dq(51)"
				( attribute "CDS_PHYS_NET_NAME" "M_E_DQ<51>"
					( Origin gPackager )
				)
				( attribute "PNN" "M_E_DQ<51>"
					( Origin gPackager )
				)
				( objectStatus "M_E_DQ<51>" )
			)
			( signal "@baseboard_fab2_lib.baseboard_fab2(sch_1):m_e_dq(52)"
				( attribute "CDS_PHYS_NET_NAME" "M_E_DQ<52>"
					( Origin gPackager )
				)
				( attribute "PNN" "M_E_DQ<52>"
					( Origin gPackager )
				)
				( objectStatus "M_E_DQ<52>" )
			)
			( signal "@baseboard_fab2_lib.baseboard_fab2(sch_1):m_e_dq(53)"
				( attribute "CDS_PHYS_NET_NAME" "M_E_DQ<53>"
					( Origin gPackager )
				)
				( attribute "PNN" "M_E_DQ<53>"
					( Origin gPackager )
				)
				( objectStatus "M_E_DQ<53>" )
			)
			( signal "@baseboard_fab2_lib.baseboard_fab2(sch_1):m_e_dq(54)"
				( attribute "CDS_PHYS_NET_NAME" "M_E_DQ<54>"
					( Origin gPackager )
				)
				( attribute "PNN" "M_E_DQ<54>"
					( Origin gPackager )
				)
				( objectStatus "M_E_DQ<54>" )
			)
			( signal "@baseboard_fab2_lib.baseboard_fab2(sch_1):m_e_dq(55)"
				( attribute "CDS_PHYS_NET_NAME" "M_E_DQ<55>"
					( Origin gPackager )
				)
				( attribute "PNN" "M_E_DQ<55>"
					( Origin gPackager )
				)
				( objectStatus "M_E_DQ<55>" )
			)
			( signal "@baseboard_fab2_lib.baseboard_fab2(sch_1):m_e_dq(56)"
				( attribute "CDS_PHYS_NET_NAME" "M_E_DQ<56>"
					( Origin gPackager )
				)
				( attribute "PNN" "M_E_DQ<56>"
					( Origin gPackager )
				)
				( objectStatus "M_E_DQ<56>" )
			)
			( signal "@baseboard_fab2_lib.baseboard_fab2(sch_1):m_e_dq(57)"
				( attribute "CDS_PHYS_NET_NAME" "M_E_DQ<57>"
					( Origin gPackager )
				)
				( attribute "PNN" "M_E_DQ<57>"
					( Origin gPackager )
				)
				( objectStatus "M_E_DQ<57>" )
			)
			( signal "@baseboard_fab2_lib.baseboard_fab2(sch_1):m_e_dq(58)"
				( attribute "CDS_PHYS_NET_NAME" "M_E_DQ<58>"
					( Origin gPackager )
				)
				( attribute "PNN" "M_E_DQ<58>"
					( Origin gPackager )
				)
				( objectStatus "M_E_DQ<58>" )
			)
			( signal "@baseboard_fab2_lib.baseboard_fab2(sch_1):m_e_dq(59)"
				( attribute "CDS_PHYS_NET_NAME" "M_E_DQ<59>"
					( Origin gPackager )
				)
				( attribute "PNN" "M_E_DQ<59>"
					( Origin gPackager )
				)
				( objectStatus "M_E_DQ<59>" )
			)
			( signal "@baseboard_fab2_lib.baseboard_fab2(sch_1):m_e_dq(60)"
				( attribute "CDS_PHYS_NET_NAME" "M_E_DQ<60>"
					( Origin gPackager )
				)
				( attribute "PNN" "M_E_DQ<60>"
					( Origin gPackager )
				)
				( objectStatus "M_E_DQ<60>" )
			)
			( signal "@baseboard_fab2_lib.baseboard_fab2(sch_1):m_e_dq(61)"
				( attribute "CDS_PHYS_NET_NAME" "M_E_DQ<61>"
					( Origin gPackager )
				)
				( attribute "PNN" "M_E_DQ<61>"
					( Origin gPackager )
				)
				( objectStatus "M_E_DQ<61>" )
			)
			( signal "@baseboard_fab2_lib.baseboard_fab2(sch_1):m_e_dq(62)"
				( attribute "CDS_PHYS_NET_NAME" "M_E_DQ<62>"
					( Origin gPackager )
				)
				( attribute "PNN" "M_E_DQ<62>"
					( Origin gPackager )
				)
				( objectStatus "M_E_DQ<62>" )
			)
			( signal "@baseboard_fab2_lib.baseboard_fab2(sch_1):m_e_dq(63)"
				( attribute "CDS_PHYS_NET_NAME" "M_E_DQ<63>"
					( Origin gPackager )
				)
				( attribute "PNN" "M_E_DQ<63>"
					( Origin gPackager )
				)
				( objectStatus "M_E_DQ<63>" )
			)
			( signal "@baseboard_fab2_lib.baseboard_fab2(sch_1):m_e_dqs_dn(0)"
				( attribute "CDS_PHYS_NET_NAME" "M_E_DQS_DN<0>"
					( Origin gPackager )
				)
				( attribute "PNN" "M_E_DQS_DN<0>"
					( Origin gPackager )
				)
				( objectStatus "M_E_DQS_DN<0>" )
			)
			( signal "@baseboard_fab2_lib.baseboard_fab2(sch_1):m_e_dqs_dn(1)"
				( attribute "CDS_PHYS_NET_NAME" "M_E_DQS_DN<1>"
					( Origin gPackager )
				)
				( attribute "PNN" "M_E_DQS_DN<1>"
					( Origin gPackager )
				)
				( objectStatus "M_E_DQS_DN<1>" )
			)
			( signal "@baseboard_fab2_lib.baseboard_fab2(sch_1):m_e_dqs_dn(2)"
				( attribute "CDS_PHYS_NET_NAME" "M_E_DQS_DN<2>"
					( Origin gPackager )
				)
				( attribute "PNN" "M_E_DQS_DN<2>"
					( Origin gPackager )
				)
				( objectStatus "M_E_DQS_DN<2>" )
			)
			( signal "@baseboard_fab2_lib.baseboard_fab2(sch_1):m_e_dqs_dn(3)"
				( attribute "CDS_PHYS_NET_NAME" "M_E_DQS_DN<3>"
					( Origin gPackager )
				)
				( attribute "PNN" "M_E_DQS_DN<3>"
					( Origin gPackager )
				)
				( objectStatus "M_E_DQS_DN<3>" )
			)
			( signal "@baseboard_fab2_lib.baseboard_fab2(sch_1):m_e_dqs_dn(4)"
				( attribute "CDS_PHYS_NET_NAME" "M_E_DQS_DN<4>"
					( Origin gPackager )
				)
				( attribute "PNN" "M_E_DQS_DN<4>"
					( Origin gPackager )
				)
				( objectStatus "M_E_DQS_DN<4>" )
			)
			( signal "@baseboard_fab2_lib.baseboard_fab2(sch_1):m_e_dqs_dn(5)"
				( attribute "CDS_PHYS_NET_NAME" "M_E_DQS_DN<5>"
					( Origin gPackager )
				)
				( attribute "PNN" "M_E_DQS_DN<5>"
					( Origin gPackager )
				)
				( objectStatus "M_E_DQS_DN<5>" )
			)
			( signal "@baseboard_fab2_lib.baseboard_fab2(sch_1):m_e_dqs_dn(6)"
				( attribute "CDS_PHYS_NET_NAME" "M_E_DQS_DN<6>"
					( Origin gPackager )
				)
				( attribute "PNN" "M_E_DQS_DN<6>"
					( Origin gPackager )
				)
				( objectStatus "M_E_DQS_DN<6>" )
			)
			( signal "@baseboard_fab2_lib.baseboard_fab2(sch_1):m_e_dqs_dn(7)"
				( attribute "CDS_PHYS_NET_NAME" "M_E_DQS_DN<7>"
					( Origin gPackager )
				)
				( attribute "PNN" "M_E_DQS_DN<7>"
					( Origin gPackager )
				)
				( objectStatus "M_E_DQS_DN<7>" )
			)
			( signal "@baseboard_fab2_lib.baseboard_fab2(sch_1):m_e_dqs_dn(8)"
				( attribute "CDS_PHYS_NET_NAME" "M_E_DQS_DN<8>"
					( Origin gPackager )
				)
				( attribute "PNN" "M_E_DQS_DN<8>"
					( Origin gPackager )
				)
				( objectStatus "M_E_DQS_DN<8>" )
			)
			( signal "@baseboard_fab2_lib.baseboard_fab2(sch_1):m_e_dqs_dn(9)"
				( attribute "CDS_PHYS_NET_NAME" "M_E_DQS_DN<9>"
					( Origin gPackager )
				)
				( attribute "PNN" "M_E_DQS_DN<9>"
					( Origin gPackager )
				)
				( objectStatus "M_E_DQS_DN<9>" )
			)
			( signal "@baseboard_fab2_lib.baseboard_fab2(sch_1):m_e_dqs_dn(10)"
				( attribute "CDS_PHYS_NET_NAME" "M_E_DQS_DN<10>"
					( Origin gPackager )
				)
				( attribute "PNN" "M_E_DQS_DN<10>"
					( Origin gPackager )
				)
				( objectStatus "M_E_DQS_DN<10>" )
			)
			( signal "@baseboard_fab2_lib.baseboard_fab2(sch_1):m_e_dqs_dn(11)"
				( attribute "CDS_PHYS_NET_NAME" "M_E_DQS_DN<11>"
					( Origin gPackager )
				)
				( attribute "PNN" "M_E_DQS_DN<11>"
					( Origin gPackager )
				)
				( objectStatus "M_E_DQS_DN<11>" )
			)
			( signal "@baseboard_fab2_lib.baseboard_fab2(sch_1):m_e_dqs_dn(12)"
				( attribute "CDS_PHYS_NET_NAME" "M_E_DQS_DN<12>"
					( Origin gPackager )
				)
				( attribute "PNN" "M_E_DQS_DN<12>"
					( Origin gPackager )
				)
				( objectStatus "M_E_DQS_DN<12>" )
			)
			( signal "@baseboard_fab2_lib.baseboard_fab2(sch_1):m_e_dqs_dn(13)"
				( attribute "CDS_PHYS_NET_NAME" "M_E_DQS_DN<13>"
					( Origin gPackager )
				)
				( attribute "PNN" "M_E_DQS_DN<13>"
					( Origin gPackager )
				)
				( objectStatus "M_E_DQS_DN<13>" )
			)
			( signal "@baseboard_fab2_lib.baseboard_fab2(sch_1):m_e_dqs_dn(14)"
				( attribute "CDS_PHYS_NET_NAME" "M_E_DQS_DN<14>"
					( Origin gPackager )
				)
				( attribute "PNN" "M_E_DQS_DN<14>"
					( Origin gPackager )
				)
				( objectStatus "M_E_DQS_DN<14>" )
			)
			( signal "@baseboard_fab2_lib.baseboard_fab2(sch_1):m_e_dqs_dn(15)"
				( attribute "CDS_PHYS_NET_NAME" "M_E_DQS_DN<15>"
					( Origin gPackager )
				)
				( attribute "PNN" "M_E_DQS_DN<15>"
					( Origin gPackager )
				)
				( objectStatus "M_E_DQS_DN<15>" )
			)
			( signal "@baseboard_fab2_lib.baseboard_fab2(sch_1):m_e_dqs_dn(16)"
				( attribute "CDS_PHYS_NET_NAME" "M_E_DQS_DN<16>"
					( Origin gPackager )
				)
				( attribute "PNN" "M_E_DQS_DN<16>"
					( Origin gPackager )
				)
				( objectStatus "M_E_DQS_DN<16>" )
			)
			( signal "@baseboard_fab2_lib.baseboard_fab2(sch_1):m_e_dqs_dn(17)"
				( attribute "CDS_PHYS_NET_NAME" "M_E_DQS_DN<17>"
					( Origin gPackager )
				)
				( attribute "PNN" "M_E_DQS_DN<17>"
					( Origin gPackager )
				)
				( objectStatus "M_E_DQS_DN<17>" )
			)
			( signal "@baseboard_fab2_lib.baseboard_fab2(sch_1):m_e_dqs_dp(0)"
				( attribute "CDS_PHYS_NET_NAME" "M_E_DQS_DP<0>"
					( Origin gPackager )
				)
				( attribute "PNN" "M_E_DQS_DP<0>"
					( Origin gPackager )
				)
				( objectStatus "M_E_DQS_DP<0>" )
			)
			( signal "@baseboard_fab2_lib.baseboard_fab2(sch_1):m_e_dqs_dp(1)"
				( attribute "CDS_PHYS_NET_NAME" "M_E_DQS_DP<1>"
					( Origin gPackager )
				)
				( attribute "PNN" "M_E_DQS_DP<1>"
					( Origin gPackager )
				)
				( objectStatus "M_E_DQS_DP<1>" )
			)
			( signal "@baseboard_fab2_lib.baseboard_fab2(sch_1):m_e_dqs_dp(2)"
				( attribute "CDS_PHYS_NET_NAME" "M_E_DQS_DP<2>"
					( Origin gPackager )
				)
				( attribute "PNN" "M_E_DQS_DP<2>"
					( Origin gPackager )
				)
				( objectStatus "M_E_DQS_DP<2>" )
			)
			( signal "@baseboard_fab2_lib.baseboard_fab2(sch_1):m_e_dqs_dp(3)"
				( attribute "CDS_PHYS_NET_NAME" "M_E_DQS_DP<3>"
					( Origin gPackager )
				)
				( attribute "PNN" "M_E_DQS_DP<3>"
					( Origin gPackager )
				)
				( objectStatus "M_E_DQS_DP<3>" )
			)
			( signal "@baseboard_fab2_lib.baseboard_fab2(sch_1):m_e_dqs_dp(4)"
				( attribute "CDS_PHYS_NET_NAME" "M_E_DQS_DP<4>"
					( Origin gPackager )
				)
				( attribute "PNN" "M_E_DQS_DP<4>"
					( Origin gPackager )
				)
				( objectStatus "M_E_DQS_DP<4>" )
			)
			( signal "@baseboard_fab2_lib.baseboard_fab2(sch_1):m_e_dqs_dp(5)"
				( attribute "CDS_PHYS_NET_NAME" "M_E_DQS_DP<5>"
					( Origin gPackager )
				)
				( attribute "PNN" "M_E_DQS_DP<5>"
					( Origin gPackager )
				)
				( objectStatus "M_E_DQS_DP<5>" )
			)
			( signal "@baseboard_fab2_lib.baseboard_fab2(sch_1):m_e_dqs_dp(6)"
				( attribute "CDS_PHYS_NET_NAME" "M_E_DQS_DP<6>"
					( Origin gPackager )
				)
				( attribute "PNN" "M_E_DQS_DP<6>"
					( Origin gPackager )
				)
				( objectStatus "M_E_DQS_DP<6>" )
			)
			( signal "@baseboard_fab2_lib.baseboard_fab2(sch_1):m_e_dqs_dp(7)"
				( attribute "CDS_PHYS_NET_NAME" "M_E_DQS_DP<7>"
					( Origin gPackager )
				)
				( attribute "PNN" "M_E_DQS_DP<7>"
					( Origin gPackager )
				)
				( objectStatus "M_E_DQS_DP<7>" )
			)
			( signal "@baseboard_fab2_lib.baseboard_fab2(sch_1):m_e_dqs_dp(8)"
				( attribute "CDS_PHYS_NET_NAME" "M_E_DQS_DP<8>"
					( Origin gPackager )
				)
				( attribute "PNN" "M_E_DQS_DP<8>"
					( Origin gPackager )
				)
				( objectStatus "M_E_DQS_DP<8>" )
			)
			( signal "@baseboard_fab2_lib.baseboard_fab2(sch_1):m_e_dqs_dp(9)"
				( attribute "CDS_PHYS_NET_NAME" "M_E_DQS_DP<9>"
					( Origin gPackager )
				)
				( attribute "PNN" "M_E_DQS_DP<9>"
					( Origin gPackager )
				)
				( objectStatus "M_E_DQS_DP<9>" )
			)
			( signal "@baseboard_fab2_lib.baseboard_fab2(sch_1):m_e_dqs_dp(10)"
				( attribute "CDS_PHYS_NET_NAME" "M_E_DQS_DP<10>"
					( Origin gPackager )
				)
				( attribute "PNN" "M_E_DQS_DP<10>"
					( Origin gPackager )
				)
				( objectStatus "M_E_DQS_DP<10>" )
			)
			( signal "@baseboard_fab2_lib.baseboard_fab2(sch_1):m_e_dqs_dp(11)"
				( attribute "CDS_PHYS_NET_NAME" "M_E_DQS_DP<11>"
					( Origin gPackager )
				)
				( attribute "PNN" "M_E_DQS_DP<11>"
					( Origin gPackager )
				)
				( objectStatus "M_E_DQS_DP<11>" )
			)
			( signal "@baseboard_fab2_lib.baseboard_fab2(sch_1):m_e_dqs_dp(12)"
				( attribute "CDS_PHYS_NET_NAME" "M_E_DQS_DP<12>"
					( Origin gPackager )
				)
				( attribute "PNN" "M_E_DQS_DP<12>"
					( Origin gPackager )
				)
				( objectStatus "M_E_DQS_DP<12>" )
			)
			( signal "@baseboard_fab2_lib.baseboard_fab2(sch_1):m_e_dqs_dp(13)"
				( attribute "CDS_PHYS_NET_NAME" "M_E_DQS_DP<13>"
					( Origin gPackager )
				)
				( attribute "PNN" "M_E_DQS_DP<13>"
					( Origin gPackager )
				)
				( objectStatus "M_E_DQS_DP<13>" )
			)
			( signal "@baseboard_fab2_lib.baseboard_fab2(sch_1):m_e_dqs_dp(14)"
				( attribute "CDS_PHYS_NET_NAME" "M_E_DQS_DP<14>"
					( Origin gPackager )
				)
				( attribute "PNN" "M_E_DQS_DP<14>"
					( Origin gPackager )
				)
				( objectStatus "M_E_DQS_DP<14>" )
			)
			( signal "@baseboard_fab2_lib.baseboard_fab2(sch_1):m_e_dqs_dp(15)"
				( attribute "CDS_PHYS_NET_NAME" "M_E_DQS_DP<15>"
					( Origin gPackager )
				)
				( attribute "PNN" "M_E_DQS_DP<15>"
					( Origin gPackager )
				)
				( objectStatus "M_E_DQS_DP<15>" )
			)
			( signal "@baseboard_fab2_lib.baseboard_fab2(sch_1):m_e_dqs_dp(16)"
				( attribute "CDS_PHYS_NET_NAME" "M_E_DQS_DP<16>"
					( Origin gPackager )
				)
				( attribute "PNN" "M_E_DQS_DP<16>"
					( Origin gPackager )
				)
				( objectStatus "M_E_DQS_DP<16>" )
			)
			( signal "@baseboard_fab2_lib.baseboard_fab2(sch_1):m_e_dqs_dp(17)"
				( attribute "CDS_PHYS_NET_NAME" "M_E_DQS_DP<17>"
					( Origin gPackager )
				)
				( attribute "PNN" "M_E_DQS_DP<17>"
					( Origin gPackager )
				)
				( objectStatus "M_E_DQS_DP<17>" )
			)
			( signal "@baseboard_fab2_lib.baseboard_fab2(sch_1):m_e_ecc(0)"
				( attribute "CDS_PHYS_NET_NAME" "M_E_ECC<0>"
					( Origin gPackager )
				)
				( attribute "PNN" "M_E_ECC<0>"
					( Origin gPackager )
				)
				( objectStatus "M_E_ECC<0>" )
			)
			( signal "@baseboard_fab2_lib.baseboard_fab2(sch_1):m_e_ecc(1)"
				( attribute "CDS_PHYS_NET_NAME" "M_E_ECC<1>"
					( Origin gPackager )
				)
				( attribute "PNN" "M_E_ECC<1>"
					( Origin gPackager )
				)
				( objectStatus "M_E_ECC<1>" )
			)
			( signal "@baseboard_fab2_lib.baseboard_fab2(sch_1):m_e_ecc(2)"
				( attribute "CDS_PHYS_NET_NAME" "M_E_ECC<2>"
					( Origin gPackager )
				)
				( attribute "PNN" "M_E_ECC<2>"
					( Origin gPackager )
				)
				( objectStatus "M_E_ECC<2>" )
			)
			( signal "@baseboard_fab2_lib.baseboard_fab2(sch_1):m_e_ecc(3)"
				( attribute "CDS_PHYS_NET_NAME" "M_E_ECC<3>"
					( Origin gPackager )
				)
				( attribute "PNN" "M_E_ECC<3>"
					( Origin gPackager )
				)
				( objectStatus "M_E_ECC<3>" )
			)
			( signal "@baseboard_fab2_lib.baseboard_fab2(sch_1):m_e_ecc(4)"
				( attribute "CDS_PHYS_NET_NAME" "M_E_ECC<4>"
					( Origin gPackager )
				)
				( attribute "PNN" "M_E_ECC<4>"
					( Origin gPackager )
				)
				( objectStatus "M_E_ECC<4>" )
			)
			( signal "@baseboard_fab2_lib.baseboard_fab2(sch_1):m_e_ecc(5)"
				( attribute "CDS_PHYS_NET_NAME" "M_E_ECC<5>"
					( Origin gPackager )
				)
				( attribute "PNN" "M_E_ECC<5>"
					( Origin gPackager )
				)
				( objectStatus "M_E_ECC<5>" )
			)
			( signal "@baseboard_fab2_lib.baseboard_fab2(sch_1):m_e_ecc(6)"
				( attribute "CDS_PHYS_NET_NAME" "M_E_ECC<6>"
					( Origin gPackager )
				)
				( attribute "PNN" "M_E_ECC<6>"
					( Origin gPackager )
				)
				( objectStatus "M_E_ECC<6>" )
			)
			( signal "@baseboard_fab2_lib.baseboard_fab2(sch_1):m_e_ecc(7)"
				( attribute "CDS_PHYS_NET_NAME" "M_E_ECC<7>"
					( Origin gPackager )
				)
				( attribute "PNN" "M_E_ECC<7>"
					( Origin gPackager )
				)
				( objectStatus "M_E_ECC<7>" )
			)
			( signal "@baseboard_fab2_lib.baseboard_fab2(sch_1):m_e_ma(0)"
				( attribute "CDS_PHYS_NET_NAME" "M_E_MA<0>"
					( Origin gPackager )
				)
				( attribute "PNN" "M_E_MA<0>"
					( Origin gPackager )
				)
				( objectStatus "M_E_MA<0>" )
			)
			( signal "@baseboard_fab2_lib.baseboard_fab2(sch_1):m_e_ma(1)"
				( attribute "CDS_PHYS_NET_NAME" "M_E_MA<1>"
					( Origin gPackager )
				)
				( attribute "PNN" "M_E_MA<1>"
					( Origin gPackager )
				)
				( objectStatus "M_E_MA<1>" )
			)
			( signal "@baseboard_fab2_lib.baseboard_fab2(sch_1):m_e_ma(2)"
				( attribute "CDS_PHYS_NET_NAME" "M_E_MA<2>"
					( Origin gPackager )
				)
				( attribute "PNN" "M_E_MA<2>"
					( Origin gPackager )
				)
				( objectStatus "M_E_MA<2>" )
			)
			( signal "@baseboard_fab2_lib.baseboard_fab2(sch_1):m_e_ma(3)"
				( attribute "CDS_PHYS_NET_NAME" "M_E_MA<3>"
					( Origin gPackager )
				)
				( attribute "PNN" "M_E_MA<3>"
					( Origin gPackager )
				)
				( objectStatus "M_E_MA<3>" )
			)
			( signal "@baseboard_fab2_lib.baseboard_fab2(sch_1):m_e_ma(4)"
				( attribute "CDS_PHYS_NET_NAME" "M_E_MA<4>"
					( Origin gPackager )
				)
				( attribute "PNN" "M_E_MA<4>"
					( Origin gPackager )
				)
				( objectStatus "M_E_MA<4>" )
			)
			( signal "@baseboard_fab2_lib.baseboard_fab2(sch_1):m_e_ma(5)"
				( attribute "CDS_PHYS_NET_NAME" "M_E_MA<5>"
					( Origin gPackager )
				)
				( attribute "PNN" "M_E_MA<5>"
					( Origin gPackager )
				)
				( objectStatus "M_E_MA<5>" )
			)
			( signal "@baseboard_fab2_lib.baseboard_fab2(sch_1):m_e_ma(6)"
				( attribute "CDS_PHYS_NET_NAME" "M_E_MA<6>"
					( Origin gPackager )
				)
				( attribute "PNN" "M_E_MA<6>"
					( Origin gPackager )
				)
				( objectStatus "M_E_MA<6>" )
			)
			( signal "@baseboard_fab2_lib.baseboard_fab2(sch_1):m_e_ma(7)"
				( attribute "CDS_PHYS_NET_NAME" "M_E_MA<7>"
					( Origin gPackager )
				)
				( attribute "PNN" "M_E_MA<7>"
					( Origin gPackager )
				)
				( objectStatus "M_E_MA<7>" )
			)
			( signal "@baseboard_fab2_lib.baseboard_fab2(sch_1):m_e_ma(8)"
				( attribute "CDS_PHYS_NET_NAME" "M_E_MA<8>"
					( Origin gPackager )
				)
				( attribute "PNN" "M_E_MA<8>"
					( Origin gPackager )
				)
				( objectStatus "M_E_MA<8>" )
			)
			( signal "@baseboard_fab2_lib.baseboard_fab2(sch_1):m_e_ma(9)"
				( attribute "CDS_PHYS_NET_NAME" "M_E_MA<9>"
					( Origin gPackager )
				)
				( attribute "PNN" "M_E_MA<9>"
					( Origin gPackager )
				)
				( objectStatus "M_E_MA<9>" )
			)
			( signal "@baseboard_fab2_lib.baseboard_fab2(sch_1):m_e_ma(10)"
				( attribute "CDS_PHYS_NET_NAME" "M_E_MA<10>"
					( Origin gPackager )
				)
				( attribute "PNN" "M_E_MA<10>"
					( Origin gPackager )
				)
				( objectStatus "M_E_MA<10>" )
			)
			( signal "@baseboard_fab2_lib.baseboard_fab2(sch_1):m_e_ma(11)"
				( attribute "CDS_PHYS_NET_NAME" "M_E_MA<11>"
					( Origin gPackager )
				)
				( attribute "PNN" "M_E_MA<11>"
					( Origin gPackager )
				)
				( objectStatus "M_E_MA<11>" )
			)
			( signal "@baseboard_fab2_lib.baseboard_fab2(sch_1):m_e_ma(12)"
				( attribute "CDS_PHYS_NET_NAME" "M_E_MA<12>"
					( Origin gPackager )
				)
				( attribute "PNN" "M_E_MA<12>"
					( Origin gPackager )
				)
				( objectStatus "M_E_MA<12>" )
			)
			( signal "@baseboard_fab2_lib.baseboard_fab2(sch_1):m_e_ma(13)"
				( attribute "CDS_PHYS_NET_NAME" "M_E_MA<13>"
					( Origin gPackager )
				)
				( attribute "PNN" "M_E_MA<13>"
					( Origin gPackager )
				)
				( objectStatus "M_E_MA<13>" )
			)
			( signal "@baseboard_fab2_lib.baseboard_fab2(sch_1):m_e_ma(14)"
				( attribute "CDS_PHYS_NET_NAME" "M_E_MA<14>"
					( Origin gPackager )
				)
				( attribute "PNN" "M_E_MA<14>"
					( Origin gPackager )
				)
				( objectStatus "M_E_MA<14>" )
			)
			( signal "@baseboard_fab2_lib.baseboard_fab2(sch_1):m_e_ma(15)"
				( attribute "CDS_PHYS_NET_NAME" "M_E_MA<15>"
					( Origin gPackager )
				)
				( attribute "PNN" "M_E_MA<15>"
					( Origin gPackager )
				)
				( objectStatus "M_E_MA<15>" )
			)
			( signal "@baseboard_fab2_lib.baseboard_fab2(sch_1):m_e_ma(16)"
				( attribute "CDS_PHYS_NET_NAME" "M_E_MA<16>"
					( Origin gPackager )
				)
				( attribute "PNN" "M_E_MA<16>"
					( Origin gPackager )
				)
				( objectStatus "M_E_MA<16>" )
			)
			( signal "@baseboard_fab2_lib.baseboard_fab2(sch_1):m_e_ma(17)"
				( attribute "CDS_PHYS_NET_NAME" "M_E_MA<17>"
					( Origin gPackager )
				)
				( attribute "PNN" "M_E_MA<17>"
					( Origin gPackager )
				)
				( objectStatus "M_E_MA<17>" )
			)
			( signal "@baseboard_fab2_lib.baseboard_fab2(sch_1):m_e_odt(0)"
				( attribute "CDS_PHYS_NET_NAME" "M_E_ODT<0>"
					( Origin gPackager )
				)
				( attribute "PNN" "M_E_ODT<0>"
					( Origin gPackager )
				)
				( objectStatus "M_E_ODT<0>" )
			)
			( signal "@baseboard_fab2_lib.baseboard_fab2(sch_1):m_e_odt(1)"
				( attribute "CDS_PHYS_NET_NAME" "M_E_ODT<1>"
					( Origin gPackager )
				)
				( attribute "PNN" "M_E_ODT<1>"
					( Origin gPackager )
				)
				( objectStatus "M_E_ODT<1>" )
			)
			( signal "@baseboard_fab2_lib.baseboard_fab2(sch_1):m_e_odt(2)"
				( attribute "CDS_PHYS_NET_NAME" "M_E_ODT<2>"
					( Origin gPackager )
				)
				( attribute "PNN" "M_E_ODT<2>"
					( Origin gPackager )
				)
				( objectStatus "M_E_ODT<2>" )
			)
			( signal "@baseboard_fab2_lib.baseboard_fab2(sch_1):m_e_odt(3)"
				( attribute "CDS_PHYS_NET_NAME" "M_E_ODT<3>"
					( Origin gPackager )
				)
				( attribute "PNN" "M_E_ODT<3>"
					( Origin gPackager )
				)
				( objectStatus "M_E_ODT<3>" )
			)
			( signal "@baseboard_fab2_lib.baseboard_fab2(sch_1):m_e_par"
				( attribute "CDS_PHYS_NET_NAME" "M_E_PAR"
					( Origin gPackager )
				)
				( objectStatus "M_E_PAR" )
			)
			( signal "@baseboard_fab2_lib.baseboard_fab2(sch_1):m_f_act_n"
				( attribute "CDS_PHYS_NET_NAME" "M_F_ACT_N"
					( Origin gPackager )
				)
				( objectStatus "M_F_ACT_N" )
			)
			( signal "@baseboard_fab2_lib.baseboard_fab2(sch_1):m_f_alert_n"
				( attribute "CDS_PHYS_NET_NAME" "M_F_ALERT_N"
					( Origin gPackager )
				)
				( objectStatus "M_F_ALERT_N" )
			)
			( signal "@baseboard_fab2_lib.baseboard_fab2(sch_1):m_f_ba(0)"
				( attribute "CDS_PHYS_NET_NAME" "M_F_BA<0>"
					( Origin gPackager )
				)
				( attribute "PNN" "M_F_BA<0>"
					( Origin gPackager )
				)
				( objectStatus "M_F_BA<0>" )
			)
			( signal "@baseboard_fab2_lib.baseboard_fab2(sch_1):m_f_ba(1)"
				( attribute "CDS_PHYS_NET_NAME" "M_F_BA<1>"
					( Origin gPackager )
				)
				( attribute "PNN" "M_F_BA<1>"
					( Origin gPackager )
				)
				( objectStatus "M_F_BA<1>" )
			)
			( signal "@baseboard_fab2_lib.baseboard_fab2(sch_1):m_f_bg(0)"
				( attribute "CDS_PHYS_NET_NAME" "M_F_BG<0>"
					( Origin gPackager )
				)
				( attribute "PNN" "M_F_BG<0>"
					( Origin gPackager )
				)
				( objectStatus "M_F_BG<0>" )
			)
			( signal "@baseboard_fab2_lib.baseboard_fab2(sch_1):m_f_bg(1)"
				( attribute "CDS_PHYS_NET_NAME" "M_F_BG<1>"
					( Origin gPackager )
				)
				( attribute "PNN" "M_F_BG<1>"
					( Origin gPackager )
				)
				( objectStatus "M_F_BG<1>" )
			)
			( signal "@baseboard_fab2_lib.baseboard_fab2(sch_1):m_f_c(2)"
				( attribute "CDS_PHYS_NET_NAME" "M_F_C<2>"
					( Origin gPackager )
				)
				( attribute "PNN" "M_F_C<2>"
					( Origin gPackager )
				)
				( objectStatus "M_F_C<2>" )
			)
			( signal "@baseboard_fab2_lib.baseboard_fab2(sch_1):m_f_cke(0)"
				( attribute "CDS_PHYS_NET_NAME" "M_F_CKE<0>"
					( Origin gPackager )
				)
				( attribute "PNN" "M_F_CKE<0>"
					( Origin gPackager )
				)
				( objectStatus "M_F_CKE<0>" )
			)
			( signal "@baseboard_fab2_lib.baseboard_fab2(sch_1):m_f_cke(1)"
				( attribute "CDS_PHYS_NET_NAME" "M_F_CKE<1>"
					( Origin gPackager )
				)
				( attribute "PNN" "M_F_CKE<1>"
					( Origin gPackager )
				)
				( objectStatus "M_F_CKE<1>" )
			)
			( signal "@baseboard_fab2_lib.baseboard_fab2(sch_1):m_f_cke(2)"
				( attribute "CDS_PHYS_NET_NAME" "M_F_CKE<2>"
					( Origin gPackager )
				)
				( attribute "PNN" "M_F_CKE<2>"
					( Origin gPackager )
				)
				( objectStatus "M_F_CKE<2>" )
			)
			( signal "@baseboard_fab2_lib.baseboard_fab2(sch_1):m_f_cke(3)"
				( attribute "CDS_PHYS_NET_NAME" "M_F_CKE<3>"
					( Origin gPackager )
				)
				( attribute "PNN" "M_F_CKE<3>"
					( Origin gPackager )
				)
				( objectStatus "M_F_CKE<3>" )
			)
			( signal "@baseboard_fab2_lib.baseboard_fab2(sch_1):m_f_clk_dn(0)"
				( attribute "CDS_PHYS_NET_NAME" "M_F_CLK_DN<0>"
					( Origin gPackager )
				)
				( attribute "PNN" "M_F_CLK_DN<0>"
					( Origin gPackager )
				)
				( objectStatus "M_F_CLK_DN<0>" )
			)
			( signal "@baseboard_fab2_lib.baseboard_fab2(sch_1):m_f_clk_dn(1)"
				( attribute "CDS_PHYS_NET_NAME" "M_F_CLK_DN<1>"
					( Origin gPackager )
				)
				( attribute "PNN" "M_F_CLK_DN<1>"
					( Origin gPackager )
				)
				( objectStatus "M_F_CLK_DN<1>" )
			)
			( signal "@baseboard_fab2_lib.baseboard_fab2(sch_1):m_f_clk_dn(2)"
				( attribute "CDS_PHYS_NET_NAME" "M_F_CLK_DN<2>"
					( Origin gPackager )
				)
				( attribute "PNN" "M_F_CLK_DN<2>"
					( Origin gPackager )
				)
				( objectStatus "M_F_CLK_DN<2>" )
			)
			( signal "@baseboard_fab2_lib.baseboard_fab2(sch_1):m_f_clk_dn(3)"
				( attribute "CDS_PHYS_NET_NAME" "M_F_CLK_DN<3>"
					( Origin gPackager )
				)
				( attribute "PNN" "M_F_CLK_DN<3>"
					( Origin gPackager )
				)
				( objectStatus "M_F_CLK_DN<3>" )
			)
			( signal "@baseboard_fab2_lib.baseboard_fab2(sch_1):m_f_clk_dp(0)"
				( attribute "CDS_PHYS_NET_NAME" "M_F_CLK_DP<0>"
					( Origin gPackager )
				)
				( attribute "PNN" "M_F_CLK_DP<0>"
					( Origin gPackager )
				)
				( objectStatus "M_F_CLK_DP<0>" )
			)
			( signal "@baseboard_fab2_lib.baseboard_fab2(sch_1):m_f_clk_dp(1)"
				( attribute "CDS_PHYS_NET_NAME" "M_F_CLK_DP<1>"
					( Origin gPackager )
				)
				( attribute "PNN" "M_F_CLK_DP<1>"
					( Origin gPackager )
				)
				( objectStatus "M_F_CLK_DP<1>" )
			)
			( signal "@baseboard_fab2_lib.baseboard_fab2(sch_1):m_f_clk_dp(2)"
				( attribute "CDS_PHYS_NET_NAME" "M_F_CLK_DP<2>"
					( Origin gPackager )
				)
				( attribute "PNN" "M_F_CLK_DP<2>"
					( Origin gPackager )
				)
				( objectStatus "M_F_CLK_DP<2>" )
			)
			( signal "@baseboard_fab2_lib.baseboard_fab2(sch_1):m_f_clk_dp(3)"
				( attribute "CDS_PHYS_NET_NAME" "M_F_CLK_DP<3>"
					( Origin gPackager )
				)
				( attribute "PNN" "M_F_CLK_DP<3>"
					( Origin gPackager )
				)
				( objectStatus "M_F_CLK_DP<3>" )
			)
			( signal "@baseboard_fab2_lib.baseboard_fab2(sch_1):m_f_cs_n(0)"
				( attribute "CDS_PHYS_NET_NAME" "M_F_CS_N<0>"
					( Origin gPackager )
				)
				( attribute "PNN" "M_F_CS_N<0>"
					( Origin gPackager )
				)
				( objectStatus "M_F_CS_N<0>" )
			)
			( signal "@baseboard_fab2_lib.baseboard_fab2(sch_1):m_f_cs_n(1)"
				( attribute "CDS_PHYS_NET_NAME" "M_F_CS_N<1>"
					( Origin gPackager )
				)
				( attribute "PNN" "M_F_CS_N<1>"
					( Origin gPackager )
				)
				( objectStatus "M_F_CS_N<1>" )
			)
			( signal "@baseboard_fab2_lib.baseboard_fab2(sch_1):m_f_cs_n(2)"
				( attribute "CDS_PHYS_NET_NAME" "M_F_CS_N<2>"
					( Origin gPackager )
				)
				( attribute "PNN" "M_F_CS_N<2>"
					( Origin gPackager )
				)
				( objectStatus "M_F_CS_N<2>" )
			)
			( signal "@baseboard_fab2_lib.baseboard_fab2(sch_1):m_f_cs_n(3)"
				( attribute "CDS_PHYS_NET_NAME" "M_F_CS_N<3>"
					( Origin gPackager )
				)
				( attribute "PNN" "M_F_CS_N<3>"
					( Origin gPackager )
				)
				( objectStatus "M_F_CS_N<3>" )
			)
			( signal "@baseboard_fab2_lib.baseboard_fab2(sch_1):m_f_cs_n(4)"
				( attribute "CDS_PHYS_NET_NAME" "M_F_CS_N<4>"
					( Origin gPackager )
				)
				( attribute "PNN" "M_F_CS_N<4>"
					( Origin gPackager )
				)
				( objectStatus "M_F_CS_N<4>" )
			)
			( signal "@baseboard_fab2_lib.baseboard_fab2(sch_1):m_f_cs_n(5)"
				( attribute "CDS_PHYS_NET_NAME" "M_F_CS_N<5>"
					( Origin gPackager )
				)
				( attribute "PNN" "M_F_CS_N<5>"
					( Origin gPackager )
				)
				( objectStatus "M_F_CS_N<5>" )
			)
			( signal "@baseboard_fab2_lib.baseboard_fab2(sch_1):m_f_cs_n(6)"
				( attribute "CDS_PHYS_NET_NAME" "M_F_CS_N<6>"
					( Origin gPackager )
				)
				( attribute "PNN" "M_F_CS_N<6>"
					( Origin gPackager )
				)
				( objectStatus "M_F_CS_N<6>" )
			)
			( signal "@baseboard_fab2_lib.baseboard_fab2(sch_1):m_f_cs_n(7)"
				( attribute "CDS_PHYS_NET_NAME" "M_F_CS_N<7>"
					( Origin gPackager )
				)
				( attribute "PNN" "M_F_CS_N<7>"
					( Origin gPackager )
				)
				( objectStatus "M_F_CS_N<7>" )
			)
			( signal "@baseboard_fab2_lib.baseboard_fab2(sch_1):m_f_dq(0)"
				( attribute "CDS_PHYS_NET_NAME" "M_F_DQ<0>"
					( Origin gPackager )
				)
				( attribute "PNN" "M_F_DQ<0>"
					( Origin gPackager )
				)
				( objectStatus "M_F_DQ<0>" )
			)
			( signal "@baseboard_fab2_lib.baseboard_fab2(sch_1):m_f_dq(1)"
				( attribute "CDS_PHYS_NET_NAME" "M_F_DQ<1>"
					( Origin gPackager )
				)
				( attribute "PNN" "M_F_DQ<1>"
					( Origin gPackager )
				)
				( objectStatus "M_F_DQ<1>" )
			)
			( signal "@baseboard_fab2_lib.baseboard_fab2(sch_1):m_f_dq(2)"
				( attribute "CDS_PHYS_NET_NAME" "M_F_DQ<2>"
					( Origin gPackager )
				)
				( attribute "PNN" "M_F_DQ<2>"
					( Origin gPackager )
				)
				( objectStatus "M_F_DQ<2>" )
			)
			( signal "@baseboard_fab2_lib.baseboard_fab2(sch_1):m_f_dq(3)"
				( attribute "CDS_PHYS_NET_NAME" "M_F_DQ<3>"
					( Origin gPackager )
				)
				( attribute "PNN" "M_F_DQ<3>"
					( Origin gPackager )
				)
				( objectStatus "M_F_DQ<3>" )
			)
			( signal "@baseboard_fab2_lib.baseboard_fab2(sch_1):m_f_dq(4)"
				( attribute "CDS_PHYS_NET_NAME" "M_F_DQ<4>"
					( Origin gPackager )
				)
				( attribute "PNN" "M_F_DQ<4>"
					( Origin gPackager )
				)
				( objectStatus "M_F_DQ<4>" )
			)
			( signal "@baseboard_fab2_lib.baseboard_fab2(sch_1):m_f_dq(5)"
				( attribute "CDS_PHYS_NET_NAME" "M_F_DQ<5>"
					( Origin gPackager )
				)
				( attribute "PNN" "M_F_DQ<5>"
					( Origin gPackager )
				)
				( objectStatus "M_F_DQ<5>" )
			)
			( signal "@baseboard_fab2_lib.baseboard_fab2(sch_1):m_f_dq(6)"
				( attribute "CDS_PHYS_NET_NAME" "M_F_DQ<6>"
					( Origin gPackager )
				)
				( attribute "PNN" "M_F_DQ<6>"
					( Origin gPackager )
				)
				( objectStatus "M_F_DQ<6>" )
			)
			( signal "@baseboard_fab2_lib.baseboard_fab2(sch_1):m_f_dq(7)"
				( attribute "CDS_PHYS_NET_NAME" "M_F_DQ<7>"
					( Origin gPackager )
				)
				( attribute "PNN" "M_F_DQ<7>"
					( Origin gPackager )
				)
				( objectStatus "M_F_DQ<7>" )
			)
			( signal "@baseboard_fab2_lib.baseboard_fab2(sch_1):m_f_dq(8)"
				( attribute "CDS_PHYS_NET_NAME" "M_F_DQ<8>"
					( Origin gPackager )
				)
				( attribute "PNN" "M_F_DQ<8>"
					( Origin gPackager )
				)
				( objectStatus "M_F_DQ<8>" )
			)
			( signal "@baseboard_fab2_lib.baseboard_fab2(sch_1):m_f_dq(9)"
				( attribute "CDS_PHYS_NET_NAME" "M_F_DQ<9>"
					( Origin gPackager )
				)
				( attribute "PNN" "M_F_DQ<9>"
					( Origin gPackager )
				)
				( objectStatus "M_F_DQ<9>" )
			)
			( signal "@baseboard_fab2_lib.baseboard_fab2(sch_1):m_f_dq(10)"
				( attribute "CDS_PHYS_NET_NAME" "M_F_DQ<10>"
					( Origin gPackager )
				)
				( attribute "PNN" "M_F_DQ<10>"
					( Origin gPackager )
				)
				( objectStatus "M_F_DQ<10>" )
			)
			( signal "@baseboard_fab2_lib.baseboard_fab2(sch_1):m_f_dq(11)"
				( attribute "CDS_PHYS_NET_NAME" "M_F_DQ<11>"
					( Origin gPackager )
				)
				( attribute "PNN" "M_F_DQ<11>"
					( Origin gPackager )
				)
				( objectStatus "M_F_DQ<11>" )
			)
			( signal "@baseboard_fab2_lib.baseboard_fab2(sch_1):m_f_dq(12)"
				( attribute "CDS_PHYS_NET_NAME" "M_F_DQ<12>"
					( Origin gPackager )
				)
				( attribute "PNN" "M_F_DQ<12>"
					( Origin gPackager )
				)
				( objectStatus "M_F_DQ<12>" )
			)
			( signal "@baseboard_fab2_lib.baseboard_fab2(sch_1):m_f_dq(13)"
				( attribute "CDS_PHYS_NET_NAME" "M_F_DQ<13>"
					( Origin gPackager )
				)
				( attribute "PNN" "M_F_DQ<13>"
					( Origin gPackager )
				)
				( objectStatus "M_F_DQ<13>" )
			)
			( signal "@baseboard_fab2_lib.baseboard_fab2(sch_1):m_f_dq(14)"
				( attribute "CDS_PHYS_NET_NAME" "M_F_DQ<14>"
					( Origin gPackager )
				)
				( attribute "PNN" "M_F_DQ<14>"
					( Origin gPackager )
				)
				( objectStatus "M_F_DQ<14>" )
			)
			( signal "@baseboard_fab2_lib.baseboard_fab2(sch_1):m_f_dq(15)"
				( attribute "CDS_PHYS_NET_NAME" "M_F_DQ<15>"
					( Origin gPackager )
				)
				( attribute "PNN" "M_F_DQ<15>"
					( Origin gPackager )
				)
				( objectStatus "M_F_DQ<15>" )
			)
			( signal "@baseboard_fab2_lib.baseboard_fab2(sch_1):m_f_dq(16)"
				( attribute "CDS_PHYS_NET_NAME" "M_F_DQ<16>"
					( Origin gPackager )
				)
				( attribute "PNN" "M_F_DQ<16>"
					( Origin gPackager )
				)
				( objectStatus "M_F_DQ<16>" )
			)
			( signal "@baseboard_fab2_lib.baseboard_fab2(sch_1):m_f_dq(17)"
				( attribute "CDS_PHYS_NET_NAME" "M_F_DQ<17>"
					( Origin gPackager )
				)
				( attribute "PNN" "M_F_DQ<17>"
					( Origin gPackager )
				)
				( objectStatus "M_F_DQ<17>" )
			)
			( signal "@baseboard_fab2_lib.baseboard_fab2(sch_1):m_f_dq(18)"
				( attribute "CDS_PHYS_NET_NAME" "M_F_DQ<18>"
					( Origin gPackager )
				)
				( attribute "PNN" "M_F_DQ<18>"
					( Origin gPackager )
				)
				( objectStatus "M_F_DQ<18>" )
			)
			( signal "@baseboard_fab2_lib.baseboard_fab2(sch_1):m_f_dq(19)"
				( attribute "CDS_PHYS_NET_NAME" "M_F_DQ<19>"
					( Origin gPackager )
				)
				( attribute "PNN" "M_F_DQ<19>"
					( Origin gPackager )
				)
				( objectStatus "M_F_DQ<19>" )
			)
			( signal "@baseboard_fab2_lib.baseboard_fab2(sch_1):m_f_dq(20)"
				( attribute "CDS_PHYS_NET_NAME" "M_F_DQ<20>"
					( Origin gPackager )
				)
				( attribute "PNN" "M_F_DQ<20>"
					( Origin gPackager )
				)
				( objectStatus "M_F_DQ<20>" )
			)
			( signal "@baseboard_fab2_lib.baseboard_fab2(sch_1):m_f_dq(21)"
				( attribute "CDS_PHYS_NET_NAME" "M_F_DQ<21>"
					( Origin gPackager )
				)
				( attribute "PNN" "M_F_DQ<21>"
					( Origin gPackager )
				)
				( objectStatus "M_F_DQ<21>" )
			)
			( signal "@baseboard_fab2_lib.baseboard_fab2(sch_1):m_f_dq(22)"
				( attribute "CDS_PHYS_NET_NAME" "M_F_DQ<22>"
					( Origin gPackager )
				)
				( attribute "PNN" "M_F_DQ<22>"
					( Origin gPackager )
				)
				( objectStatus "M_F_DQ<22>" )
			)
			( signal "@baseboard_fab2_lib.baseboard_fab2(sch_1):m_f_dq(23)"
				( attribute "CDS_PHYS_NET_NAME" "M_F_DQ<23>"
					( Origin gPackager )
				)
				( attribute "PNN" "M_F_DQ<23>"
					( Origin gPackager )
				)
				( objectStatus "M_F_DQ<23>" )
			)
			( signal "@baseboard_fab2_lib.baseboard_fab2(sch_1):m_f_dq(24)"
				( attribute "CDS_PHYS_NET_NAME" "M_F_DQ<24>"
					( Origin gPackager )
				)
				( attribute "PNN" "M_F_DQ<24>"
					( Origin gPackager )
				)
				( objectStatus "M_F_DQ<24>" )
			)
			( signal "@baseboard_fab2_lib.baseboard_fab2(sch_1):m_f_dq(25)"
				( attribute "CDS_PHYS_NET_NAME" "M_F_DQ<25>"
					( Origin gPackager )
				)
				( attribute "PNN" "M_F_DQ<25>"
					( Origin gPackager )
				)
				( objectStatus "M_F_DQ<25>" )
			)
			( signal "@baseboard_fab2_lib.baseboard_fab2(sch_1):m_f_dq(26)"
				( attribute "CDS_PHYS_NET_NAME" "M_F_DQ<26>"
					( Origin gPackager )
				)
				( attribute "PNN" "M_F_DQ<26>"
					( Origin gPackager )
				)
				( objectStatus "M_F_DQ<26>" )
			)
			( signal "@baseboard_fab2_lib.baseboard_fab2(sch_1):m_f_dq(27)"
				( attribute "CDS_PHYS_NET_NAME" "M_F_DQ<27>"
					( Origin gPackager )
				)
				( attribute "PNN" "M_F_DQ<27>"
					( Origin gPackager )
				)
				( objectStatus "M_F_DQ<27>" )
			)
			( signal "@baseboard_fab2_lib.baseboard_fab2(sch_1):m_f_dq(28)"
				( attribute "CDS_PHYS_NET_NAME" "M_F_DQ<28>"
					( Origin gPackager )
				)
				( attribute "PNN" "M_F_DQ<28>"
					( Origin gPackager )
				)
				( objectStatus "M_F_DQ<28>" )
			)
			( signal "@baseboard_fab2_lib.baseboard_fab2(sch_1):m_f_dq(29)"
				( attribute "CDS_PHYS_NET_NAME" "M_F_DQ<29>"
					( Origin gPackager )
				)
				( attribute "PNN" "M_F_DQ<29>"
					( Origin gPackager )
				)
				( objectStatus "M_F_DQ<29>" )
			)
			( signal "@baseboard_fab2_lib.baseboard_fab2(sch_1):m_f_dq(30)"
				( attribute "CDS_PHYS_NET_NAME" "M_F_DQ<30>"
					( Origin gPackager )
				)
				( attribute "PNN" "M_F_DQ<30>"
					( Origin gPackager )
				)
				( objectStatus "M_F_DQ<30>" )
			)
			( signal "@baseboard_fab2_lib.baseboard_fab2(sch_1):m_f_dq(31)"
				( attribute "CDS_PHYS_NET_NAME" "M_F_DQ<31>"
					( Origin gPackager )
				)
				( attribute "PNN" "M_F_DQ<31>"
					( Origin gPackager )
				)
				( objectStatus "M_F_DQ<31>" )
			)
			( signal "@baseboard_fab2_lib.baseboard_fab2(sch_1):m_f_dq(32)"
				( attribute "CDS_PHYS_NET_NAME" "M_F_DQ<32>"
					( Origin gPackager )
				)
				( attribute "PNN" "M_F_DQ<32>"
					( Origin gPackager )
				)
				( objectStatus "M_F_DQ<32>" )
			)
			( signal "@baseboard_fab2_lib.baseboard_fab2(sch_1):m_f_dq(33)"
				( attribute "CDS_PHYS_NET_NAME" "M_F_DQ<33>"
					( Origin gPackager )
				)
				( attribute "PNN" "M_F_DQ<33>"
					( Origin gPackager )
				)
				( objectStatus "M_F_DQ<33>" )
			)
			( signal "@baseboard_fab2_lib.baseboard_fab2(sch_1):m_f_dq(34)"
				( attribute "CDS_PHYS_NET_NAME" "M_F_DQ<34>"
					( Origin gPackager )
				)
				( attribute "PNN" "M_F_DQ<34>"
					( Origin gPackager )
				)
				( objectStatus "M_F_DQ<34>" )
			)
			( signal "@baseboard_fab2_lib.baseboard_fab2(sch_1):m_f_dq(35)"
				( attribute "CDS_PHYS_NET_NAME" "M_F_DQ<35>"
					( Origin gPackager )
				)
				( attribute "PNN" "M_F_DQ<35>"
					( Origin gPackager )
				)
				( objectStatus "M_F_DQ<35>" )
			)
			( signal "@baseboard_fab2_lib.baseboard_fab2(sch_1):m_f_dq(36)"
				( attribute "CDS_PHYS_NET_NAME" "M_F_DQ<36>"
					( Origin gPackager )
				)
				( attribute "PNN" "M_F_DQ<36>"
					( Origin gPackager )
				)
				( objectStatus "M_F_DQ<36>" )
			)
			( signal "@baseboard_fab2_lib.baseboard_fab2(sch_1):m_f_dq(37)"
				( attribute "CDS_PHYS_NET_NAME" "M_F_DQ<37>"
					( Origin gPackager )
				)
				( attribute "PNN" "M_F_DQ<37>"
					( Origin gPackager )
				)
				( objectStatus "M_F_DQ<37>" )
			)
			( signal "@baseboard_fab2_lib.baseboard_fab2(sch_1):m_f_dq(38)"
				( attribute "CDS_PHYS_NET_NAME" "M_F_DQ<38>"
					( Origin gPackager )
				)
				( attribute "PNN" "M_F_DQ<38>"
					( Origin gPackager )
				)
				( objectStatus "M_F_DQ<38>" )
			)
			( signal "@baseboard_fab2_lib.baseboard_fab2(sch_1):m_f_dq(39)"
				( attribute "CDS_PHYS_NET_NAME" "M_F_DQ<39>"
					( Origin gPackager )
				)
				( attribute "PNN" "M_F_DQ<39>"
					( Origin gPackager )
				)
				( objectStatus "M_F_DQ<39>" )
			)
			( signal "@baseboard_fab2_lib.baseboard_fab2(sch_1):m_f_dq(40)"
				( attribute "CDS_PHYS_NET_NAME" "M_F_DQ<40>"
					( Origin gPackager )
				)
				( attribute "PNN" "M_F_DQ<40>"
					( Origin gPackager )
				)
				( objectStatus "M_F_DQ<40>" )
			)
			( signal "@baseboard_fab2_lib.baseboard_fab2(sch_1):m_f_dq(41)"
				( attribute "CDS_PHYS_NET_NAME" "M_F_DQ<41>"
					( Origin gPackager )
				)
				( attribute "PNN" "M_F_DQ<41>"
					( Origin gPackager )
				)
				( objectStatus "M_F_DQ<41>" )
			)
			( signal "@baseboard_fab2_lib.baseboard_fab2(sch_1):m_f_dq(42)"
				( attribute "CDS_PHYS_NET_NAME" "M_F_DQ<42>"
					( Origin gPackager )
				)
				( attribute "PNN" "M_F_DQ<42>"
					( Origin gPackager )
				)
				( objectStatus "M_F_DQ<42>" )
			)
			( signal "@baseboard_fab2_lib.baseboard_fab2(sch_1):m_f_dq(43)"
				( attribute "CDS_PHYS_NET_NAME" "M_F_DQ<43>"
					( Origin gPackager )
				)
				( attribute "PNN" "M_F_DQ<43>"
					( Origin gPackager )
				)
				( objectStatus "M_F_DQ<43>" )
			)
			( signal "@baseboard_fab2_lib.baseboard_fab2(sch_1):m_f_dq(44)"
				( attribute "CDS_PHYS_NET_NAME" "M_F_DQ<44>"
					( Origin gPackager )
				)
				( attribute "PNN" "M_F_DQ<44>"
					( Origin gPackager )
				)
				( objectStatus "M_F_DQ<44>" )
			)
			( signal "@baseboard_fab2_lib.baseboard_fab2(sch_1):m_f_dq(45)"
				( attribute "CDS_PHYS_NET_NAME" "M_F_DQ<45>"
					( Origin gPackager )
				)
				( attribute "PNN" "M_F_DQ<45>"
					( Origin gPackager )
				)
				( objectStatus "M_F_DQ<45>" )
			)
			( signal "@baseboard_fab2_lib.baseboard_fab2(sch_1):m_f_dq(46)"
				( attribute "CDS_PHYS_NET_NAME" "M_F_DQ<46>"
					( Origin gPackager )
				)
				( attribute "PNN" "M_F_DQ<46>"
					( Origin gPackager )
				)
				( objectStatus "M_F_DQ<46>" )
			)
			( signal "@baseboard_fab2_lib.baseboard_fab2(sch_1):m_f_dq(47)"
				( attribute "CDS_PHYS_NET_NAME" "M_F_DQ<47>"
					( Origin gPackager )
				)
				( attribute "PNN" "M_F_DQ<47>"
					( Origin gPackager )
				)
				( objectStatus "M_F_DQ<47>" )
			)
			( signal "@baseboard_fab2_lib.baseboard_fab2(sch_1):m_f_dq(48)"
				( attribute "CDS_PHYS_NET_NAME" "M_F_DQ<48>"
					( Origin gPackager )
				)
				( attribute "PNN" "M_F_DQ<48>"
					( Origin gPackager )
				)
				( objectStatus "M_F_DQ<48>" )
			)
			( signal "@baseboard_fab2_lib.baseboard_fab2(sch_1):m_f_dq(49)"
				( attribute "CDS_PHYS_NET_NAME" "M_F_DQ<49>"
					( Origin gPackager )
				)
				( attribute "PNN" "M_F_DQ<49>"
					( Origin gPackager )
				)
				( objectStatus "M_F_DQ<49>" )
			)
			( signal "@baseboard_fab2_lib.baseboard_fab2(sch_1):m_f_dq(50)"
				( attribute "CDS_PHYS_NET_NAME" "M_F_DQ<50>"
					( Origin gPackager )
				)
				( attribute "PNN" "M_F_DQ<50>"
					( Origin gPackager )
				)
				( objectStatus "M_F_DQ<50>" )
			)
			( signal "@baseboard_fab2_lib.baseboard_fab2(sch_1):m_f_dq(51)"
				( attribute "CDS_PHYS_NET_NAME" "M_F_DQ<51>"
					( Origin gPackager )
				)
				( attribute "PNN" "M_F_DQ<51>"
					( Origin gPackager )
				)
				( objectStatus "M_F_DQ<51>" )
			)
			( signal "@baseboard_fab2_lib.baseboard_fab2(sch_1):m_f_dq(52)"
				( attribute "CDS_PHYS_NET_NAME" "M_F_DQ<52>"
					( Origin gPackager )
				)
				( attribute "PNN" "M_F_DQ<52>"
					( Origin gPackager )
				)
				( objectStatus "M_F_DQ<52>" )
			)
			( signal "@baseboard_fab2_lib.baseboard_fab2(sch_1):m_f_dq(53)"
				( attribute "CDS_PHYS_NET_NAME" "M_F_DQ<53>"
					( Origin gPackager )
				)
				( attribute "PNN" "M_F_DQ<53>"
					( Origin gPackager )
				)
				( objectStatus "M_F_DQ<53>" )
			)
			( signal "@baseboard_fab2_lib.baseboard_fab2(sch_1):m_f_dq(54)"
				( attribute "CDS_PHYS_NET_NAME" "M_F_DQ<54>"
					( Origin gPackager )
				)
				( attribute "PNN" "M_F_DQ<54>"
					( Origin gPackager )
				)
				( objectStatus "M_F_DQ<54>" )
			)
			( signal "@baseboard_fab2_lib.baseboard_fab2(sch_1):m_f_dq(55)"
				( attribute "CDS_PHYS_NET_NAME" "M_F_DQ<55>"
					( Origin gPackager )
				)
				( attribute "PNN" "M_F_DQ<55>"
					( Origin gPackager )
				)
				( objectStatus "M_F_DQ<55>" )
			)
			( signal "@baseboard_fab2_lib.baseboard_fab2(sch_1):m_f_dq(56)"
				( attribute "CDS_PHYS_NET_NAME" "M_F_DQ<56>"
					( Origin gPackager )
				)
				( attribute "PNN" "M_F_DQ<56>"
					( Origin gPackager )
				)
				( objectStatus "M_F_DQ<56>" )
			)
			( signal "@baseboard_fab2_lib.baseboard_fab2(sch_1):m_f_dq(57)"
				( attribute "CDS_PHYS_NET_NAME" "M_F_DQ<57>"
					( Origin gPackager )
				)
				( attribute "PNN" "M_F_DQ<57>"
					( Origin gPackager )
				)
				( objectStatus "M_F_DQ<57>" )
			)
			( signal "@baseboard_fab2_lib.baseboard_fab2(sch_1):m_f_dq(58)"
				( attribute "CDS_PHYS_NET_NAME" "M_F_DQ<58>"
					( Origin gPackager )
				)
				( attribute "PNN" "M_F_DQ<58>"
					( Origin gPackager )
				)
				( objectStatus "M_F_DQ<58>" )
			)
			( signal "@baseboard_fab2_lib.baseboard_fab2(sch_1):m_f_dq(59)"
				( attribute "CDS_PHYS_NET_NAME" "M_F_DQ<59>"
					( Origin gPackager )
				)
				( attribute "PNN" "M_F_DQ<59>"
					( Origin gPackager )
				)
				( objectStatus "M_F_DQ<59>" )
			)
			( signal "@baseboard_fab2_lib.baseboard_fab2(sch_1):m_f_dq(60)"
				( attribute "CDS_PHYS_NET_NAME" "M_F_DQ<60>"
					( Origin gPackager )
				)
				( attribute "PNN" "M_F_DQ<60>"
					( Origin gPackager )
				)
				( objectStatus "M_F_DQ<60>" )
			)
			( signal "@baseboard_fab2_lib.baseboard_fab2(sch_1):m_f_dq(61)"
				( attribute "CDS_PHYS_NET_NAME" "M_F_DQ<61>"
					( Origin gPackager )
				)
				( attribute "PNN" "M_F_DQ<61>"
					( Origin gPackager )
				)
				( objectStatus "M_F_DQ<61>" )
			)
			( signal "@baseboard_fab2_lib.baseboard_fab2(sch_1):m_f_dq(62)"
				( attribute "CDS_PHYS_NET_NAME" "M_F_DQ<62>"
					( Origin gPackager )
				)
				( attribute "PNN" "M_F_DQ<62>"
					( Origin gPackager )
				)
				( objectStatus "M_F_DQ<62>" )
			)
			( signal "@baseboard_fab2_lib.baseboard_fab2(sch_1):m_f_dq(63)"
				( attribute "CDS_PHYS_NET_NAME" "M_F_DQ<63>"
					( Origin gPackager )
				)
				( attribute "PNN" "M_F_DQ<63>"
					( Origin gPackager )
				)
				( objectStatus "M_F_DQ<63>" )
			)
			( signal "@baseboard_fab2_lib.baseboard_fab2(sch_1):m_f_dqs_dn(0)"
				( attribute "CDS_PHYS_NET_NAME" "M_F_DQS_DN<0>"
					( Origin gPackager )
				)
				( attribute "PNN" "M_F_DQS_DN<0>"
					( Origin gPackager )
				)
				( objectStatus "M_F_DQS_DN<0>" )
			)
			( signal "@baseboard_fab2_lib.baseboard_fab2(sch_1):m_f_dqs_dn(1)"
				( attribute "CDS_PHYS_NET_NAME" "M_F_DQS_DN<1>"
					( Origin gPackager )
				)
				( attribute "PNN" "M_F_DQS_DN<1>"
					( Origin gPackager )
				)
				( objectStatus "M_F_DQS_DN<1>" )
			)
			( signal "@baseboard_fab2_lib.baseboard_fab2(sch_1):m_f_dqs_dn(2)"
				( attribute "CDS_PHYS_NET_NAME" "M_F_DQS_DN<2>"
					( Origin gPackager )
				)
				( attribute "PNN" "M_F_DQS_DN<2>"
					( Origin gPackager )
				)
				( objectStatus "M_F_DQS_DN<2>" )
			)
			( signal "@baseboard_fab2_lib.baseboard_fab2(sch_1):m_f_dqs_dn(3)"
				( attribute "CDS_PHYS_NET_NAME" "M_F_DQS_DN<3>"
					( Origin gPackager )
				)
				( attribute "PNN" "M_F_DQS_DN<3>"
					( Origin gPackager )
				)
				( objectStatus "M_F_DQS_DN<3>" )
			)
			( signal "@baseboard_fab2_lib.baseboard_fab2(sch_1):m_f_dqs_dn(4)"
				( attribute "CDS_PHYS_NET_NAME" "M_F_DQS_DN<4>"
					( Origin gPackager )
				)
				( attribute "PNN" "M_F_DQS_DN<4>"
					( Origin gPackager )
				)
				( objectStatus "M_F_DQS_DN<4>" )
			)
			( signal "@baseboard_fab2_lib.baseboard_fab2(sch_1):m_f_dqs_dn(5)"
				( attribute "CDS_PHYS_NET_NAME" "M_F_DQS_DN<5>"
					( Origin gPackager )
				)
				( attribute "PNN" "M_F_DQS_DN<5>"
					( Origin gPackager )
				)
				( objectStatus "M_F_DQS_DN<5>" )
			)
			( signal "@baseboard_fab2_lib.baseboard_fab2(sch_1):m_f_dqs_dn(6)"
				( attribute "CDS_PHYS_NET_NAME" "M_F_DQS_DN<6>"
					( Origin gPackager )
				)
				( attribute "PNN" "M_F_DQS_DN<6>"
					( Origin gPackager )
				)
				( objectStatus "M_F_DQS_DN<6>" )
			)
			( signal "@baseboard_fab2_lib.baseboard_fab2(sch_1):m_f_dqs_dn(7)"
				( attribute "CDS_PHYS_NET_NAME" "M_F_DQS_DN<7>"
					( Origin gPackager )
				)
				( attribute "PNN" "M_F_DQS_DN<7>"
					( Origin gPackager )
				)
				( objectStatus "M_F_DQS_DN<7>" )
			)
			( signal "@baseboard_fab2_lib.baseboard_fab2(sch_1):m_f_dqs_dn(8)"
				( attribute "CDS_PHYS_NET_NAME" "M_F_DQS_DN<8>"
					( Origin gPackager )
				)
				( attribute "PNN" "M_F_DQS_DN<8>"
					( Origin gPackager )
				)
				( objectStatus "M_F_DQS_DN<8>" )
			)
			( signal "@baseboard_fab2_lib.baseboard_fab2(sch_1):m_f_dqs_dn(9)"
				( attribute "CDS_PHYS_NET_NAME" "M_F_DQS_DN<9>"
					( Origin gPackager )
				)
				( attribute "PNN" "M_F_DQS_DN<9>"
					( Origin gPackager )
				)
				( objectStatus "M_F_DQS_DN<9>" )
			)
			( signal "@baseboard_fab2_lib.baseboard_fab2(sch_1):m_f_dqs_dn(10)"
				( attribute "CDS_PHYS_NET_NAME" "M_F_DQS_DN<10>"
					( Origin gPackager )
				)
				( attribute "PNN" "M_F_DQS_DN<10>"
					( Origin gPackager )
				)
				( objectStatus "M_F_DQS_DN<10>" )
			)
			( signal "@baseboard_fab2_lib.baseboard_fab2(sch_1):m_f_dqs_dn(11)"
				( attribute "CDS_PHYS_NET_NAME" "M_F_DQS_DN<11>"
					( Origin gPackager )
				)
				( attribute "PNN" "M_F_DQS_DN<11>"
					( Origin gPackager )
				)
				( objectStatus "M_F_DQS_DN<11>" )
			)
			( signal "@baseboard_fab2_lib.baseboard_fab2(sch_1):m_f_dqs_dn(12)"
				( attribute "CDS_PHYS_NET_NAME" "M_F_DQS_DN<12>"
					( Origin gPackager )
				)
				( attribute "PNN" "M_F_DQS_DN<12>"
					( Origin gPackager )
				)
				( objectStatus "M_F_DQS_DN<12>" )
			)
			( signal "@baseboard_fab2_lib.baseboard_fab2(sch_1):m_f_dqs_dn(13)"
				( attribute "CDS_PHYS_NET_NAME" "M_F_DQS_DN<13>"
					( Origin gPackager )
				)
				( attribute "PNN" "M_F_DQS_DN<13>"
					( Origin gPackager )
				)
				( objectStatus "M_F_DQS_DN<13>" )
			)
			( signal "@baseboard_fab2_lib.baseboard_fab2(sch_1):m_f_dqs_dn(14)"
				( attribute "CDS_PHYS_NET_NAME" "M_F_DQS_DN<14>"
					( Origin gPackager )
				)
				( attribute "PNN" "M_F_DQS_DN<14>"
					( Origin gPackager )
				)
				( objectStatus "M_F_DQS_DN<14>" )
			)
			( signal "@baseboard_fab2_lib.baseboard_fab2(sch_1):m_f_dqs_dn(15)"
				( attribute "CDS_PHYS_NET_NAME" "M_F_DQS_DN<15>"
					( Origin gPackager )
				)
				( attribute "PNN" "M_F_DQS_DN<15>"
					( Origin gPackager )
				)
				( objectStatus "M_F_DQS_DN<15>" )
			)
			( signal "@baseboard_fab2_lib.baseboard_fab2(sch_1):m_f_dqs_dn(16)"
				( attribute "CDS_PHYS_NET_NAME" "M_F_DQS_DN<16>"
					( Origin gPackager )
				)
				( attribute "PNN" "M_F_DQS_DN<16>"
					( Origin gPackager )
				)
				( objectStatus "M_F_DQS_DN<16>" )
			)
			( signal "@baseboard_fab2_lib.baseboard_fab2(sch_1):m_f_dqs_dn(17)"
				( attribute "CDS_PHYS_NET_NAME" "M_F_DQS_DN<17>"
					( Origin gPackager )
				)
				( attribute "PNN" "M_F_DQS_DN<17>"
					( Origin gPackager )
				)
				( objectStatus "M_F_DQS_DN<17>" )
			)
			( signal "@baseboard_fab2_lib.baseboard_fab2(sch_1):m_f_dqs_dp(0)"
				( attribute "CDS_PHYS_NET_NAME" "M_F_DQS_DP<0>"
					( Origin gPackager )
				)
				( attribute "PNN" "M_F_DQS_DP<0>"
					( Origin gPackager )
				)
				( objectStatus "M_F_DQS_DP<0>" )
			)
			( signal "@baseboard_fab2_lib.baseboard_fab2(sch_1):m_f_dqs_dp(1)"
				( attribute "CDS_PHYS_NET_NAME" "M_F_DQS_DP<1>"
					( Origin gPackager )
				)
				( attribute "PNN" "M_F_DQS_DP<1>"
					( Origin gPackager )
				)
				( objectStatus "M_F_DQS_DP<1>" )
			)
			( signal "@baseboard_fab2_lib.baseboard_fab2(sch_1):m_f_dqs_dp(2)"
				( attribute "CDS_PHYS_NET_NAME" "M_F_DQS_DP<2>"
					( Origin gPackager )
				)
				( attribute "PNN" "M_F_DQS_DP<2>"
					( Origin gPackager )
				)
				( objectStatus "M_F_DQS_DP<2>" )
			)
			( signal "@baseboard_fab2_lib.baseboard_fab2(sch_1):m_f_dqs_dp(3)"
				( attribute "CDS_PHYS_NET_NAME" "M_F_DQS_DP<3>"
					( Origin gPackager )
				)
				( attribute "PNN" "M_F_DQS_DP<3>"
					( Origin gPackager )
				)
				( objectStatus "M_F_DQS_DP<3>" )
			)
			( signal "@baseboard_fab2_lib.baseboard_fab2(sch_1):m_f_dqs_dp(4)"
				( attribute "CDS_PHYS_NET_NAME" "M_F_DQS_DP<4>"
					( Origin gPackager )
				)
				( attribute "PNN" "M_F_DQS_DP<4>"
					( Origin gPackager )
				)
				( objectStatus "M_F_DQS_DP<4>" )
			)
			( signal "@baseboard_fab2_lib.baseboard_fab2(sch_1):m_f_dqs_dp(5)"
				( attribute "CDS_PHYS_NET_NAME" "M_F_DQS_DP<5>"
					( Origin gPackager )
				)
				( attribute "PNN" "M_F_DQS_DP<5>"
					( Origin gPackager )
				)
				( objectStatus "M_F_DQS_DP<5>" )
			)
			( signal "@baseboard_fab2_lib.baseboard_fab2(sch_1):m_f_dqs_dp(6)"
				( attribute "CDS_PHYS_NET_NAME" "M_F_DQS_DP<6>"
					( Origin gPackager )
				)
				( attribute "PNN" "M_F_DQS_DP<6>"
					( Origin gPackager )
				)
				( objectStatus "M_F_DQS_DP<6>" )
			)
			( signal "@baseboard_fab2_lib.baseboard_fab2(sch_1):m_f_dqs_dp(7)"
				( attribute "CDS_PHYS_NET_NAME" "M_F_DQS_DP<7>"
					( Origin gPackager )
				)
				( attribute "PNN" "M_F_DQS_DP<7>"
					( Origin gPackager )
				)
				( objectStatus "M_F_DQS_DP<7>" )
			)
			( signal "@baseboard_fab2_lib.baseboard_fab2(sch_1):m_f_dqs_dp(8)"
				( attribute "CDS_PHYS_NET_NAME" "M_F_DQS_DP<8>"
					( Origin gPackager )
				)
				( attribute "PNN" "M_F_DQS_DP<8>"
					( Origin gPackager )
				)
				( objectStatus "M_F_DQS_DP<8>" )
			)
			( signal "@baseboard_fab2_lib.baseboard_fab2(sch_1):m_f_dqs_dp(9)"
				( attribute "CDS_PHYS_NET_NAME" "M_F_DQS_DP<9>"
					( Origin gPackager )
				)
				( attribute "PNN" "M_F_DQS_DP<9>"
					( Origin gPackager )
				)
				( objectStatus "M_F_DQS_DP<9>" )
			)
			( signal "@baseboard_fab2_lib.baseboard_fab2(sch_1):m_f_dqs_dp(10)"
				( attribute "CDS_PHYS_NET_NAME" "M_F_DQS_DP<10>"
					( Origin gPackager )
				)
				( attribute "PNN" "M_F_DQS_DP<10>"
					( Origin gPackager )
				)
				( objectStatus "M_F_DQS_DP<10>" )
			)
			( signal "@baseboard_fab2_lib.baseboard_fab2(sch_1):m_f_dqs_dp(11)"
				( attribute "CDS_PHYS_NET_NAME" "M_F_DQS_DP<11>"
					( Origin gPackager )
				)
				( attribute "PNN" "M_F_DQS_DP<11>"
					( Origin gPackager )
				)
				( objectStatus "M_F_DQS_DP<11>" )
			)
			( signal "@baseboard_fab2_lib.baseboard_fab2(sch_1):m_f_dqs_dp(12)"
				( attribute "CDS_PHYS_NET_NAME" "M_F_DQS_DP<12>"
					( Origin gPackager )
				)
				( attribute "PNN" "M_F_DQS_DP<12>"
					( Origin gPackager )
				)
				( objectStatus "M_F_DQS_DP<12>" )
			)
			( signal "@baseboard_fab2_lib.baseboard_fab2(sch_1):m_f_dqs_dp(13)"
				( attribute "CDS_PHYS_NET_NAME" "M_F_DQS_DP<13>"
					( Origin gPackager )
				)
				( attribute "PNN" "M_F_DQS_DP<13>"
					( Origin gPackager )
				)
				( objectStatus "M_F_DQS_DP<13>" )
			)
			( signal "@baseboard_fab2_lib.baseboard_fab2(sch_1):m_f_dqs_dp(14)"
				( attribute "CDS_PHYS_NET_NAME" "M_F_DQS_DP<14>"
					( Origin gPackager )
				)
				( attribute "PNN" "M_F_DQS_DP<14>"
					( Origin gPackager )
				)
				( objectStatus "M_F_DQS_DP<14>" )
			)
			( signal "@baseboard_fab2_lib.baseboard_fab2(sch_1):m_f_dqs_dp(15)"
				( attribute "CDS_PHYS_NET_NAME" "M_F_DQS_DP<15>"
					( Origin gPackager )
				)
				( attribute "PNN" "M_F_DQS_DP<15>"
					( Origin gPackager )
				)
				( objectStatus "M_F_DQS_DP<15>" )
			)
			( signal "@baseboard_fab2_lib.baseboard_fab2(sch_1):m_f_dqs_dp(16)"
				( attribute "CDS_PHYS_NET_NAME" "M_F_DQS_DP<16>"
					( Origin gPackager )
				)
				( attribute "PNN" "M_F_DQS_DP<16>"
					( Origin gPackager )
				)
				( objectStatus "M_F_DQS_DP<16>" )
			)
			( signal "@baseboard_fab2_lib.baseboard_fab2(sch_1):m_f_dqs_dp(17)"
				( attribute "CDS_PHYS_NET_NAME" "M_F_DQS_DP<17>"
					( Origin gPackager )
				)
				( attribute "PNN" "M_F_DQS_DP<17>"
					( Origin gPackager )
				)
				( objectStatus "M_F_DQS_DP<17>" )
			)
			( signal "@baseboard_fab2_lib.baseboard_fab2(sch_1):m_f_ecc(0)"
				( attribute "CDS_PHYS_NET_NAME" "M_F_ECC<0>"
					( Origin gPackager )
				)
				( attribute "PNN" "M_F_ECC<0>"
					( Origin gPackager )
				)
				( objectStatus "M_F_ECC<0>" )
			)
			( signal "@baseboard_fab2_lib.baseboard_fab2(sch_1):m_f_ecc(1)"
				( attribute "CDS_PHYS_NET_NAME" "M_F_ECC<1>"
					( Origin gPackager )
				)
				( attribute "PNN" "M_F_ECC<1>"
					( Origin gPackager )
				)
				( objectStatus "M_F_ECC<1>" )
			)
			( signal "@baseboard_fab2_lib.baseboard_fab2(sch_1):m_f_ecc(2)"
				( attribute "CDS_PHYS_NET_NAME" "M_F_ECC<2>"
					( Origin gPackager )
				)
				( attribute "PNN" "M_F_ECC<2>"
					( Origin gPackager )
				)
				( objectStatus "M_F_ECC<2>" )
			)
			( signal "@baseboard_fab2_lib.baseboard_fab2(sch_1):m_f_ecc(3)"
				( attribute "CDS_PHYS_NET_NAME" "M_F_ECC<3>"
					( Origin gPackager )
				)
				( attribute "PNN" "M_F_ECC<3>"
					( Origin gPackager )
				)
				( objectStatus "M_F_ECC<3>" )
			)
			( signal "@baseboard_fab2_lib.baseboard_fab2(sch_1):m_f_ecc(4)"
				( attribute "CDS_PHYS_NET_NAME" "M_F_ECC<4>"
					( Origin gPackager )
				)
				( attribute "PNN" "M_F_ECC<4>"
					( Origin gPackager )
				)
				( objectStatus "M_F_ECC<4>" )
			)
			( signal "@baseboard_fab2_lib.baseboard_fab2(sch_1):m_f_ecc(5)"
				( attribute "CDS_PHYS_NET_NAME" "M_F_ECC<5>"
					( Origin gPackager )
				)
				( attribute "PNN" "M_F_ECC<5>"
					( Origin gPackager )
				)
				( objectStatus "M_F_ECC<5>" )
			)
			( signal "@baseboard_fab2_lib.baseboard_fab2(sch_1):m_f_ecc(6)"
				( attribute "CDS_PHYS_NET_NAME" "M_F_ECC<6>"
					( Origin gPackager )
				)
				( attribute "PNN" "M_F_ECC<6>"
					( Origin gPackager )
				)
				( objectStatus "M_F_ECC<6>" )
			)
			( signal "@baseboard_fab2_lib.baseboard_fab2(sch_1):m_f_ecc(7)"
				( attribute "CDS_PHYS_NET_NAME" "M_F_ECC<7>"
					( Origin gPackager )
				)
				( attribute "PNN" "M_F_ECC<7>"
					( Origin gPackager )
				)
				( objectStatus "M_F_ECC<7>" )
			)
			( signal "@baseboard_fab2_lib.baseboard_fab2(sch_1):m_f_ma(0)"
				( attribute "CDS_PHYS_NET_NAME" "M_F_MA<0>"
					( Origin gPackager )
				)
				( attribute "PNN" "M_F_MA<0>"
					( Origin gPackager )
				)
				( objectStatus "M_F_MA<0>" )
			)
			( signal "@baseboard_fab2_lib.baseboard_fab2(sch_1):m_f_ma(1)"
				( attribute "CDS_PHYS_NET_NAME" "M_F_MA<1>"
					( Origin gPackager )
				)
				( attribute "PNN" "M_F_MA<1>"
					( Origin gPackager )
				)
				( objectStatus "M_F_MA<1>" )
			)
			( signal "@baseboard_fab2_lib.baseboard_fab2(sch_1):m_f_ma(2)"
				( attribute "CDS_PHYS_NET_NAME" "M_F_MA<2>"
					( Origin gPackager )
				)
				( attribute "PNN" "M_F_MA<2>"
					( Origin gPackager )
				)
				( objectStatus "M_F_MA<2>" )
			)
			( signal "@baseboard_fab2_lib.baseboard_fab2(sch_1):m_f_ma(3)"
				( attribute "CDS_PHYS_NET_NAME" "M_F_MA<3>"
					( Origin gPackager )
				)
				( attribute "PNN" "M_F_MA<3>"
					( Origin gPackager )
				)
				( objectStatus "M_F_MA<3>" )
			)
			( signal "@baseboard_fab2_lib.baseboard_fab2(sch_1):m_f_ma(4)"
				( attribute "CDS_PHYS_NET_NAME" "M_F_MA<4>"
					( Origin gPackager )
				)
				( attribute "PNN" "M_F_MA<4>"
					( Origin gPackager )
				)
				( objectStatus "M_F_MA<4>" )
			)
			( signal "@baseboard_fab2_lib.baseboard_fab2(sch_1):m_f_ma(5)"
				( attribute "CDS_PHYS_NET_NAME" "M_F_MA<5>"
					( Origin gPackager )
				)
				( attribute "PNN" "M_F_MA<5>"
					( Origin gPackager )
				)
				( objectStatus "M_F_MA<5>" )
			)
			( signal "@baseboard_fab2_lib.baseboard_fab2(sch_1):m_f_ma(6)"
				( attribute "CDS_PHYS_NET_NAME" "M_F_MA<6>"
					( Origin gPackager )
				)
				( attribute "PNN" "M_F_MA<6>"
					( Origin gPackager )
				)
				( objectStatus "M_F_MA<6>" )
			)
			( signal "@baseboard_fab2_lib.baseboard_fab2(sch_1):m_f_ma(7)"
				( attribute "CDS_PHYS_NET_NAME" "M_F_MA<7>"
					( Origin gPackager )
				)
				( attribute "PNN" "M_F_MA<7>"
					( Origin gPackager )
				)
				( objectStatus "M_F_MA<7>" )
			)
			( signal "@baseboard_fab2_lib.baseboard_fab2(sch_1):m_f_ma(8)"
				( attribute "CDS_PHYS_NET_NAME" "M_F_MA<8>"
					( Origin gPackager )
				)
				( attribute "PNN" "M_F_MA<8>"
					( Origin gPackager )
				)
				( objectStatus "M_F_MA<8>" )
			)
			( signal "@baseboard_fab2_lib.baseboard_fab2(sch_1):m_f_ma(9)"
				( attribute "CDS_PHYS_NET_NAME" "M_F_MA<9>"
					( Origin gPackager )
				)
				( attribute "PNN" "M_F_MA<9>"
					( Origin gPackager )
				)
				( objectStatus "M_F_MA<9>" )
			)
			( signal "@baseboard_fab2_lib.baseboard_fab2(sch_1):m_f_ma(10)"
				( attribute "CDS_PHYS_NET_NAME" "M_F_MA<10>"
					( Origin gPackager )
				)
				( attribute "PNN" "M_F_MA<10>"
					( Origin gPackager )
				)
				( objectStatus "M_F_MA<10>" )
			)
			( signal "@baseboard_fab2_lib.baseboard_fab2(sch_1):m_f_ma(11)"
				( attribute "CDS_PHYS_NET_NAME" "M_F_MA<11>"
					( Origin gPackager )
				)
				( attribute "PNN" "M_F_MA<11>"
					( Origin gPackager )
				)
				( objectStatus "M_F_MA<11>" )
			)
			( signal "@baseboard_fab2_lib.baseboard_fab2(sch_1):m_f_ma(12)"
				( attribute "CDS_PHYS_NET_NAME" "M_F_MA<12>"
					( Origin gPackager )
				)
				( attribute "PNN" "M_F_MA<12>"
					( Origin gPackager )
				)
				( objectStatus "M_F_MA<12>" )
			)
			( signal "@baseboard_fab2_lib.baseboard_fab2(sch_1):m_f_ma(13)"
				( attribute "CDS_PHYS_NET_NAME" "M_F_MA<13>"
					( Origin gPackager )
				)
				( attribute "PNN" "M_F_MA<13>"
					( Origin gPackager )
				)
				( objectStatus "M_F_MA<13>" )
			)
			( signal "@baseboard_fab2_lib.baseboard_fab2(sch_1):m_f_ma(14)"
				( attribute "CDS_PHYS_NET_NAME" "M_F_MA<14>"
					( Origin gPackager )
				)
				( attribute "PNN" "M_F_MA<14>"
					( Origin gPackager )
				)
				( objectStatus "M_F_MA<14>" )
			)
			( signal "@baseboard_fab2_lib.baseboard_fab2(sch_1):m_f_ma(15)"
				( attribute "CDS_PHYS_NET_NAME" "M_F_MA<15>"
					( Origin gPackager )
				)
				( attribute "PNN" "M_F_MA<15>"
					( Origin gPackager )
				)
				( objectStatus "M_F_MA<15>" )
			)
			( signal "@baseboard_fab2_lib.baseboard_fab2(sch_1):m_f_ma(16)"
				( attribute "CDS_PHYS_NET_NAME" "M_F_MA<16>"
					( Origin gPackager )
				)
				( attribute "PNN" "M_F_MA<16>"
					( Origin gPackager )
				)
				( objectStatus "M_F_MA<16>" )
			)
			( signal "@baseboard_fab2_lib.baseboard_fab2(sch_1):m_f_ma(17)"
				( attribute "CDS_PHYS_NET_NAME" "M_F_MA<17>"
					( Origin gPackager )
				)
				( attribute "PNN" "M_F_MA<17>"
					( Origin gPackager )
				)
				( objectStatus "M_F_MA<17>" )
			)
			( signal "@baseboard_fab2_lib.baseboard_fab2(sch_1):m_f_odt(0)"
				( attribute "CDS_PHYS_NET_NAME" "M_F_ODT<0>"
					( Origin gPackager )
				)
				( attribute "PNN" "M_F_ODT<0>"
					( Origin gPackager )
				)
				( objectStatus "M_F_ODT<0>" )
			)
			( signal "@baseboard_fab2_lib.baseboard_fab2(sch_1):m_f_odt(1)"
				( attribute "CDS_PHYS_NET_NAME" "M_F_ODT<1>"
					( Origin gPackager )
				)
				( attribute "PNN" "M_F_ODT<1>"
					( Origin gPackager )
				)
				( objectStatus "M_F_ODT<1>" )
			)
			( signal "@baseboard_fab2_lib.baseboard_fab2(sch_1):m_f_odt(2)"
				( attribute "CDS_PHYS_NET_NAME" "M_F_ODT<2>"
					( Origin gPackager )
				)
				( attribute "PNN" "M_F_ODT<2>"
					( Origin gPackager )
				)
				( objectStatus "M_F_ODT<2>" )
			)
			( signal "@baseboard_fab2_lib.baseboard_fab2(sch_1):m_f_odt(3)"
				( attribute "CDS_PHYS_NET_NAME" "M_F_ODT<3>"
					( Origin gPackager )
				)
				( attribute "PNN" "M_F_ODT<3>"
					( Origin gPackager )
				)
				( objectStatus "M_F_ODT<3>" )
			)
			( signal "@baseboard_fab2_lib.baseboard_fab2(sch_1):m_f_par"
				( attribute "CDS_PHYS_NET_NAME" "M_F_PAR"
					( Origin gPackager )
				)
				( objectStatus "M_F_PAR" )
			)
			( signal "@baseboard_fab2_lib.baseboard_fab2(sch_1):clk_100m_cpu0_pe_refclk_dn"
				( attribute "CDS_PHYS_NET_NAME" "CLK_100M_CPU0_PE_REFCLK_DN"
					( Origin gPackager )
				)
				( objectStatus "CLK_100M_CPU0_PE_REFCLK_DN" )
			)
			( signal "@baseboard_fab2_lib.baseboard_fab2(sch_1):clk_100m_cpu0_pe_refclk_dp"
				( attribute "CDS_PHYS_NET_NAME" "CLK_100M_CPU0_PE_REFCLK_DP"
					( Origin gPackager )
				)
				( objectStatus "CLK_100M_CPU0_PE_REFCLK_DP" )
			)
			( signal "@baseboard_fab2_lib.baseboard_fab2(sch_1):clk_156m_osc_cpu0_hfi_dn"
				( attribute "CDS_PHYS_NET_NAME" "CLK_156M_OSC_CPU0_HFI_DN"
					( Origin gPackager )
				)
				( objectStatus "CLK_156M_OSC_CPU0_HFI_DN" )
			)
			( signal "@baseboard_fab2_lib.baseboard_fab2(sch_1):clk_156m_osc_cpu0_hfi_dp"
				( attribute "CDS_PHYS_NET_NAME" "CLK_156M_OSC_CPU0_HFI_DP"
					( Origin gPackager )
				)
				( objectStatus "CLK_156M_OSC_CPU0_HFI_DP" )
			)
			( signal "@baseboard_fab2_lib.baseboard_fab2(sch_1):dmi_cpu0_pch_rx_c_dn(0)"
				( attribute "CDS_PHYS_NET_NAME" "DMI_CPU0_PCH_RX_C_DN<0>"
					( Origin gPackager )
				)
				( attribute "PNN" "DMI_CPU0_PCH_RX_C_DN<0>"
					( Origin gPackager )
				)
				( objectStatus "DMI_CPU0_PCH_RX_C_DN<0>" )
			)
			( signal "@baseboard_fab2_lib.baseboard_fab2(sch_1):dmi_cpu0_pch_rx_c_dn(1)"
				( attribute "CDS_PHYS_NET_NAME" "DMI_CPU0_PCH_RX_C_DN<1>"
					( Origin gPackager )
				)
				( attribute "PNN" "DMI_CPU0_PCH_RX_C_DN<1>"
					( Origin gPackager )
				)
				( objectStatus "DMI_CPU0_PCH_RX_C_DN<1>" )
			)
			( signal "@baseboard_fab2_lib.baseboard_fab2(sch_1):dmi_cpu0_pch_rx_c_dn(2)"
				( attribute "CDS_PHYS_NET_NAME" "DMI_CPU0_PCH_RX_C_DN<2>"
					( Origin gPackager )
				)
				( attribute "PNN" "DMI_CPU0_PCH_RX_C_DN<2>"
					( Origin gPackager )
				)
				( objectStatus "DMI_CPU0_PCH_RX_C_DN<2>" )
			)
			( signal "@baseboard_fab2_lib.baseboard_fab2(sch_1):dmi_cpu0_pch_rx_c_dn(3)"
				( attribute "CDS_PHYS_NET_NAME" "DMI_CPU0_PCH_RX_C_DN<3>"
					( Origin gPackager )
				)
				( attribute "PNN" "DMI_CPU0_PCH_RX_C_DN<3>"
					( Origin gPackager )
				)
				( objectStatus "DMI_CPU0_PCH_RX_C_DN<3>" )
			)
			( signal "@baseboard_fab2_lib.baseboard_fab2(sch_1):dmi_cpu0_pch_rx_c_dp(0)"
				( attribute "CDS_PHYS_NET_NAME" "DMI_CPU0_PCH_RX_C_DP<0>"
					( Origin gPackager )
				)
				( attribute "PNN" "DMI_CPU0_PCH_RX_C_DP<0>"
					( Origin gPackager )
				)
				( objectStatus "DMI_CPU0_PCH_RX_C_DP<0>" )
			)
			( signal "@baseboard_fab2_lib.baseboard_fab2(sch_1):dmi_cpu0_pch_rx_c_dp(1)"
				( attribute "CDS_PHYS_NET_NAME" "DMI_CPU0_PCH_RX_C_DP<1>"
					( Origin gPackager )
				)
				( attribute "PNN" "DMI_CPU0_PCH_RX_C_DP<1>"
					( Origin gPackager )
				)
				( objectStatus "DMI_CPU0_PCH_RX_C_DP<1>" )
			)
			( signal "@baseboard_fab2_lib.baseboard_fab2(sch_1):dmi_cpu0_pch_rx_c_dp(2)"
				( attribute "CDS_PHYS_NET_NAME" "DMI_CPU0_PCH_RX_C_DP<2>"
					( Origin gPackager )
				)
				( attribute "PNN" "DMI_CPU0_PCH_RX_C_DP<2>"
					( Origin gPackager )
				)
				( objectStatus "DMI_CPU0_PCH_RX_C_DP<2>" )
			)
			( signal "@baseboard_fab2_lib.baseboard_fab2(sch_1):dmi_cpu0_pch_rx_c_dp(3)"
				( attribute "CDS_PHYS_NET_NAME" "DMI_CPU0_PCH_RX_C_DP<3>"
					( Origin gPackager )
				)
				( attribute "PNN" "DMI_CPU0_PCH_RX_C_DP<3>"
					( Origin gPackager )
				)
				( objectStatus "DMI_CPU0_PCH_RX_C_DP<3>" )
			)
			( signal "@baseboard_fab2_lib.baseboard_fab2(sch_1):dmi_cpu0_pch_tx_dn(0)"
				( attribute "CDS_PHYS_NET_NAME" "DMI_CPU0_PCH_TX_DN<0>"
					( Origin gPackager )
				)
				( attribute "PNN" "DMI_CPU0_PCH_TX_DN<0>"
					( Origin gPackager )
				)
				( objectStatus "DMI_CPU0_PCH_TX_DN<0>" )
			)
			( signal "@baseboard_fab2_lib.baseboard_fab2(sch_1):dmi_cpu0_pch_tx_dn(1)"
				( attribute "CDS_PHYS_NET_NAME" "DMI_CPU0_PCH_TX_DN<1>"
					( Origin gPackager )
				)
				( attribute "PNN" "DMI_CPU0_PCH_TX_DN<1>"
					( Origin gPackager )
				)
				( objectStatus "DMI_CPU0_PCH_TX_DN<1>" )
			)
			( signal "@baseboard_fab2_lib.baseboard_fab2(sch_1):dmi_cpu0_pch_tx_dn(2)"
				( attribute "CDS_PHYS_NET_NAME" "DMI_CPU0_PCH_TX_DN<2>"
					( Origin gPackager )
				)
				( attribute "PNN" "DMI_CPU0_PCH_TX_DN<2>"
					( Origin gPackager )
				)
				( objectStatus "DMI_CPU0_PCH_TX_DN<2>" )
			)
			( signal "@baseboard_fab2_lib.baseboard_fab2(sch_1):dmi_cpu0_pch_tx_dn(3)"
				( attribute "CDS_PHYS_NET_NAME" "DMI_CPU0_PCH_TX_DN<3>"
					( Origin gPackager )
				)
				( attribute "PNN" "DMI_CPU0_PCH_TX_DN<3>"
					( Origin gPackager )
				)
				( objectStatus "DMI_CPU0_PCH_TX_DN<3>" )
			)
			( signal "@baseboard_fab2_lib.baseboard_fab2(sch_1):dmi_cpu0_pch_tx_dp(0)"
				( attribute "CDS_PHYS_NET_NAME" "DMI_CPU0_PCH_TX_DP<0>"
					( Origin gPackager )
				)
				( attribute "PNN" "DMI_CPU0_PCH_TX_DP<0>"
					( Origin gPackager )
				)
				( objectStatus "DMI_CPU0_PCH_TX_DP<0>" )
			)
			( signal "@baseboard_fab2_lib.baseboard_fab2(sch_1):dmi_cpu0_pch_tx_dp(1)"
				( attribute "CDS_PHYS_NET_NAME" "DMI_CPU0_PCH_TX_DP<1>"
					( Origin gPackager )
				)
				( attribute "PNN" "DMI_CPU0_PCH_TX_DP<1>"
					( Origin gPackager )
				)
				( objectStatus "DMI_CPU0_PCH_TX_DP<1>" )
			)
			( signal "@baseboard_fab2_lib.baseboard_fab2(sch_1):dmi_cpu0_pch_tx_dp(2)"
				( attribute "CDS_PHYS_NET_NAME" "DMI_CPU0_PCH_TX_DP<2>"
					( Origin gPackager )
				)
				( attribute "PNN" "DMI_CPU0_PCH_TX_DP<2>"
					( Origin gPackager )
				)
				( objectStatus "DMI_CPU0_PCH_TX_DP<2>" )
			)
			( signal "@baseboard_fab2_lib.baseboard_fab2(sch_1):dmi_cpu0_pch_tx_dp(3)"
				( attribute "CDS_PHYS_NET_NAME" "DMI_CPU0_PCH_TX_DP<3>"
					( Origin gPackager )
				)
				( attribute "PNN" "DMI_CPU0_PCH_TX_DP<3>"
					( Origin gPackager )
				)
				( objectStatus "DMI_CPU0_PCH_TX_DP<3>" )
			)
			( signal "@baseboard_fab2_lib.baseboard_fab2(sch_1):fm_modprst_hfi0_cpu0_lvt2_n"
				( attribute "CDS_PHYS_NET_NAME" "FM_MODPRST_HFI0_CPU0_LVT2_N"
					( Origin gPackager )
				)
				( objectStatus "FM_MODPRST_HFI0_CPU0_LVT2_N" )
			)
			( signal "@baseboard_fab2_lib.baseboard_fab2(sch_1):fm_modprst_hfi1_cpu0_lvt2_n"
				( attribute "CDS_PHYS_NET_NAME" "FM_MODPRST_HFI1_CPU0_LVT2_N"
					( Origin gPackager )
				)
				( objectStatus "FM_MODPRST_HFI1_CPU0_LVT2_N" )
			)
			( signal "@baseboard_fab2_lib.baseboard_fab2(sch_1):irq_hfi0_cpu0_lvt2_n"
				( attribute "CDS_PHYS_NET_NAME" "IRQ_HFI0_CPU0_LVT2_N"
					( Origin gPackager )
				)
				( objectStatus "IRQ_HFI0_CPU0_LVT2_N" )
			)
			( signal "@baseboard_fab2_lib.baseboard_fab2(sch_1):irq_hfi1_cpu0_lvt2_n"
				( attribute "CDS_PHYS_NET_NAME" "IRQ_HFI1_CPU0_LVT2_N"
					( Origin gPackager )
				)
				( objectStatus "IRQ_HFI1_CPU0_LVT2_N" )
			)
			( signal "@baseboard_fab2_lib.baseboard_fab2(sch_1):jtag_mcp_cpu0_tdi"
				( attribute "CDS_PHYS_NET_NAME" "JTAG_MCP_CPU0_TDI"
					( Origin gPackager )
				)
				( objectStatus "JTAG_MCP_CPU0_TDI" )
			)
			( signal "@baseboard_fab2_lib.baseboard_fab2(sch_1):jtag_mcp_cpu0_tdo"
				( attribute "CDS_PHYS_NET_NAME" "JTAG_MCP_CPU0_TDO"
					( Origin gPackager )
				)
				( objectStatus "JTAG_MCP_CPU0_TDO" )
			)
			( signal "@baseboard_fab2_lib.baseboard_fab2(sch_1):jtag_mcp_tck"
				( attribute "CDS_PHYS_NET_NAME" "JTAG_MCP_TCK"
					( Origin gPackager )
				)
				( objectStatus "JTAG_MCP_TCK" )
			)
			( signal "@baseboard_fab2_lib.baseboard_fab2(sch_1):jtag_mcp_tms"
				( attribute "CDS_PHYS_NET_NAME" "JTAG_MCP_TMS"
					( Origin gPackager )
				)
				( objectStatus "JTAG_MCP_TMS" )
			)
			( signal "@baseboard_fab2_lib.baseboard_fab2(sch_1):jtag_mcp_trst_n"
				( attribute "CDS_PHYS_NET_NAME" "JTAG_MCP_TRST_N"
					( Origin gPackager )
				)
				( objectStatus "JTAG_MCP_TRST_N" )
			)
			( signal "@baseboard_fab2_lib.baseboard_fab2(sch_1):led_hfi0_cpu0_n"
				( attribute "CDS_PHYS_NET_NAME" "LED_HFI0_CPU0_N"
					( Origin gPackager )
				)
				( objectStatus "LED_HFI0_CPU0_N" )
			)
			( signal "@baseboard_fab2_lib.baseboard_fab2(sch_1):led_hfi1_cpu0_n"
				( attribute "CDS_PHYS_NET_NAME" "LED_HFI1_CPU0_N"
					( Origin gPackager )
				)
				( objectStatus "LED_HFI1_CPU0_N" )
			)
			( signal "@baseboard_fab2_lib.baseboard_fab2(sch_1):rst_cd_cpu0_por_n"
				( attribute "CDS_PHYS_NET_NAME" "RST_CD_CPU0_POR_N"
					( Origin gPackager )
				)
				( objectStatus "RST_CD_CPU0_POR_N" )
			)
			( signal "@baseboard_fab2_lib.baseboard_fab2(sch_1):rst_hfi0_cpu0_lvt2_n"
				( attribute "CDS_PHYS_NET_NAME" "RST_HFI0_CPU0_LVT2_N"
					( Origin gPackager )
				)
				( objectStatus "RST_HFI0_CPU0_LVT2_N" )
			)
			( signal "@baseboard_fab2_lib.baseboard_fab2(sch_1):rst_hfi1_cpu0_lvt2_n"
				( attribute "CDS_PHYS_NET_NAME" "RST_HFI1_CPU0_LVT2_N"
					( Origin gPackager )
				)
				( objectStatus "RST_HFI1_CPU0_LVT2_N" )
			)
			( signal "@baseboard_fab2_lib.baseboard_fab2(sch_1):smb_hfi0_cpu0_lvc2_scl"
				( attribute "CDS_PHYS_NET_NAME" "SMB_HFI0_CPU0_LVC2_SCL"
					( Origin gPackager )
				)
				( objectStatus "SMB_HFI0_CPU0_LVC2_SCL" )
			)
			( signal "@baseboard_fab2_lib.baseboard_fab2(sch_1):smb_hfi0_cpu0_lvc2_sda"
				( attribute "CDS_PHYS_NET_NAME" "SMB_HFI0_CPU0_LVC2_SDA"
					( Origin gPackager )
				)
				( objectStatus "SMB_HFI0_CPU0_LVC2_SDA" )
			)
			( signal "@baseboard_fab2_lib.baseboard_fab2(sch_1):smb_hfi1_cpu0_lvc2_scl"
				( attribute "CDS_PHYS_NET_NAME" "SMB_HFI1_CPU0_LVC2_SCL"
					( Origin gPackager )
				)
				( objectStatus "SMB_HFI1_CPU0_LVC2_SCL" )
			)
			( signal "@baseboard_fab2_lib.baseboard_fab2(sch_1):smb_hfi1_cpu0_lvc2_sda"
				( attribute "CDS_PHYS_NET_NAME" "SMB_HFI1_CPU0_LVC2_SDA"
					( Origin gPackager )
				)
				( objectStatus "SMB_HFI1_CPU0_LVC2_SDA" )
			)
			( signal "@baseboard_fab2_lib.baseboard_fab2(sch_1):tp_cpu0_rsvd_172"
				( attribute "CDS_PHYS_NET_NAME" "TP_CPU0_RSVD_172"
					( Origin gPackager )
				)
				( objectStatus "TP_CPU0_RSVD_172" )
			)
			( signal "@baseboard_fab2_lib.baseboard_fab2(sch_1):tp_cpu0_rsvd_173"
				( attribute "CDS_PHYS_NET_NAME" "TP_CPU0_RSVD_173"
					( Origin gPackager )
				)
				( objectStatus "TP_CPU0_RSVD_173" )
			)
			( signal "@baseboard_fab2_lib.baseboard_fab2(sch_1):tp_cpu0_rsvd_174"
				( attribute "CDS_PHYS_NET_NAME" "TP_CPU0_RSVD_174"
					( Origin gPackager )
				)
				( objectStatus "TP_CPU0_RSVD_174" )
			)
			( signal "@baseboard_fab2_lib.baseboard_fab2(sch_1):tp_cpu0_rsvd_175"
				( attribute "CDS_PHYS_NET_NAME" "TP_CPU0_RSVD_175"
					( Origin gPackager )
				)
				( objectStatus "TP_CPU0_RSVD_175" )
			)
			( signal "@baseboard_fab2_lib.baseboard_fab2(sch_1):tp_cpu0_rsvd_176"
				( attribute "CDS_PHYS_NET_NAME" "TP_CPU0_RSVD_176"
					( Origin gPackager )
				)
				( objectStatus "TP_CPU0_RSVD_176" )
			)
			( signal "@baseboard_fab2_lib.baseboard_fab2(sch_1):tp_cpu0_rsvd_177"
				( attribute "CDS_PHYS_NET_NAME" "TP_CPU0_RSVD_177"
					( Origin gPackager )
				)
				( objectStatus "TP_CPU0_RSVD_177" )
			)
			( signal "@baseboard_fab2_lib.baseboard_fab2(sch_1):tp_cpu0_rsvd_178"
				( attribute "CDS_PHYS_NET_NAME" "TP_CPU0_RSVD_178"
					( Origin gPackager )
				)
				( objectStatus "TP_CPU0_RSVD_178" )
			)
			( signal "@baseboard_fab2_lib.baseboard_fab2(sch_1):tp_cpu0_rsvd_179"
				( attribute "CDS_PHYS_NET_NAME" "TP_CPU0_RSVD_179"
					( Origin gPackager )
				)
				( objectStatus "TP_CPU0_RSVD_179" )
			)
			( signal "@baseboard_fab2_lib.baseboard_fab2(sch_1):tp_cpu0_rsvd_180"
				( attribute "CDS_PHYS_NET_NAME" "TP_CPU0_RSVD_180"
					( Origin gPackager )
				)
				( objectStatus "TP_CPU0_RSVD_180" )
			)
			( signal "@baseboard_fab2_lib.baseboard_fab2(sch_1):tp_cpu0_rsvd_181"
				( attribute "CDS_PHYS_NET_NAME" "TP_CPU0_RSVD_181"
					( Origin gPackager )
				)
				( objectStatus "TP_CPU0_RSVD_181" )
			)
			( signal "@baseboard_fab2_lib.baseboard_fab2(sch_1):tp_cpu0_rsvd_182"
				( attribute "CDS_PHYS_NET_NAME" "TP_CPU0_RSVD_182"
					( Origin gPackager )
				)
				( objectStatus "TP_CPU0_RSVD_182" )
			)
			( signal "@baseboard_fab2_lib.baseboard_fab2(sch_1):tp_cpu0_rsvd_183"
				( attribute "CDS_PHYS_NET_NAME" "TP_CPU0_RSVD_183"
					( Origin gPackager )
				)
				( objectStatus "TP_CPU0_RSVD_183" )
			)
			( signal "@baseboard_fab2_lib.baseboard_fab2(sch_1):tp_cpu0_rsvd_184"
				( attribute "CDS_PHYS_NET_NAME" "TP_CPU0_RSVD_184"
					( Origin gPackager )
				)
				( objectStatus "TP_CPU0_RSVD_184" )
			)
			( signal "@baseboard_fab2_lib.baseboard_fab2(sch_1):tp_cpu0_rsvd_186"
				( attribute "CDS_PHYS_NET_NAME" "TP_CPU0_RSVD_186"
					( Origin gPackager )
				)
				( objectStatus "TP_CPU0_RSVD_186" )
			)
			( signal "@baseboard_fab2_lib.baseboard_fab2(sch_1):tp_cpu0_rsvd_189"
				( attribute "CDS_PHYS_NET_NAME" "TP_CPU0_RSVD_189"
					( Origin gPackager )
				)
				( objectStatus "TP_CPU0_RSVD_189" )
			)
			( signal "@baseboard_fab2_lib.baseboard_fab2(sch_1):tp_cpu0_rsvd_190"
				( attribute "CDS_PHYS_NET_NAME" "TP_CPU0_RSVD_190"
					( Origin gPackager )
				)
				( objectStatus "TP_CPU0_RSVD_190" )
			)
			( signal "@baseboard_fab2_lib.baseboard_fab2(sch_1):p3e_cpu0_pe1_pch_rxn(8)"
				( attribute "CDS_PHYS_NET_NAME" "P3E_CPU0_PE1_PCH_RXN<8>"
					( Origin gPackager )
				)
				( attribute "PNN" "P3E_CPU0_PE1_PCH_RXN<8>"
					( Origin gPackager )
				)
				( objectStatus "P3E_CPU0_PE1_PCH_RXN<8>" )
			)
			( signal "@baseboard_fab2_lib.baseboard_fab2(sch_1):p3e_cpu0_pe1_pch_rxn(9)"
				( attribute "CDS_PHYS_NET_NAME" "P3E_CPU0_PE1_PCH_RXN<9>"
					( Origin gPackager )
				)
				( attribute "PNN" "P3E_CPU0_PE1_PCH_RXN<9>"
					( Origin gPackager )
				)
				( objectStatus "P3E_CPU0_PE1_PCH_RXN<9>" )
			)
			( signal "@baseboard_fab2_lib.baseboard_fab2(sch_1):p3e_cpu0_pe1_pch_rxn(10)"
				( attribute "CDS_PHYS_NET_NAME" "P3E_CPU0_PE1_PCH_RXN<10>"
					( Origin gPackager )
				)
				( attribute "PNN" "P3E_CPU0_PE1_PCH_RXN<10>"
					( Origin gPackager )
				)
				( objectStatus "P3E_CPU0_PE1_PCH_RXN<10>" )
			)
			( signal "@baseboard_fab2_lib.baseboard_fab2(sch_1):p3e_cpu0_pe1_pch_rxn(11)"
				( attribute "CDS_PHYS_NET_NAME" "P3E_CPU0_PE1_PCH_RXN<11>"
					( Origin gPackager )
				)
				( attribute "PNN" "P3E_CPU0_PE1_PCH_RXN<11>"
					( Origin gPackager )
				)
				( objectStatus "P3E_CPU0_PE1_PCH_RXN<11>" )
			)
			( signal "@baseboard_fab2_lib.baseboard_fab2(sch_1):p3e_cpu0_pe1_pch_rxn(12)"
				( attribute "CDS_PHYS_NET_NAME" "P3E_CPU0_PE1_PCH_RXN<12>"
					( Origin gPackager )
				)
				( attribute "PNN" "P3E_CPU0_PE1_PCH_RXN<12>"
					( Origin gPackager )
				)
				( objectStatus "P3E_CPU0_PE1_PCH_RXN<12>" )
			)
			( signal "@baseboard_fab2_lib.baseboard_fab2(sch_1):p3e_cpu0_pe1_pch_rxn(13)"
				( attribute "CDS_PHYS_NET_NAME" "P3E_CPU0_PE1_PCH_RXN<13>"
					( Origin gPackager )
				)
				( attribute "PNN" "P3E_CPU0_PE1_PCH_RXN<13>"
					( Origin gPackager )
				)
				( objectStatus "P3E_CPU0_PE1_PCH_RXN<13>" )
			)
			( signal "@baseboard_fab2_lib.baseboard_fab2(sch_1):p3e_cpu0_pe1_pch_rxn(14)"
				( attribute "CDS_PHYS_NET_NAME" "P3E_CPU0_PE1_PCH_RXN<14>"
					( Origin gPackager )
				)
				( attribute "PNN" "P3E_CPU0_PE1_PCH_RXN<14>"
					( Origin gPackager )
				)
				( objectStatus "P3E_CPU0_PE1_PCH_RXN<14>" )
			)
			( signal "@baseboard_fab2_lib.baseboard_fab2(sch_1):p3e_cpu0_pe1_pch_rxn(15)"
				( attribute "CDS_PHYS_NET_NAME" "P3E_CPU0_PE1_PCH_RXN<15>"
					( Origin gPackager )
				)
				( attribute "PNN" "P3E_CPU0_PE1_PCH_RXN<15>"
					( Origin gPackager )
				)
				( objectStatus "P3E_CPU0_PE1_PCH_RXN<15>" )
			)
			( signal "@baseboard_fab2_lib.baseboard_fab2(sch_1):p3e_cpu0_pe1_pch_rxp(8)"
				( attribute "CDS_PHYS_NET_NAME" "P3E_CPU0_PE1_PCH_RXP<8>"
					( Origin gPackager )
				)
				( attribute "PNN" "P3E_CPU0_PE1_PCH_RXP<8>"
					( Origin gPackager )
				)
				( objectStatus "P3E_CPU0_PE1_PCH_RXP<8>" )
			)
			( signal "@baseboard_fab2_lib.baseboard_fab2(sch_1):p3e_cpu0_pe1_pch_rxp(9)"
				( attribute "CDS_PHYS_NET_NAME" "P3E_CPU0_PE1_PCH_RXP<9>"
					( Origin gPackager )
				)
				( attribute "PNN" "P3E_CPU0_PE1_PCH_RXP<9>"
					( Origin gPackager )
				)
				( objectStatus "P3E_CPU0_PE1_PCH_RXP<9>" )
			)
			( signal "@baseboard_fab2_lib.baseboard_fab2(sch_1):p3e_cpu0_pe1_pch_rxp(10)"
				( attribute "CDS_PHYS_NET_NAME" "P3E_CPU0_PE1_PCH_RXP<10>"
					( Origin gPackager )
				)
				( attribute "PNN" "P3E_CPU0_PE1_PCH_RXP<10>"
					( Origin gPackager )
				)
				( objectStatus "P3E_CPU0_PE1_PCH_RXP<10>" )
			)
			( signal "@baseboard_fab2_lib.baseboard_fab2(sch_1):p3e_cpu0_pe1_pch_rxp(11)"
				( attribute "CDS_PHYS_NET_NAME" "P3E_CPU0_PE1_PCH_RXP<11>"
					( Origin gPackager )
				)
				( attribute "PNN" "P3E_CPU0_PE1_PCH_RXP<11>"
					( Origin gPackager )
				)
				( objectStatus "P3E_CPU0_PE1_PCH_RXP<11>" )
			)
			( signal "@baseboard_fab2_lib.baseboard_fab2(sch_1):p3e_cpu0_pe1_pch_rxp(12)"
				( attribute "CDS_PHYS_NET_NAME" "P3E_CPU0_PE1_PCH_RXP<12>"
					( Origin gPackager )
				)
				( attribute "PNN" "P3E_CPU0_PE1_PCH_RXP<12>"
					( Origin gPackager )
				)
				( objectStatus "P3E_CPU0_PE1_PCH_RXP<12>" )
			)
			( signal "@baseboard_fab2_lib.baseboard_fab2(sch_1):p3e_cpu0_pe1_pch_rxp(13)"
				( attribute "CDS_PHYS_NET_NAME" "P3E_CPU0_PE1_PCH_RXP<13>"
					( Origin gPackager )
				)
				( attribute "PNN" "P3E_CPU0_PE1_PCH_RXP<13>"
					( Origin gPackager )
				)
				( objectStatus "P3E_CPU0_PE1_PCH_RXP<13>" )
			)
			( signal "@baseboard_fab2_lib.baseboard_fab2(sch_1):p3e_cpu0_pe1_pch_rxp(14)"
				( attribute "CDS_PHYS_NET_NAME" "P3E_CPU0_PE1_PCH_RXP<14>"
					( Origin gPackager )
				)
				( attribute "PNN" "P3E_CPU0_PE1_PCH_RXP<14>"
					( Origin gPackager )
				)
				( objectStatus "P3E_CPU0_PE1_PCH_RXP<14>" )
			)
			( signal "@baseboard_fab2_lib.baseboard_fab2(sch_1):p3e_cpu0_pe1_pch_rxp(15)"
				( attribute "CDS_PHYS_NET_NAME" "P3E_CPU0_PE1_PCH_RXP<15>"
					( Origin gPackager )
				)
				( attribute "PNN" "P3E_CPU0_PE1_PCH_RXP<15>"
					( Origin gPackager )
				)
				( objectStatus "P3E_CPU0_PE1_PCH_RXP<15>" )
			)
			( signal "@baseboard_fab2_lib.baseboard_fab2(sch_1):p3e_cpu0_pe1_pch_txn(8)"
				( attribute "CDS_PHYS_NET_NAME" "P3E_CPU0_PE1_PCH_TXN<8>"
					( Origin gPackager )
				)
				( attribute "PNN" "P3E_CPU0_PE1_PCH_TXN<8>"
					( Origin gPackager )
				)
				( objectStatus "P3E_CPU0_PE1_PCH_TXN<8>" )
			)
			( signal "@baseboard_fab2_lib.baseboard_fab2(sch_1):p3e_cpu0_pe1_pch_txn(9)"
				( attribute "CDS_PHYS_NET_NAME" "P3E_CPU0_PE1_PCH_TXN<9>"
					( Origin gPackager )
				)
				( attribute "PNN" "P3E_CPU0_PE1_PCH_TXN<9>"
					( Origin gPackager )
				)
				( objectStatus "P3E_CPU0_PE1_PCH_TXN<9>" )
			)
			( signal "@baseboard_fab2_lib.baseboard_fab2(sch_1):p3e_cpu0_pe1_pch_txn(10)"
				( attribute "CDS_PHYS_NET_NAME" "P3E_CPU0_PE1_PCH_TXN<10>"
					( Origin gPackager )
				)
				( attribute "PNN" "P3E_CPU0_PE1_PCH_TXN<10>"
					( Origin gPackager )
				)
				( objectStatus "P3E_CPU0_PE1_PCH_TXN<10>" )
			)
			( signal "@baseboard_fab2_lib.baseboard_fab2(sch_1):p3e_cpu0_pe1_pch_txn(11)"
				( attribute "CDS_PHYS_NET_NAME" "P3E_CPU0_PE1_PCH_TXN<11>"
					( Origin gPackager )
				)
				( attribute "PNN" "P3E_CPU0_PE1_PCH_TXN<11>"
					( Origin gPackager )
				)
				( objectStatus "P3E_CPU0_PE1_PCH_TXN<11>" )
			)
			( signal "@baseboard_fab2_lib.baseboard_fab2(sch_1):p3e_cpu0_pe1_pch_txn(12)"
				( attribute "CDS_PHYS_NET_NAME" "P3E_CPU0_PE1_PCH_TXN<12>"
					( Origin gPackager )
				)
				( attribute "PNN" "P3E_CPU0_PE1_PCH_TXN<12>"
					( Origin gPackager )
				)
				( objectStatus "P3E_CPU0_PE1_PCH_TXN<12>" )
			)
			( signal "@baseboard_fab2_lib.baseboard_fab2(sch_1):p3e_cpu0_pe1_pch_txn(13)"
				( attribute "CDS_PHYS_NET_NAME" "P3E_CPU0_PE1_PCH_TXN<13>"
					( Origin gPackager )
				)
				( attribute "PNN" "P3E_CPU0_PE1_PCH_TXN<13>"
					( Origin gPackager )
				)
				( objectStatus "P3E_CPU0_PE1_PCH_TXN<13>" )
			)
			( signal "@baseboard_fab2_lib.baseboard_fab2(sch_1):p3e_cpu0_pe1_pch_txn(14)"
				( attribute "CDS_PHYS_NET_NAME" "P3E_CPU0_PE1_PCH_TXN<14>"
					( Origin gPackager )
				)
				( attribute "PNN" "P3E_CPU0_PE1_PCH_TXN<14>"
					( Origin gPackager )
				)
				( objectStatus "P3E_CPU0_PE1_PCH_TXN<14>" )
			)
			( signal "@baseboard_fab2_lib.baseboard_fab2(sch_1):p3e_cpu0_pe1_pch_txn(15)"
				( attribute "CDS_PHYS_NET_NAME" "P3E_CPU0_PE1_PCH_TXN<15>"
					( Origin gPackager )
				)
				( attribute "PNN" "P3E_CPU0_PE1_PCH_TXN<15>"
					( Origin gPackager )
				)
				( objectStatus "P3E_CPU0_PE1_PCH_TXN<15>" )
			)
			( signal "@baseboard_fab2_lib.baseboard_fab2(sch_1):p3e_cpu0_pe1_pch_txp(8)"
				( attribute "CDS_PHYS_NET_NAME" "P3E_CPU0_PE1_PCH_TXP<8>"
					( Origin gPackager )
				)
				( attribute "PNN" "P3E_CPU0_PE1_PCH_TXP<8>"
					( Origin gPackager )
				)
				( objectStatus "P3E_CPU0_PE1_PCH_TXP<8>" )
			)
			( signal "@baseboard_fab2_lib.baseboard_fab2(sch_1):p3e_cpu0_pe1_pch_txp(9)"
				( attribute "CDS_PHYS_NET_NAME" "P3E_CPU0_PE1_PCH_TXP<9>"
					( Origin gPackager )
				)
				( attribute "PNN" "P3E_CPU0_PE1_PCH_TXP<9>"
					( Origin gPackager )
				)
				( objectStatus "P3E_CPU0_PE1_PCH_TXP<9>" )
			)
			( signal "@baseboard_fab2_lib.baseboard_fab2(sch_1):p3e_cpu0_pe1_pch_txp(10)"
				( attribute "CDS_PHYS_NET_NAME" "P3E_CPU0_PE1_PCH_TXP<10>"
					( Origin gPackager )
				)
				( attribute "PNN" "P3E_CPU0_PE1_PCH_TXP<10>"
					( Origin gPackager )
				)
				( objectStatus "P3E_CPU0_PE1_PCH_TXP<10>" )
			)
			( signal "@baseboard_fab2_lib.baseboard_fab2(sch_1):p3e_cpu0_pe1_pch_txp(11)"
				( attribute "CDS_PHYS_NET_NAME" "P3E_CPU0_PE1_PCH_TXP<11>"
					( Origin gPackager )
				)
				( attribute "PNN" "P3E_CPU0_PE1_PCH_TXP<11>"
					( Origin gPackager )
				)
				( objectStatus "P3E_CPU0_PE1_PCH_TXP<11>" )
			)
			( signal "@baseboard_fab2_lib.baseboard_fab2(sch_1):p3e_cpu0_pe1_pch_txp(12)"
				( attribute "CDS_PHYS_NET_NAME" "P3E_CPU0_PE1_PCH_TXP<12>"
					( Origin gPackager )
				)
				( attribute "PNN" "P3E_CPU0_PE1_PCH_TXP<12>"
					( Origin gPackager )
				)
				( objectStatus "P3E_CPU0_PE1_PCH_TXP<12>" )
			)
			( signal "@baseboard_fab2_lib.baseboard_fab2(sch_1):p3e_cpu0_pe1_pch_txp(13)"
				( attribute "CDS_PHYS_NET_NAME" "P3E_CPU0_PE1_PCH_TXP<13>"
					( Origin gPackager )
				)
				( attribute "PNN" "P3E_CPU0_PE1_PCH_TXP<13>"
					( Origin gPackager )
				)
				( objectStatus "P3E_CPU0_PE1_PCH_TXP<13>" )
			)
			( signal "@baseboard_fab2_lib.baseboard_fab2(sch_1):p3e_cpu0_pe1_pch_txp(14)"
				( attribute "CDS_PHYS_NET_NAME" "P3E_CPU0_PE1_PCH_TXP<14>"
					( Origin gPackager )
				)
				( attribute "PNN" "P3E_CPU0_PE1_PCH_TXP<14>"
					( Origin gPackager )
				)
				( objectStatus "P3E_CPU0_PE1_PCH_TXP<14>" )
			)
			( signal "@baseboard_fab2_lib.baseboard_fab2(sch_1):p3e_cpu0_pe1_pch_txp(15)"
				( attribute "CDS_PHYS_NET_NAME" "P3E_CPU0_PE1_PCH_TXP<15>"
					( Origin gPackager )
				)
				( attribute "PNN" "P3E_CPU0_PE1_PCH_TXP<15>"
					( Origin gPackager )
				)
				( objectStatus "P3E_CPU0_PE1_PCH_TXP<15>" )
			)
			( signal "@baseboard_fab2_lib.baseboard_fab2(sch_1):p3e_cpu0_pe1_ss_rxn(0)"
				( attribute "CDS_PHYS_NET_NAME" "P3E_CPU0_PE1_SS_RXN<0>"
					( Origin gPackager )
				)
				( attribute "PNN" "P3E_CPU0_PE1_SS_RXN<0>"
					( Origin gPackager )
				)
				( objectStatus "P3E_CPU0_PE1_SS_RXN<0>" )
			)
			( signal "@baseboard_fab2_lib.baseboard_fab2(sch_1):p3e_cpu0_pe1_ss_rxn(1)"
				( attribute "CDS_PHYS_NET_NAME" "P3E_CPU0_PE1_SS_RXN<1>"
					( Origin gPackager )
				)
				( attribute "PNN" "P3E_CPU0_PE1_SS_RXN<1>"
					( Origin gPackager )
				)
				( objectStatus "P3E_CPU0_PE1_SS_RXN<1>" )
			)
			( signal "@baseboard_fab2_lib.baseboard_fab2(sch_1):p3e_cpu0_pe1_ss_rxn(2)"
				( attribute "CDS_PHYS_NET_NAME" "P3E_CPU0_PE1_SS_RXN<2>"
					( Origin gPackager )
				)
				( attribute "PNN" "P3E_CPU0_PE1_SS_RXN<2>"
					( Origin gPackager )
				)
				( objectStatus "P3E_CPU0_PE1_SS_RXN<2>" )
			)
			( signal "@baseboard_fab2_lib.baseboard_fab2(sch_1):p3e_cpu0_pe1_ss_rxn(3)"
				( attribute "CDS_PHYS_NET_NAME" "P3E_CPU0_PE1_SS_RXN<3>"
					( Origin gPackager )
				)
				( attribute "PNN" "P3E_CPU0_PE1_SS_RXN<3>"
					( Origin gPackager )
				)
				( objectStatus "P3E_CPU0_PE1_SS_RXN<3>" )
			)
			( signal "@baseboard_fab2_lib.baseboard_fab2(sch_1):p3e_cpu0_pe1_ss_rxn(4)"
				( attribute "CDS_PHYS_NET_NAME" "P3E_CPU0_PE1_SS_RXN<4>"
					( Origin gPackager )
				)
				( attribute "PNN" "P3E_CPU0_PE1_SS_RXN<4>"
					( Origin gPackager )
				)
				( objectStatus "P3E_CPU0_PE1_SS_RXN<4>" )
			)
			( signal "@baseboard_fab2_lib.baseboard_fab2(sch_1):p3e_cpu0_pe1_ss_rxn(5)"
				( attribute "CDS_PHYS_NET_NAME" "P3E_CPU0_PE1_SS_RXN<5>"
					( Origin gPackager )
				)
				( attribute "PNN" "P3E_CPU0_PE1_SS_RXN<5>"
					( Origin gPackager )
				)
				( objectStatus "P3E_CPU0_PE1_SS_RXN<5>" )
			)
			( signal "@baseboard_fab2_lib.baseboard_fab2(sch_1):p3e_cpu0_pe1_ss_rxn(6)"
				( attribute "CDS_PHYS_NET_NAME" "P3E_CPU0_PE1_SS_RXN<6>"
					( Origin gPackager )
				)
				( attribute "PNN" "P3E_CPU0_PE1_SS_RXN<6>"
					( Origin gPackager )
				)
				( objectStatus "P3E_CPU0_PE1_SS_RXN<6>" )
			)
			( signal "@baseboard_fab2_lib.baseboard_fab2(sch_1):p3e_cpu0_pe1_ss_rxn(7)"
				( attribute "CDS_PHYS_NET_NAME" "P3E_CPU0_PE1_SS_RXN<7>"
					( Origin gPackager )
				)
				( attribute "PNN" "P3E_CPU0_PE1_SS_RXN<7>"
					( Origin gPackager )
				)
				( objectStatus "P3E_CPU0_PE1_SS_RXN<7>" )
			)
			( signal "@baseboard_fab2_lib.baseboard_fab2(sch_1):p3e_cpu0_pe1_ss_rxp(0)"
				( attribute "CDS_PHYS_NET_NAME" "P3E_CPU0_PE1_SS_RXP<0>"
					( Origin gPackager )
				)
				( attribute "PNN" "P3E_CPU0_PE1_SS_RXP<0>"
					( Origin gPackager )
				)
				( objectStatus "P3E_CPU0_PE1_SS_RXP<0>" )
			)
			( signal "@baseboard_fab2_lib.baseboard_fab2(sch_1):p3e_cpu0_pe1_ss_rxp(1)"
				( attribute "CDS_PHYS_NET_NAME" "P3E_CPU0_PE1_SS_RXP<1>"
					( Origin gPackager )
				)
				( attribute "PNN" "P3E_CPU0_PE1_SS_RXP<1>"
					( Origin gPackager )
				)
				( objectStatus "P3E_CPU0_PE1_SS_RXP<1>" )
			)
			( signal "@baseboard_fab2_lib.baseboard_fab2(sch_1):p3e_cpu0_pe1_ss_rxp(2)"
				( attribute "CDS_PHYS_NET_NAME" "P3E_CPU0_PE1_SS_RXP<2>"
					( Origin gPackager )
				)
				( attribute "PNN" "P3E_CPU0_PE1_SS_RXP<2>"
					( Origin gPackager )
				)
				( objectStatus "P3E_CPU0_PE1_SS_RXP<2>" )
			)
			( signal "@baseboard_fab2_lib.baseboard_fab2(sch_1):p3e_cpu0_pe1_ss_rxp(3)"
				( attribute "CDS_PHYS_NET_NAME" "P3E_CPU0_PE1_SS_RXP<3>"
					( Origin gPackager )
				)
				( attribute "PNN" "P3E_CPU0_PE1_SS_RXP<3>"
					( Origin gPackager )
				)
				( objectStatus "P3E_CPU0_PE1_SS_RXP<3>" )
			)
			( signal "@baseboard_fab2_lib.baseboard_fab2(sch_1):p3e_cpu0_pe1_ss_rxp(4)"
				( attribute "CDS_PHYS_NET_NAME" "P3E_CPU0_PE1_SS_RXP<4>"
					( Origin gPackager )
				)
				( attribute "PNN" "P3E_CPU0_PE1_SS_RXP<4>"
					( Origin gPackager )
				)
				( objectStatus "P3E_CPU0_PE1_SS_RXP<4>" )
			)
			( signal "@baseboard_fab2_lib.baseboard_fab2(sch_1):p3e_cpu0_pe1_ss_rxp(5)"
				( attribute "CDS_PHYS_NET_NAME" "P3E_CPU0_PE1_SS_RXP<5>"
					( Origin gPackager )
				)
				( attribute "PNN" "P3E_CPU0_PE1_SS_RXP<5>"
					( Origin gPackager )
				)
				( objectStatus "P3E_CPU0_PE1_SS_RXP<5>" )
			)
			( signal "@baseboard_fab2_lib.baseboard_fab2(sch_1):p3e_cpu0_pe1_ss_rxp(6)"
				( attribute "CDS_PHYS_NET_NAME" "P3E_CPU0_PE1_SS_RXP<6>"
					( Origin gPackager )
				)
				( attribute "PNN" "P3E_CPU0_PE1_SS_RXP<6>"
					( Origin gPackager )
				)
				( objectStatus "P3E_CPU0_PE1_SS_RXP<6>" )
			)
			( signal "@baseboard_fab2_lib.baseboard_fab2(sch_1):p3e_cpu0_pe1_ss_rxp(7)"
				( attribute "CDS_PHYS_NET_NAME" "P3E_CPU0_PE1_SS_RXP<7>"
					( Origin gPackager )
				)
				( attribute "PNN" "P3E_CPU0_PE1_SS_RXP<7>"
					( Origin gPackager )
				)
				( objectStatus "P3E_CPU0_PE1_SS_RXP<7>" )
			)
			( signal "@baseboard_fab2_lib.baseboard_fab2(sch_1):p3e_cpu0_pe1_ss_txn(0)"
				( attribute "CDS_PHYS_NET_NAME" "P3E_CPU0_PE1_SS_TXN<0>"
					( Origin gPackager )
				)
				( attribute "PNN" "P3E_CPU0_PE1_SS_TXN<0>"
					( Origin gPackager )
				)
				( objectStatus "P3E_CPU0_PE1_SS_TXN<0>" )
			)
			( signal "@baseboard_fab2_lib.baseboard_fab2(sch_1):p3e_cpu0_pe1_ss_txn(1)"
				( attribute "CDS_PHYS_NET_NAME" "P3E_CPU0_PE1_SS_TXN<1>"
					( Origin gPackager )
				)
				( attribute "PNN" "P3E_CPU0_PE1_SS_TXN<1>"
					( Origin gPackager )
				)
				( objectStatus "P3E_CPU0_PE1_SS_TXN<1>" )
			)
			( signal "@baseboard_fab2_lib.baseboard_fab2(sch_1):p3e_cpu0_pe1_ss_txn(2)"
				( attribute "CDS_PHYS_NET_NAME" "P3E_CPU0_PE1_SS_TXN<2>"
					( Origin gPackager )
				)
				( attribute "PNN" "P3E_CPU0_PE1_SS_TXN<2>"
					( Origin gPackager )
				)
				( objectStatus "P3E_CPU0_PE1_SS_TXN<2>" )
			)
			( signal "@baseboard_fab2_lib.baseboard_fab2(sch_1):p3e_cpu0_pe1_ss_txn(3)"
				( attribute "CDS_PHYS_NET_NAME" "P3E_CPU0_PE1_SS_TXN<3>"
					( Origin gPackager )
				)
				( attribute "PNN" "P3E_CPU0_PE1_SS_TXN<3>"
					( Origin gPackager )
				)
				( objectStatus "P3E_CPU0_PE1_SS_TXN<3>" )
			)
			( signal "@baseboard_fab2_lib.baseboard_fab2(sch_1):p3e_cpu0_pe1_ss_txn(4)"
				( attribute "CDS_PHYS_NET_NAME" "P3E_CPU0_PE1_SS_TXN<4>"
					( Origin gPackager )
				)
				( attribute "PNN" "P3E_CPU0_PE1_SS_TXN<4>"
					( Origin gPackager )
				)
				( objectStatus "P3E_CPU0_PE1_SS_TXN<4>" )
			)
			( signal "@baseboard_fab2_lib.baseboard_fab2(sch_1):p3e_cpu0_pe1_ss_txn(5)"
				( attribute "CDS_PHYS_NET_NAME" "P3E_CPU0_PE1_SS_TXN<5>"
					( Origin gPackager )
				)
				( attribute "PNN" "P3E_CPU0_PE1_SS_TXN<5>"
					( Origin gPackager )
				)
				( objectStatus "P3E_CPU0_PE1_SS_TXN<5>" )
			)
			( signal "@baseboard_fab2_lib.baseboard_fab2(sch_1):p3e_cpu0_pe1_ss_txn(6)"
				( attribute "CDS_PHYS_NET_NAME" "P3E_CPU0_PE1_SS_TXN<6>"
					( Origin gPackager )
				)
				( attribute "PNN" "P3E_CPU0_PE1_SS_TXN<6>"
					( Origin gPackager )
				)
				( objectStatus "P3E_CPU0_PE1_SS_TXN<6>" )
			)
			( signal "@baseboard_fab2_lib.baseboard_fab2(sch_1):p3e_cpu0_pe1_ss_txn(7)"
				( attribute "CDS_PHYS_NET_NAME" "P3E_CPU0_PE1_SS_TXN<7>"
					( Origin gPackager )
				)
				( attribute "PNN" "P3E_CPU0_PE1_SS_TXN<7>"
					( Origin gPackager )
				)
				( objectStatus "P3E_CPU0_PE1_SS_TXN<7>" )
			)
			( signal "@baseboard_fab2_lib.baseboard_fab2(sch_1):p3e_cpu0_pe1_ss_txp(0)"
				( attribute "CDS_PHYS_NET_NAME" "P3E_CPU0_PE1_SS_TXP<0>"
					( Origin gPackager )
				)
				( attribute "PNN" "P3E_CPU0_PE1_SS_TXP<0>"
					( Origin gPackager )
				)
				( objectStatus "P3E_CPU0_PE1_SS_TXP<0>" )
			)
			( signal "@baseboard_fab2_lib.baseboard_fab2(sch_1):p3e_cpu0_pe1_ss_txp(1)"
				( attribute "CDS_PHYS_NET_NAME" "P3E_CPU0_PE1_SS_TXP<1>"
					( Origin gPackager )
				)
				( attribute "PNN" "P3E_CPU0_PE1_SS_TXP<1>"
					( Origin gPackager )
				)
				( objectStatus "P3E_CPU0_PE1_SS_TXP<1>" )
			)
			( signal "@baseboard_fab2_lib.baseboard_fab2(sch_1):p3e_cpu0_pe1_ss_txp(2)"
				( attribute "CDS_PHYS_NET_NAME" "P3E_CPU0_PE1_SS_TXP<2>"
					( Origin gPackager )
				)
				( attribute "PNN" "P3E_CPU0_PE1_SS_TXP<2>"
					( Origin gPackager )
				)
				( objectStatus "P3E_CPU0_PE1_SS_TXP<2>" )
			)
			( signal "@baseboard_fab2_lib.baseboard_fab2(sch_1):p3e_cpu0_pe1_ss_txp(3)"
				( attribute "CDS_PHYS_NET_NAME" "P3E_CPU0_PE1_SS_TXP<3>"
					( Origin gPackager )
				)
				( attribute "PNN" "P3E_CPU0_PE1_SS_TXP<3>"
					( Origin gPackager )
				)
				( objectStatus "P3E_CPU0_PE1_SS_TXP<3>" )
			)
			( signal "@baseboard_fab2_lib.baseboard_fab2(sch_1):p3e_cpu0_pe1_ss_txp(4)"
				( attribute "CDS_PHYS_NET_NAME" "P3E_CPU0_PE1_SS_TXP<4>"
					( Origin gPackager )
				)
				( attribute "PNN" "P3E_CPU0_PE1_SS_TXP<4>"
					( Origin gPackager )
				)
				( objectStatus "P3E_CPU0_PE1_SS_TXP<4>" )
			)
			( signal "@baseboard_fab2_lib.baseboard_fab2(sch_1):p3e_cpu0_pe1_ss_txp(5)"
				( attribute "CDS_PHYS_NET_NAME" "P3E_CPU0_PE1_SS_TXP<5>"
					( Origin gPackager )
				)
				( attribute "PNN" "P3E_CPU0_PE1_SS_TXP<5>"
					( Origin gPackager )
				)
				( objectStatus "P3E_CPU0_PE1_SS_TXP<5>" )
			)
			( signal "@baseboard_fab2_lib.baseboard_fab2(sch_1):p3e_cpu0_pe1_ss_txp(6)"
				( attribute "CDS_PHYS_NET_NAME" "P3E_CPU0_PE1_SS_TXP<6>"
					( Origin gPackager )
				)
				( attribute "PNN" "P3E_CPU0_PE1_SS_TXP<6>"
					( Origin gPackager )
				)
				( objectStatus "P3E_CPU0_PE1_SS_TXP<6>" )
			)
			( signal "@baseboard_fab2_lib.baseboard_fab2(sch_1):p3e_cpu0_pe1_ss_txp(7)"
				( attribute "CDS_PHYS_NET_NAME" "P3E_CPU0_PE1_SS_TXP<7>"
					( Origin gPackager )
				)
				( attribute "PNN" "P3E_CPU0_PE1_SS_TXP<7>"
					( Origin gPackager )
				)
				( objectStatus "P3E_CPU0_PE1_SS_TXP<7>" )
			)
			( signal "@baseboard_fab2_lib.baseboard_fab2(sch_1):p3e_cpu0_pe2_ss_rxn(0)"
				( attribute "CDS_PHYS_NET_NAME" "P3E_CPU0_PE2_SS_RXN<0>"
					( Origin gPackager )
				)
				( attribute "PNN" "P3E_CPU0_PE2_SS_RXN<0>"
					( Origin gPackager )
				)
				( objectStatus "P3E_CPU0_PE2_SS_RXN<0>" )
			)
			( signal "@baseboard_fab2_lib.baseboard_fab2(sch_1):p3e_cpu0_pe2_ss_rxn(1)"
				( attribute "CDS_PHYS_NET_NAME" "P3E_CPU0_PE2_SS_RXN<1>"
					( Origin gPackager )
				)
				( attribute "PNN" "P3E_CPU0_PE2_SS_RXN<1>"
					( Origin gPackager )
				)
				( objectStatus "P3E_CPU0_PE2_SS_RXN<1>" )
			)
			( signal "@baseboard_fab2_lib.baseboard_fab2(sch_1):p3e_cpu0_pe2_ss_rxn(2)"
				( attribute "CDS_PHYS_NET_NAME" "P3E_CPU0_PE2_SS_RXN<2>"
					( Origin gPackager )
				)
				( attribute "PNN" "P3E_CPU0_PE2_SS_RXN<2>"
					( Origin gPackager )
				)
				( objectStatus "P3E_CPU0_PE2_SS_RXN<2>" )
			)
			( signal "@baseboard_fab2_lib.baseboard_fab2(sch_1):p3e_cpu0_pe2_ss_rxn(3)"
				( attribute "CDS_PHYS_NET_NAME" "P3E_CPU0_PE2_SS_RXN<3>"
					( Origin gPackager )
				)
				( attribute "PNN" "P3E_CPU0_PE2_SS_RXN<3>"
					( Origin gPackager )
				)
				( objectStatus "P3E_CPU0_PE2_SS_RXN<3>" )
			)
			( signal "@baseboard_fab2_lib.baseboard_fab2(sch_1):p3e_cpu0_pe2_ss_rxn(4)"
				( attribute "CDS_PHYS_NET_NAME" "P3E_CPU0_PE2_SS_RXN<4>"
					( Origin gPackager )
				)
				( attribute "PNN" "P3E_CPU0_PE2_SS_RXN<4>"
					( Origin gPackager )
				)
				( objectStatus "P3E_CPU0_PE2_SS_RXN<4>" )
			)
			( signal "@baseboard_fab2_lib.baseboard_fab2(sch_1):p3e_cpu0_pe2_ss_rxn(5)"
				( attribute "CDS_PHYS_NET_NAME" "P3E_CPU0_PE2_SS_RXN<5>"
					( Origin gPackager )
				)
				( attribute "PNN" "P3E_CPU0_PE2_SS_RXN<5>"
					( Origin gPackager )
				)
				( objectStatus "P3E_CPU0_PE2_SS_RXN<5>" )
			)
			( signal "@baseboard_fab2_lib.baseboard_fab2(sch_1):p3e_cpu0_pe2_ss_rxn(6)"
				( attribute "CDS_PHYS_NET_NAME" "P3E_CPU0_PE2_SS_RXN<6>"
					( Origin gPackager )
				)
				( attribute "PNN" "P3E_CPU0_PE2_SS_RXN<6>"
					( Origin gPackager )
				)
				( objectStatus "P3E_CPU0_PE2_SS_RXN<6>" )
			)
			( signal "@baseboard_fab2_lib.baseboard_fab2(sch_1):p3e_cpu0_pe2_ss_rxn(7)"
				( attribute "CDS_PHYS_NET_NAME" "P3E_CPU0_PE2_SS_RXN<7>"
					( Origin gPackager )
				)
				( attribute "PNN" "P3E_CPU0_PE2_SS_RXN<7>"
					( Origin gPackager )
				)
				( objectStatus "P3E_CPU0_PE2_SS_RXN<7>" )
			)
			( signal "@baseboard_fab2_lib.baseboard_fab2(sch_1):p3e_cpu0_pe2_ss_rxn(8)"
				( alias ( signalRef "@baseboard_fab2_lib.baseboard_fab2(sch_1):page245_p3e_cpu0_pe2_ss_rxn(8)") )
				( attribute "CDS_PHYS_NET_NAME" "P3E_CPU0_PE2_SS_RXN<8>"
					( Origin gPackager )
				)
				( attribute "PNN" "P3E_CPU0_PE2_SS_RXN<8>"
					( Origin gPackager )
				)
				( objectStatus "P3E_CPU0_PE2_SS_RXN<8>" )
			)
			( signal "@baseboard_fab2_lib.baseboard_fab2(sch_1):page245_p3e_cpu0_pe2_ss_rxn(8)"
				( attribute "CDS_PHYS_NET_NAME" "P3E_CPU0_PE2_SS_RXN<8>"
					( Origin gPackager )
				)
				( objectFlag fObjectAlias )
				( objectStatus "page245_p3e_cpu0_pe2_ss_rxn<8>" )
			)
			( signal "@baseboard_fab2_lib.baseboard_fab2(sch_1):p3e_cpu0_pe2_ss_rxn(9)"
				( alias ( signalRef "@baseboard_fab2_lib.baseboard_fab2(sch_1):page245_p3e_cpu0_pe2_ss_rxn(9)") )
				( attribute "CDS_PHYS_NET_NAME" "P3E_CPU0_PE2_SS_RXN<9>"
					( Origin gPackager )
				)
				( attribute "PNN" "P3E_CPU0_PE2_SS_RXN<9>"
					( Origin gPackager )
				)
				( objectStatus "P3E_CPU0_PE2_SS_RXN<9>" )
			)
			( signal "@baseboard_fab2_lib.baseboard_fab2(sch_1):page245_p3e_cpu0_pe2_ss_rxn(9)"
				( objectFlag fObjectAlias )
				( objectStatus "page245_p3e_cpu0_pe2_ss_rxn<9>" )
			)
			( signal "@baseboard_fab2_lib.baseboard_fab2(sch_1):p3e_cpu0_pe2_ss_rxn(10)"
				( alias ( signalRef "@baseboard_fab2_lib.baseboard_fab2(sch_1):page245_p3e_cpu0_pe2_ss_rxn(10)") )
				( attribute "CDS_PHYS_NET_NAME" "P3E_CPU0_PE2_SS_RXN<10>"
					( Origin gPackager )
				)
				( attribute "PNN" "P3E_CPU0_PE2_SS_RXN<10>"
					( Origin gPackager )
				)
				( objectStatus "P3E_CPU0_PE2_SS_RXN<10>" )
			)
			( signal "@baseboard_fab2_lib.baseboard_fab2(sch_1):page245_p3e_cpu0_pe2_ss_rxn(10)"
				( objectFlag fObjectAlias )
				( objectStatus "page245_p3e_cpu0_pe2_ss_rxn<10>" )
			)
			( signal "@baseboard_fab2_lib.baseboard_fab2(sch_1):p3e_cpu0_pe2_ss_rxn(11)"
				( alias ( signalRef "@baseboard_fab2_lib.baseboard_fab2(sch_1):page245_p3e_cpu0_pe2_ss_rxn(11)") )
				( attribute "CDS_PHYS_NET_NAME" "P3E_CPU0_PE2_SS_RXN<11>"
					( Origin gPackager )
				)
				( attribute "PNN" "P3E_CPU0_PE2_SS_RXN<11>"
					( Origin gPackager )
				)
				( objectStatus "P3E_CPU0_PE2_SS_RXN<11>" )
			)
			( signal "@baseboard_fab2_lib.baseboard_fab2(sch_1):page245_p3e_cpu0_pe2_ss_rxn(11)"
				( objectFlag fObjectAlias )
				( objectStatus "page245_p3e_cpu0_pe2_ss_rxn<11>" )
			)
			( signal "@baseboard_fab2_lib.baseboard_fab2(sch_1):p3e_cpu0_pe2_ss_rxn(12)"
				( alias ( signalRef "@baseboard_fab2_lib.baseboard_fab2(sch_1):page245_p3e_cpu0_pe2_ss_rxn(12)") )
				( attribute "CDS_PHYS_NET_NAME" "P3E_CPU0_PE2_SS_RXN<12>"
					( Origin gPackager )
				)
				( attribute "PNN" "P3E_CPU0_PE2_SS_RXN<12>"
					( Origin gPackager )
				)
				( objectStatus "P3E_CPU0_PE2_SS_RXN<12>" )
			)
			( signal "@baseboard_fab2_lib.baseboard_fab2(sch_1):page245_p3e_cpu0_pe2_ss_rxn(12)"
				( objectFlag fObjectAlias )
				( objectStatus "page245_p3e_cpu0_pe2_ss_rxn<12>" )
			)
			( signal "@baseboard_fab2_lib.baseboard_fab2(sch_1):p3e_cpu0_pe2_ss_rxn(13)"
				( alias ( signalRef "@baseboard_fab2_lib.baseboard_fab2(sch_1):page245_p3e_cpu0_pe2_ss_rxn(13)") )
				( attribute "CDS_PHYS_NET_NAME" "P3E_CPU0_PE2_SS_RXN<13>"
					( Origin gPackager )
				)
				( attribute "PNN" "P3E_CPU0_PE2_SS_RXN<13>"
					( Origin gPackager )
				)
				( objectStatus "P3E_CPU0_PE2_SS_RXN<13>" )
			)
			( signal "@baseboard_fab2_lib.baseboard_fab2(sch_1):page245_p3e_cpu0_pe2_ss_rxn(13)"
				( objectFlag fObjectAlias )
				( objectStatus "page245_p3e_cpu0_pe2_ss_rxn<13>" )
			)
			( signal "@baseboard_fab2_lib.baseboard_fab2(sch_1):p3e_cpu0_pe2_ss_rxn(14)"
				( alias ( signalRef "@baseboard_fab2_lib.baseboard_fab2(sch_1):page245_p3e_cpu0_pe2_ss_rxn(14)") )
				( attribute "CDS_PHYS_NET_NAME" "P3E_CPU0_PE2_SS_RXN<14>"
					( Origin gPackager )
				)
				( attribute "PNN" "P3E_CPU0_PE2_SS_RXN<14>"
					( Origin gPackager )
				)
				( objectStatus "P3E_CPU0_PE2_SS_RXN<14>" )
			)
			( signal "@baseboard_fab2_lib.baseboard_fab2(sch_1):page245_p3e_cpu0_pe2_ss_rxn(14)"
				( objectFlag fObjectAlias )
				( objectStatus "page245_p3e_cpu0_pe2_ss_rxn<14>" )
			)
			( signal "@baseboard_fab2_lib.baseboard_fab2(sch_1):p3e_cpu0_pe2_ss_rxn(15)"
				( alias ( signalRef "@baseboard_fab2_lib.baseboard_fab2(sch_1):page245_p3e_cpu0_pe2_ss_rxn(15)") )
				( attribute "CDS_PHYS_NET_NAME" "P3E_CPU0_PE2_SS_RXN<15>"
					( Origin gPackager )
				)
				( attribute "PNN" "P3E_CPU0_PE2_SS_RXN<15>"
					( Origin gPackager )
				)
				( objectStatus "P3E_CPU0_PE2_SS_RXN<15>" )
			)
			( signal "@baseboard_fab2_lib.baseboard_fab2(sch_1):page245_p3e_cpu0_pe2_ss_rxn(15)"
				( objectFlag fObjectAlias )
				( objectStatus "page245_p3e_cpu0_pe2_ss_rxn<15>" )
			)
			( signal "@baseboard_fab2_lib.baseboard_fab2(sch_1):p3e_cpu0_pe2_ss_rxp(0)"
				( attribute "CDS_PHYS_NET_NAME" "P3E_CPU0_PE2_SS_RXP<0>"
					( Origin gPackager )
				)
				( attribute "PNN" "P3E_CPU0_PE2_SS_RXP<0>"
					( Origin gPackager )
				)
				( objectStatus "P3E_CPU0_PE2_SS_RXP<0>" )
			)
			( signal "@baseboard_fab2_lib.baseboard_fab2(sch_1):p3e_cpu0_pe2_ss_rxp(1)"
				( attribute "CDS_PHYS_NET_NAME" "P3E_CPU0_PE2_SS_RXP<1>"
					( Origin gPackager )
				)
				( attribute "PNN" "P3E_CPU0_PE2_SS_RXP<1>"
					( Origin gPackager )
				)
				( objectStatus "P3E_CPU0_PE2_SS_RXP<1>" )
			)
			( signal "@baseboard_fab2_lib.baseboard_fab2(sch_1):p3e_cpu0_pe2_ss_rxp(2)"
				( attribute "CDS_PHYS_NET_NAME" "P3E_CPU0_PE2_SS_RXP<2>"
					( Origin gPackager )
				)
				( attribute "PNN" "P3E_CPU0_PE2_SS_RXP<2>"
					( Origin gPackager )
				)
				( objectStatus "P3E_CPU0_PE2_SS_RXP<2>" )
			)
			( signal "@baseboard_fab2_lib.baseboard_fab2(sch_1):p3e_cpu0_pe2_ss_rxp(3)"
				( attribute "CDS_PHYS_NET_NAME" "P3E_CPU0_PE2_SS_RXP<3>"
					( Origin gPackager )
				)
				( attribute "PNN" "P3E_CPU0_PE2_SS_RXP<3>"
					( Origin gPackager )
				)
				( objectStatus "P3E_CPU0_PE2_SS_RXP<3>" )
			)
			( signal "@baseboard_fab2_lib.baseboard_fab2(sch_1):p3e_cpu0_pe2_ss_rxp(4)"
				( attribute "CDS_PHYS_NET_NAME" "P3E_CPU0_PE2_SS_RXP<4>"
					( Origin gPackager )
				)
				( attribute "PNN" "P3E_CPU0_PE2_SS_RXP<4>"
					( Origin gPackager )
				)
				( objectStatus "P3E_CPU0_PE2_SS_RXP<4>" )
			)
			( signal "@baseboard_fab2_lib.baseboard_fab2(sch_1):p3e_cpu0_pe2_ss_rxp(5)"
				( attribute "CDS_PHYS_NET_NAME" "P3E_CPU0_PE2_SS_RXP<5>"
					( Origin gPackager )
				)
				( attribute "PNN" "P3E_CPU0_PE2_SS_RXP<5>"
					( Origin gPackager )
				)
				( objectStatus "P3E_CPU0_PE2_SS_RXP<5>" )
			)
			( signal "@baseboard_fab2_lib.baseboard_fab2(sch_1):p3e_cpu0_pe2_ss_rxp(6)"
				( attribute "CDS_PHYS_NET_NAME" "P3E_CPU0_PE2_SS_RXP<6>"
					( Origin gPackager )
				)
				( attribute "PNN" "P3E_CPU0_PE2_SS_RXP<6>"
					( Origin gPackager )
				)
				( objectStatus "P3E_CPU0_PE2_SS_RXP<6>" )
			)
			( signal "@baseboard_fab2_lib.baseboard_fab2(sch_1):p3e_cpu0_pe2_ss_rxp(7)"
				( attribute "CDS_PHYS_NET_NAME" "P3E_CPU0_PE2_SS_RXP<7>"
					( Origin gPackager )
				)
				( attribute "PNN" "P3E_CPU0_PE2_SS_RXP<7>"
					( Origin gPackager )
				)
				( objectStatus "P3E_CPU0_PE2_SS_RXP<7>" )
			)
			( signal "@baseboard_fab2_lib.baseboard_fab2(sch_1):p3e_cpu0_pe2_ss_rxp(8)"
				( alias ( signalRef "@baseboard_fab2_lib.baseboard_fab2(sch_1):page245_p3e_cpu0_pe2_ss_rxp(8)") )
				( attribute "CDS_PHYS_NET_NAME" "P3E_CPU0_PE2_SS_RXP<8>"
					( Origin gPackager )
				)
				( attribute "PNN" "P3E_CPU0_PE2_SS_RXP<8>"
					( Origin gPackager )
				)
				( objectStatus "P3E_CPU0_PE2_SS_RXP<8>" )
			)
			( signal "@baseboard_fab2_lib.baseboard_fab2(sch_1):page245_p3e_cpu0_pe2_ss_rxp(8)"
				( attribute "CDS_PHYS_NET_NAME" "P3E_CPU0_PE2_SS_RXP<8>"
					( Origin gPackager )
				)
				( objectFlag fObjectAlias )
				( objectStatus "page245_p3e_cpu0_pe2_ss_rxp<8>" )
			)
			( signal "@baseboard_fab2_lib.baseboard_fab2(sch_1):p3e_cpu0_pe2_ss_rxp(9)"
				( alias ( signalRef "@baseboard_fab2_lib.baseboard_fab2(sch_1):page245_p3e_cpu0_pe2_ss_rxp(9)") )
				( attribute "CDS_PHYS_NET_NAME" "P3E_CPU0_PE2_SS_RXP<9>"
					( Origin gPackager )
				)
				( attribute "PNN" "P3E_CPU0_PE2_SS_RXP<9>"
					( Origin gPackager )
				)
				( objectStatus "P3E_CPU0_PE2_SS_RXP<9>" )
			)
			( signal "@baseboard_fab2_lib.baseboard_fab2(sch_1):page245_p3e_cpu0_pe2_ss_rxp(9)"
				( objectFlag fObjectAlias )
				( objectStatus "page245_p3e_cpu0_pe2_ss_rxp<9>" )
			)
			( signal "@baseboard_fab2_lib.baseboard_fab2(sch_1):p3e_cpu0_pe2_ss_rxp(10)"
				( alias ( signalRef "@baseboard_fab2_lib.baseboard_fab2(sch_1):page245_p3e_cpu0_pe2_ss_rxp(10)") )
				( attribute "CDS_PHYS_NET_NAME" "P3E_CPU0_PE2_SS_RXP<10>"
					( Origin gPackager )
				)
				( attribute "PNN" "P3E_CPU0_PE2_SS_RXP<10>"
					( Origin gPackager )
				)
				( objectStatus "P3E_CPU0_PE2_SS_RXP<10>" )
			)
			( signal "@baseboard_fab2_lib.baseboard_fab2(sch_1):page245_p3e_cpu0_pe2_ss_rxp(10)"
				( objectFlag fObjectAlias )
				( objectStatus "page245_p3e_cpu0_pe2_ss_rxp<10>" )
			)
			( signal "@baseboard_fab2_lib.baseboard_fab2(sch_1):p3e_cpu0_pe2_ss_rxp(11)"
				( alias ( signalRef "@baseboard_fab2_lib.baseboard_fab2(sch_1):page245_p3e_cpu0_pe2_ss_rxp(11)") )
				( attribute "CDS_PHYS_NET_NAME" "P3E_CPU0_PE2_SS_RXP<11>"
					( Origin gPackager )
				)
				( attribute "PNN" "P3E_CPU0_PE2_SS_RXP<11>"
					( Origin gPackager )
				)
				( objectStatus "P3E_CPU0_PE2_SS_RXP<11>" )
			)
			( signal "@baseboard_fab2_lib.baseboard_fab2(sch_1):page245_p3e_cpu0_pe2_ss_rxp(11)"
				( objectFlag fObjectAlias )
				( objectStatus "page245_p3e_cpu0_pe2_ss_rxp<11>" )
			)
			( signal "@baseboard_fab2_lib.baseboard_fab2(sch_1):p3e_cpu0_pe2_ss_rxp(12)"
				( alias ( signalRef "@baseboard_fab2_lib.baseboard_fab2(sch_1):page245_p3e_cpu0_pe2_ss_rxp(12)") )
				( attribute "CDS_PHYS_NET_NAME" "P3E_CPU0_PE2_SS_RXP<12>"
					( Origin gPackager )
				)
				( attribute "PNN" "P3E_CPU0_PE2_SS_RXP<12>"
					( Origin gPackager )
				)
				( objectStatus "P3E_CPU0_PE2_SS_RXP<12>" )
			)
			( signal "@baseboard_fab2_lib.baseboard_fab2(sch_1):page245_p3e_cpu0_pe2_ss_rxp(12)"
				( objectFlag fObjectAlias )
				( objectStatus "page245_p3e_cpu0_pe2_ss_rxp<12>" )
			)
			( signal "@baseboard_fab2_lib.baseboard_fab2(sch_1):p3e_cpu0_pe2_ss_rxp(13)"
				( alias ( signalRef "@baseboard_fab2_lib.baseboard_fab2(sch_1):page245_p3e_cpu0_pe2_ss_rxp(13)") )
				( attribute "CDS_PHYS_NET_NAME" "P3E_CPU0_PE2_SS_RXP<13>"
					( Origin gPackager )
				)
				( attribute "PNN" "P3E_CPU0_PE2_SS_RXP<13>"
					( Origin gPackager )
				)
				( objectStatus "P3E_CPU0_PE2_SS_RXP<13>" )
			)
			( signal "@baseboard_fab2_lib.baseboard_fab2(sch_1):page245_p3e_cpu0_pe2_ss_rxp(13)"
				( objectFlag fObjectAlias )
				( objectStatus "page245_p3e_cpu0_pe2_ss_rxp<13>" )
			)
			( signal "@baseboard_fab2_lib.baseboard_fab2(sch_1):p3e_cpu0_pe2_ss_rxp(14)"
				( alias ( signalRef "@baseboard_fab2_lib.baseboard_fab2(sch_1):page245_p3e_cpu0_pe2_ss_rxp(14)") )
				( attribute "CDS_PHYS_NET_NAME" "P3E_CPU0_PE2_SS_RXP<14>"
					( Origin gPackager )
				)
				( attribute "PNN" "P3E_CPU0_PE2_SS_RXP<14>"
					( Origin gPackager )
				)
				( objectStatus "P3E_CPU0_PE2_SS_RXP<14>" )
			)
			( signal "@baseboard_fab2_lib.baseboard_fab2(sch_1):page245_p3e_cpu0_pe2_ss_rxp(14)"
				( objectFlag fObjectAlias )
				( objectStatus "page245_p3e_cpu0_pe2_ss_rxp<14>" )
			)
			( signal "@baseboard_fab2_lib.baseboard_fab2(sch_1):p3e_cpu0_pe2_ss_rxp(15)"
				( alias ( signalRef "@baseboard_fab2_lib.baseboard_fab2(sch_1):page245_p3e_cpu0_pe2_ss_rxp(15)") )
				( attribute "CDS_PHYS_NET_NAME" "P3E_CPU0_PE2_SS_RXP<15>"
					( Origin gPackager )
				)
				( attribute "PNN" "P3E_CPU0_PE2_SS_RXP<15>"
					( Origin gPackager )
				)
				( objectStatus "P3E_CPU0_PE2_SS_RXP<15>" )
			)
			( signal "@baseboard_fab2_lib.baseboard_fab2(sch_1):page245_p3e_cpu0_pe2_ss_rxp(15)"
				( objectFlag fObjectAlias )
				( objectStatus "page245_p3e_cpu0_pe2_ss_rxp<15>" )
			)
			( signal "@baseboard_fab2_lib.baseboard_fab2(sch_1):p3e_cpu0_pe2_ss_txn(0)"
				( attribute "CDS_PHYS_NET_NAME" "P3E_CPU0_PE2_SS_TXN<0>"
					( Origin gPackager )
				)
				( attribute "PNN" "P3E_CPU0_PE2_SS_TXN<0>"
					( Origin gPackager )
				)
				( objectStatus "P3E_CPU0_PE2_SS_TXN<0>" )
			)
			( signal "@baseboard_fab2_lib.baseboard_fab2(sch_1):p3e_cpu0_pe2_ss_txn(1)"
				( attribute "CDS_PHYS_NET_NAME" "P3E_CPU0_PE2_SS_TXN<1>"
					( Origin gPackager )
				)
				( attribute "PNN" "P3E_CPU0_PE2_SS_TXN<1>"
					( Origin gPackager )
				)
				( objectStatus "P3E_CPU0_PE2_SS_TXN<1>" )
			)
			( signal "@baseboard_fab2_lib.baseboard_fab2(sch_1):p3e_cpu0_pe2_ss_txn(2)"
				( attribute "CDS_PHYS_NET_NAME" "P3E_CPU0_PE2_SS_TXN<2>"
					( Origin gPackager )
				)
				( attribute "PNN" "P3E_CPU0_PE2_SS_TXN<2>"
					( Origin gPackager )
				)
				( objectStatus "P3E_CPU0_PE2_SS_TXN<2>" )
			)
			( signal "@baseboard_fab2_lib.baseboard_fab2(sch_1):p3e_cpu0_pe2_ss_txn(3)"
				( attribute "CDS_PHYS_NET_NAME" "P3E_CPU0_PE2_SS_TXN<3>"
					( Origin gPackager )
				)
				( attribute "PNN" "P3E_CPU0_PE2_SS_TXN<3>"
					( Origin gPackager )
				)
				( objectStatus "P3E_CPU0_PE2_SS_TXN<3>" )
			)
			( signal "@baseboard_fab2_lib.baseboard_fab2(sch_1):p3e_cpu0_pe2_ss_txn(4)"
				( attribute "CDS_PHYS_NET_NAME" "P3E_CPU0_PE2_SS_TXN<4>"
					( Origin gPackager )
				)
				( attribute "PNN" "P3E_CPU0_PE2_SS_TXN<4>"
					( Origin gPackager )
				)
				( objectStatus "P3E_CPU0_PE2_SS_TXN<4>" )
			)
			( signal "@baseboard_fab2_lib.baseboard_fab2(sch_1):p3e_cpu0_pe2_ss_txn(5)"
				( attribute "CDS_PHYS_NET_NAME" "P3E_CPU0_PE2_SS_TXN<5>"
					( Origin gPackager )
				)
				( attribute "PNN" "P3E_CPU0_PE2_SS_TXN<5>"
					( Origin gPackager )
				)
				( objectStatus "P3E_CPU0_PE2_SS_TXN<5>" )
			)
			( signal "@baseboard_fab2_lib.baseboard_fab2(sch_1):p3e_cpu0_pe2_ss_txn(6)"
				( attribute "CDS_PHYS_NET_NAME" "P3E_CPU0_PE2_SS_TXN<6>"
					( Origin gPackager )
				)
				( attribute "PNN" "P3E_CPU0_PE2_SS_TXN<6>"
					( Origin gPackager )
				)
				( objectStatus "P3E_CPU0_PE2_SS_TXN<6>" )
			)
			( signal "@baseboard_fab2_lib.baseboard_fab2(sch_1):p3e_cpu0_pe2_ss_txn(7)"
				( attribute "CDS_PHYS_NET_NAME" "P3E_CPU0_PE2_SS_TXN<7>"
					( Origin gPackager )
				)
				( attribute "PNN" "P3E_CPU0_PE2_SS_TXN<7>"
					( Origin gPackager )
				)
				( objectStatus "P3E_CPU0_PE2_SS_TXN<7>" )
			)
			( signal "@baseboard_fab2_lib.baseboard_fab2(sch_1):p3e_cpu0_pe2_ss_txn(8)"
				( attribute "CDS_PHYS_NET_NAME" "P3E_CPU0_PE2_SS_TXN<8>"
					( Origin gPackager )
				)
				( attribute "PNN" "P3E_CPU0_PE2_SS_TXN<8>"
					( Origin gPackager )
				)
				( objectStatus "P3E_CPU0_PE2_SS_TXN<8>" )
			)
			( signal "@baseboard_fab2_lib.baseboard_fab2(sch_1):p3e_cpu0_pe2_ss_txn(9)"
				( attribute "CDS_PHYS_NET_NAME" "P3E_CPU0_PE2_SS_TXN<9>"
					( Origin gPackager )
				)
				( attribute "PNN" "P3E_CPU0_PE2_SS_TXN<9>"
					( Origin gPackager )
				)
				( objectStatus "P3E_CPU0_PE2_SS_TXN<9>" )
			)
			( signal "@baseboard_fab2_lib.baseboard_fab2(sch_1):p3e_cpu0_pe2_ss_txn(10)"
				( attribute "CDS_PHYS_NET_NAME" "P3E_CPU0_PE2_SS_TXN<10>"
					( Origin gPackager )
				)
				( attribute "PNN" "P3E_CPU0_PE2_SS_TXN<10>"
					( Origin gPackager )
				)
				( objectStatus "P3E_CPU0_PE2_SS_TXN<10>" )
			)
			( signal "@baseboard_fab2_lib.baseboard_fab2(sch_1):p3e_cpu0_pe2_ss_txn(11)"
				( attribute "CDS_PHYS_NET_NAME" "P3E_CPU0_PE2_SS_TXN<11>"
					( Origin gPackager )
				)
				( attribute "PNN" "P3E_CPU0_PE2_SS_TXN<11>"
					( Origin gPackager )
				)
				( objectStatus "P3E_CPU0_PE2_SS_TXN<11>" )
			)
			( signal "@baseboard_fab2_lib.baseboard_fab2(sch_1):p3e_cpu0_pe2_ss_txn(12)"
				( attribute "CDS_PHYS_NET_NAME" "P3E_CPU0_PE2_SS_TXN<12>"
					( Origin gPackager )
				)
				( attribute "PNN" "P3E_CPU0_PE2_SS_TXN<12>"
					( Origin gPackager )
				)
				( objectStatus "P3E_CPU0_PE2_SS_TXN<12>" )
			)
			( signal "@baseboard_fab2_lib.baseboard_fab2(sch_1):p3e_cpu0_pe2_ss_txn(13)"
				( attribute "CDS_PHYS_NET_NAME" "P3E_CPU0_PE2_SS_TXN<13>"
					( Origin gPackager )
				)
				( attribute "PNN" "P3E_CPU0_PE2_SS_TXN<13>"
					( Origin gPackager )
				)
				( objectStatus "P3E_CPU0_PE2_SS_TXN<13>" )
			)
			( signal "@baseboard_fab2_lib.baseboard_fab2(sch_1):p3e_cpu0_pe2_ss_txn(14)"
				( attribute "CDS_PHYS_NET_NAME" "P3E_CPU0_PE2_SS_TXN<14>"
					( Origin gPackager )
				)
				( attribute "PNN" "P3E_CPU0_PE2_SS_TXN<14>"
					( Origin gPackager )
				)
				( objectStatus "P3E_CPU0_PE2_SS_TXN<14>" )
			)
			( signal "@baseboard_fab2_lib.baseboard_fab2(sch_1):p3e_cpu0_pe2_ss_txn(15)"
				( attribute "CDS_PHYS_NET_NAME" "P3E_CPU0_PE2_SS_TXN<15>"
					( Origin gPackager )
				)
				( attribute "PNN" "P3E_CPU0_PE2_SS_TXN<15>"
					( Origin gPackager )
				)
				( objectStatus "P3E_CPU0_PE2_SS_TXN<15>" )
			)
			( signal "@baseboard_fab2_lib.baseboard_fab2(sch_1):p3e_cpu0_pe2_ss_txp(0)"
				( attribute "CDS_PHYS_NET_NAME" "P3E_CPU0_PE2_SS_TXP<0>"
					( Origin gPackager )
				)
				( attribute "PNN" "P3E_CPU0_PE2_SS_TXP<0>"
					( Origin gPackager )
				)
				( objectStatus "P3E_CPU0_PE2_SS_TXP<0>" )
			)
			( signal "@baseboard_fab2_lib.baseboard_fab2(sch_1):p3e_cpu0_pe2_ss_txp(1)"
				( attribute "CDS_PHYS_NET_NAME" "P3E_CPU0_PE2_SS_TXP<1>"
					( Origin gPackager )
				)
				( attribute "PNN" "P3E_CPU0_PE2_SS_TXP<1>"
					( Origin gPackager )
				)
				( objectStatus "P3E_CPU0_PE2_SS_TXP<1>" )
			)
			( signal "@baseboard_fab2_lib.baseboard_fab2(sch_1):p3e_cpu0_pe2_ss_txp(2)"
				( attribute "CDS_PHYS_NET_NAME" "P3E_CPU0_PE2_SS_TXP<2>"
					( Origin gPackager )
				)
				( attribute "PNN" "P3E_CPU0_PE2_SS_TXP<2>"
					( Origin gPackager )
				)
				( objectStatus "P3E_CPU0_PE2_SS_TXP<2>" )
			)
			( signal "@baseboard_fab2_lib.baseboard_fab2(sch_1):p3e_cpu0_pe2_ss_txp(3)"
				( attribute "CDS_PHYS_NET_NAME" "P3E_CPU0_PE2_SS_TXP<3>"
					( Origin gPackager )
				)
				( attribute "PNN" "P3E_CPU0_PE2_SS_TXP<3>"
					( Origin gPackager )
				)
				( objectStatus "P3E_CPU0_PE2_SS_TXP<3>" )
			)
			( signal "@baseboard_fab2_lib.baseboard_fab2(sch_1):p3e_cpu0_pe2_ss_txp(4)"
				( attribute "CDS_PHYS_NET_NAME" "P3E_CPU0_PE2_SS_TXP<4>"
					( Origin gPackager )
				)
				( attribute "PNN" "P3E_CPU0_PE2_SS_TXP<4>"
					( Origin gPackager )
				)
				( objectStatus "P3E_CPU0_PE2_SS_TXP<4>" )
			)
			( signal "@baseboard_fab2_lib.baseboard_fab2(sch_1):p3e_cpu0_pe2_ss_txp(5)"
				( attribute "CDS_PHYS_NET_NAME" "P3E_CPU0_PE2_SS_TXP<5>"
					( Origin gPackager )
				)
				( attribute "PNN" "P3E_CPU0_PE2_SS_TXP<5>"
					( Origin gPackager )
				)
				( objectStatus "P3E_CPU0_PE2_SS_TXP<5>" )
			)
			( signal "@baseboard_fab2_lib.baseboard_fab2(sch_1):p3e_cpu0_pe2_ss_txp(6)"
				( attribute "CDS_PHYS_NET_NAME" "P3E_CPU0_PE2_SS_TXP<6>"
					( Origin gPackager )
				)
				( attribute "PNN" "P3E_CPU0_PE2_SS_TXP<6>"
					( Origin gPackager )
				)
				( objectStatus "P3E_CPU0_PE2_SS_TXP<6>" )
			)
			( signal "@baseboard_fab2_lib.baseboard_fab2(sch_1):p3e_cpu0_pe2_ss_txp(7)"
				( attribute "CDS_PHYS_NET_NAME" "P3E_CPU0_PE2_SS_TXP<7>"
					( Origin gPackager )
				)
				( attribute "PNN" "P3E_CPU0_PE2_SS_TXP<7>"
					( Origin gPackager )
				)
				( objectStatus "P3E_CPU0_PE2_SS_TXP<7>" )
			)
			( signal "@baseboard_fab2_lib.baseboard_fab2(sch_1):p3e_cpu0_pe2_ss_txp(8)"
				( attribute "CDS_PHYS_NET_NAME" "P3E_CPU0_PE2_SS_TXP<8>"
					( Origin gPackager )
				)
				( attribute "PNN" "P3E_CPU0_PE2_SS_TXP<8>"
					( Origin gPackager )
				)
				( objectStatus "P3E_CPU0_PE2_SS_TXP<8>" )
			)
			( signal "@baseboard_fab2_lib.baseboard_fab2(sch_1):p3e_cpu0_pe2_ss_txp(9)"
				( attribute "CDS_PHYS_NET_NAME" "P3E_CPU0_PE2_SS_TXP<9>"
					( Origin gPackager )
				)
				( attribute "PNN" "P3E_CPU0_PE2_SS_TXP<9>"
					( Origin gPackager )
				)
				( objectStatus "P3E_CPU0_PE2_SS_TXP<9>" )
			)
			( signal "@baseboard_fab2_lib.baseboard_fab2(sch_1):p3e_cpu0_pe2_ss_txp(10)"
				( attribute "CDS_PHYS_NET_NAME" "P3E_CPU0_PE2_SS_TXP<10>"
					( Origin gPackager )
				)
				( attribute "PNN" "P3E_CPU0_PE2_SS_TXP<10>"
					( Origin gPackager )
				)
				( objectStatus "P3E_CPU0_PE2_SS_TXP<10>" )
			)
			( signal "@baseboard_fab2_lib.baseboard_fab2(sch_1):p3e_cpu0_pe2_ss_txp(11)"
				( attribute "CDS_PHYS_NET_NAME" "P3E_CPU0_PE2_SS_TXP<11>"
					( Origin gPackager )
				)
				( attribute "PNN" "P3E_CPU0_PE2_SS_TXP<11>"
					( Origin gPackager )
				)
				( objectStatus "P3E_CPU0_PE2_SS_TXP<11>" )
			)
			( signal "@baseboard_fab2_lib.baseboard_fab2(sch_1):p3e_cpu0_pe2_ss_txp(12)"
				( attribute "CDS_PHYS_NET_NAME" "P3E_CPU0_PE2_SS_TXP<12>"
					( Origin gPackager )
				)
				( attribute "PNN" "P3E_CPU0_PE2_SS_TXP<12>"
					( Origin gPackager )
				)
				( objectStatus "P3E_CPU0_PE2_SS_TXP<12>" )
			)
			( signal "@baseboard_fab2_lib.baseboard_fab2(sch_1):p3e_cpu0_pe2_ss_txp(13)"
				( attribute "CDS_PHYS_NET_NAME" "P3E_CPU0_PE2_SS_TXP<13>"
					( Origin gPackager )
				)
				( attribute "PNN" "P3E_CPU0_PE2_SS_TXP<13>"
					( Origin gPackager )
				)
				( objectStatus "P3E_CPU0_PE2_SS_TXP<13>" )
			)
			( signal "@baseboard_fab2_lib.baseboard_fab2(sch_1):p3e_cpu0_pe2_ss_txp(14)"
				( attribute "CDS_PHYS_NET_NAME" "P3E_CPU0_PE2_SS_TXP<14>"
					( Origin gPackager )
				)
				( attribute "PNN" "P3E_CPU0_PE2_SS_TXP<14>"
					( Origin gPackager )
				)
				( objectStatus "P3E_CPU0_PE2_SS_TXP<14>" )
			)
			( signal "@baseboard_fab2_lib.baseboard_fab2(sch_1):p3e_cpu0_pe2_ss_txp(15)"
				( attribute "CDS_PHYS_NET_NAME" "P3E_CPU0_PE2_SS_TXP<15>"
					( Origin gPackager )
				)
				( attribute "PNN" "P3E_CPU0_PE2_SS_TXP<15>"
					( Origin gPackager )
				)
				( objectStatus "P3E_CPU0_PE2_SS_TXP<15>" )
			)
			( signal "@baseboard_fab2_lib.baseboard_fab2(sch_1):p3e_cpu0_pe3_ocp_rxn(0)"
				( attribute "CDS_PHYS_NET_NAME" "P3E_CPU0_PE3_OCP_RXN<0>"
					( Origin gPackager )
				)
				( attribute "PNN" "P3E_CPU0_PE3_OCP_RXN<0>"
					( Origin gPackager )
				)
				( objectStatus "P3E_CPU0_PE3_OCP_RXN<0>" )
			)
			( signal "@baseboard_fab2_lib.baseboard_fab2(sch_1):p3e_cpu0_pe3_ocp_rxn(1)"
				( attribute "CDS_PHYS_NET_NAME" "P3E_CPU0_PE3_OCP_RXN<1>"
					( Origin gPackager )
				)
				( attribute "PNN" "P3E_CPU0_PE3_OCP_RXN<1>"
					( Origin gPackager )
				)
				( objectStatus "P3E_CPU0_PE3_OCP_RXN<1>" )
			)
			( signal "@baseboard_fab2_lib.baseboard_fab2(sch_1):p3e_cpu0_pe3_ocp_rxn(2)"
				( attribute "CDS_PHYS_NET_NAME" "P3E_CPU0_PE3_OCP_RXN<2>"
					( Origin gPackager )
				)
				( attribute "PNN" "P3E_CPU0_PE3_OCP_RXN<2>"
					( Origin gPackager )
				)
				( objectStatus "P3E_CPU0_PE3_OCP_RXN<2>" )
			)
			( signal "@baseboard_fab2_lib.baseboard_fab2(sch_1):p3e_cpu0_pe3_ocp_rxn(3)"
				( attribute "CDS_PHYS_NET_NAME" "P3E_CPU0_PE3_OCP_RXN<3>"
					( Origin gPackager )
				)
				( attribute "PNN" "P3E_CPU0_PE3_OCP_RXN<3>"
					( Origin gPackager )
				)
				( objectStatus "P3E_CPU0_PE3_OCP_RXN<3>" )
			)
			( signal "@baseboard_fab2_lib.baseboard_fab2(sch_1):p3e_cpu0_pe3_ocp_rxn(4)"
				( attribute "CDS_PHYS_NET_NAME" "P3E_CPU0_PE3_OCP_RXN<4>"
					( Origin gPackager )
				)
				( attribute "PNN" "P3E_CPU0_PE3_OCP_RXN<4>"
					( Origin gPackager )
				)
				( objectStatus "P3E_CPU0_PE3_OCP_RXN<4>" )
			)
			( signal "@baseboard_fab2_lib.baseboard_fab2(sch_1):p3e_cpu0_pe3_ocp_rxn(5)"
				( attribute "CDS_PHYS_NET_NAME" "P3E_CPU0_PE3_OCP_RXN<5>"
					( Origin gPackager )
				)
				( attribute "PNN" "P3E_CPU0_PE3_OCP_RXN<5>"
					( Origin gPackager )
				)
				( objectStatus "P3E_CPU0_PE3_OCP_RXN<5>" )
			)
			( signal "@baseboard_fab2_lib.baseboard_fab2(sch_1):p3e_cpu0_pe3_ocp_rxn(6)"
				( attribute "CDS_PHYS_NET_NAME" "P3E_CPU0_PE3_OCP_RXN<6>"
					( Origin gPackager )
				)
				( attribute "PNN" "P3E_CPU0_PE3_OCP_RXN<6>"
					( Origin gPackager )
				)
				( objectStatus "P3E_CPU0_PE3_OCP_RXN<6>" )
			)
			( signal "@baseboard_fab2_lib.baseboard_fab2(sch_1):p3e_cpu0_pe3_ocp_rxn(7)"
				( attribute "CDS_PHYS_NET_NAME" "P3E_CPU0_PE3_OCP_RXN<7>"
					( Origin gPackager )
				)
				( attribute "PNN" "P3E_CPU0_PE3_OCP_RXN<7>"
					( Origin gPackager )
				)
				( objectStatus "P3E_CPU0_PE3_OCP_RXN<7>" )
			)
			( signal "@baseboard_fab2_lib.baseboard_fab2(sch_1):p3e_cpu0_pe3_ocp_rxn(8)"
				( attribute "CDS_PHYS_NET_NAME" "P3E_CPU0_PE3_OCP_RXN<8>"
					( Origin gPackager )
				)
				( attribute "PNN" "P3E_CPU0_PE3_OCP_RXN<8>"
					( Origin gPackager )
				)
				( objectStatus "P3E_CPU0_PE3_OCP_RXN<8>" )
			)
			( signal "@baseboard_fab2_lib.baseboard_fab2(sch_1):p3e_cpu0_pe3_ocp_rxn(9)"
				( attribute "CDS_PHYS_NET_NAME" "P3E_CPU0_PE3_OCP_RXN<9>"
					( Origin gPackager )
				)
				( attribute "PNN" "P3E_CPU0_PE3_OCP_RXN<9>"
					( Origin gPackager )
				)
				( objectStatus "P3E_CPU0_PE3_OCP_RXN<9>" )
			)
			( signal "@baseboard_fab2_lib.baseboard_fab2(sch_1):p3e_cpu0_pe3_ocp_rxn(10)"
				( attribute "CDS_PHYS_NET_NAME" "P3E_CPU0_PE3_OCP_RXN<10>"
					( Origin gPackager )
				)
				( attribute "PNN" "P3E_CPU0_PE3_OCP_RXN<10>"
					( Origin gPackager )
				)
				( objectStatus "P3E_CPU0_PE3_OCP_RXN<10>" )
			)
			( signal "@baseboard_fab2_lib.baseboard_fab2(sch_1):p3e_cpu0_pe3_ocp_rxn(11)"
				( attribute "CDS_PHYS_NET_NAME" "P3E_CPU0_PE3_OCP_RXN<11>"
					( Origin gPackager )
				)
				( attribute "PNN" "P3E_CPU0_PE3_OCP_RXN<11>"
					( Origin gPackager )
				)
				( objectStatus "P3E_CPU0_PE3_OCP_RXN<11>" )
			)
			( signal "@baseboard_fab2_lib.baseboard_fab2(sch_1):p3e_cpu0_pe3_ocp_rxn(12)"
				( attribute "CDS_PHYS_NET_NAME" "P3E_CPU0_PE3_OCP_RXN<12>"
					( Origin gPackager )
				)
				( attribute "PNN" "P3E_CPU0_PE3_OCP_RXN<12>"
					( Origin gPackager )
				)
				( objectStatus "P3E_CPU0_PE3_OCP_RXN<12>" )
			)
			( signal "@baseboard_fab2_lib.baseboard_fab2(sch_1):p3e_cpu0_pe3_ocp_rxn(13)"
				( attribute "CDS_PHYS_NET_NAME" "P3E_CPU0_PE3_OCP_RXN<13>"
					( Origin gPackager )
				)
				( attribute "PNN" "P3E_CPU0_PE3_OCP_RXN<13>"
					( Origin gPackager )
				)
				( objectStatus "P3E_CPU0_PE3_OCP_RXN<13>" )
			)
			( signal "@baseboard_fab2_lib.baseboard_fab2(sch_1):p3e_cpu0_pe3_ocp_rxn(14)"
				( attribute "CDS_PHYS_NET_NAME" "P3E_CPU0_PE3_OCP_RXN<14>"
					( Origin gPackager )
				)
				( attribute "PNN" "P3E_CPU0_PE3_OCP_RXN<14>"
					( Origin gPackager )
				)
				( objectStatus "P3E_CPU0_PE3_OCP_RXN<14>" )
			)
			( signal "@baseboard_fab2_lib.baseboard_fab2(sch_1):p3e_cpu0_pe3_ocp_rxn(15)"
				( attribute "CDS_PHYS_NET_NAME" "P3E_CPU0_PE3_OCP_RXN<15>"
					( Origin gPackager )
				)
				( attribute "PNN" "P3E_CPU0_PE3_OCP_RXN<15>"
					( Origin gPackager )
				)
				( objectStatus "P3E_CPU0_PE3_OCP_RXN<15>" )
			)
			( signal "@baseboard_fab2_lib.baseboard_fab2(sch_1):p3e_cpu0_pe3_ocp_rxp(0)"
				( attribute "CDS_PHYS_NET_NAME" "P3E_CPU0_PE3_OCP_RXP<0>"
					( Origin gPackager )
				)
				( attribute "PNN" "P3E_CPU0_PE3_OCP_RXP<0>"
					( Origin gPackager )
				)
				( objectStatus "P3E_CPU0_PE3_OCP_RXP<0>" )
			)
			( signal "@baseboard_fab2_lib.baseboard_fab2(sch_1):p3e_cpu0_pe3_ocp_rxp(1)"
				( attribute "CDS_PHYS_NET_NAME" "P3E_CPU0_PE3_OCP_RXP<1>"
					( Origin gPackager )
				)
				( attribute "PNN" "P3E_CPU0_PE3_OCP_RXP<1>"
					( Origin gPackager )
				)
				( objectStatus "P3E_CPU0_PE3_OCP_RXP<1>" )
			)
			( signal "@baseboard_fab2_lib.baseboard_fab2(sch_1):p3e_cpu0_pe3_ocp_rxp(2)"
				( attribute "CDS_PHYS_NET_NAME" "P3E_CPU0_PE3_OCP_RXP<2>"
					( Origin gPackager )
				)
				( attribute "PNN" "P3E_CPU0_PE3_OCP_RXP<2>"
					( Origin gPackager )
				)
				( objectStatus "P3E_CPU0_PE3_OCP_RXP<2>" )
			)
			( signal "@baseboard_fab2_lib.baseboard_fab2(sch_1):p3e_cpu0_pe3_ocp_rxp(3)"
				( attribute "CDS_PHYS_NET_NAME" "P3E_CPU0_PE3_OCP_RXP<3>"
					( Origin gPackager )
				)
				( attribute "PNN" "P3E_CPU0_PE3_OCP_RXP<3>"
					( Origin gPackager )
				)
				( objectStatus "P3E_CPU0_PE3_OCP_RXP<3>" )
			)
			( signal "@baseboard_fab2_lib.baseboard_fab2(sch_1):p3e_cpu0_pe3_ocp_rxp(4)"
				( attribute "CDS_PHYS_NET_NAME" "P3E_CPU0_PE3_OCP_RXP<4>"
					( Origin gPackager )
				)
				( attribute "PNN" "P3E_CPU0_PE3_OCP_RXP<4>"
					( Origin gPackager )
				)
				( objectStatus "P3E_CPU0_PE3_OCP_RXP<4>" )
			)
			( signal "@baseboard_fab2_lib.baseboard_fab2(sch_1):p3e_cpu0_pe3_ocp_rxp(5)"
				( attribute "CDS_PHYS_NET_NAME" "P3E_CPU0_PE3_OCP_RXP<5>"
					( Origin gPackager )
				)
				( attribute "PNN" "P3E_CPU0_PE3_OCP_RXP<5>"
					( Origin gPackager )
				)
				( objectStatus "P3E_CPU0_PE3_OCP_RXP<5>" )
			)
			( signal "@baseboard_fab2_lib.baseboard_fab2(sch_1):p3e_cpu0_pe3_ocp_rxp(6)"
				( attribute "CDS_PHYS_NET_NAME" "P3E_CPU0_PE3_OCP_RXP<6>"
					( Origin gPackager )
				)
				( attribute "PNN" "P3E_CPU0_PE3_OCP_RXP<6>"
					( Origin gPackager )
				)
				( objectStatus "P3E_CPU0_PE3_OCP_RXP<6>" )
			)
			( signal "@baseboard_fab2_lib.baseboard_fab2(sch_1):p3e_cpu0_pe3_ocp_rxp(7)"
				( attribute "CDS_PHYS_NET_NAME" "P3E_CPU0_PE3_OCP_RXP<7>"
					( Origin gPackager )
				)
				( attribute "PNN" "P3E_CPU0_PE3_OCP_RXP<7>"
					( Origin gPackager )
				)
				( objectStatus "P3E_CPU0_PE3_OCP_RXP<7>" )
			)
			( signal "@baseboard_fab2_lib.baseboard_fab2(sch_1):p3e_cpu0_pe3_ocp_rxp(8)"
				( attribute "CDS_PHYS_NET_NAME" "P3E_CPU0_PE3_OCP_RXP<8>"
					( Origin gPackager )
				)
				( attribute "PNN" "P3E_CPU0_PE3_OCP_RXP<8>"
					( Origin gPackager )
				)
				( objectStatus "P3E_CPU0_PE3_OCP_RXP<8>" )
			)
			( signal "@baseboard_fab2_lib.baseboard_fab2(sch_1):p3e_cpu0_pe3_ocp_rxp(9)"
				( attribute "CDS_PHYS_NET_NAME" "P3E_CPU0_PE3_OCP_RXP<9>"
					( Origin gPackager )
				)
				( attribute "PNN" "P3E_CPU0_PE3_OCP_RXP<9>"
					( Origin gPackager )
				)
				( objectStatus "P3E_CPU0_PE3_OCP_RXP<9>" )
			)
			( signal "@baseboard_fab2_lib.baseboard_fab2(sch_1):p3e_cpu0_pe3_ocp_rxp(10)"
				( attribute "CDS_PHYS_NET_NAME" "P3E_CPU0_PE3_OCP_RXP<10>"
					( Origin gPackager )
				)
				( attribute "PNN" "P3E_CPU0_PE3_OCP_RXP<10>"
					( Origin gPackager )
				)
				( objectStatus "P3E_CPU0_PE3_OCP_RXP<10>" )
			)
			( signal "@baseboard_fab2_lib.baseboard_fab2(sch_1):p3e_cpu0_pe3_ocp_rxp(11)"
				( attribute "CDS_PHYS_NET_NAME" "P3E_CPU0_PE3_OCP_RXP<11>"
					( Origin gPackager )
				)
				( attribute "PNN" "P3E_CPU0_PE3_OCP_RXP<11>"
					( Origin gPackager )
				)
				( objectStatus "P3E_CPU0_PE3_OCP_RXP<11>" )
			)
			( signal "@baseboard_fab2_lib.baseboard_fab2(sch_1):p3e_cpu0_pe3_ocp_rxp(12)"
				( attribute "CDS_PHYS_NET_NAME" "P3E_CPU0_PE3_OCP_RXP<12>"
					( Origin gPackager )
				)
				( attribute "PNN" "P3E_CPU0_PE3_OCP_RXP<12>"
					( Origin gPackager )
				)
				( objectStatus "P3E_CPU0_PE3_OCP_RXP<12>" )
			)
			( signal "@baseboard_fab2_lib.baseboard_fab2(sch_1):p3e_cpu0_pe3_ocp_rxp(13)"
				( attribute "CDS_PHYS_NET_NAME" "P3E_CPU0_PE3_OCP_RXP<13>"
					( Origin gPackager )
				)
				( attribute "PNN" "P3E_CPU0_PE3_OCP_RXP<13>"
					( Origin gPackager )
				)
				( objectStatus "P3E_CPU0_PE3_OCP_RXP<13>" )
			)
			( signal "@baseboard_fab2_lib.baseboard_fab2(sch_1):p3e_cpu0_pe3_ocp_rxp(14)"
				( attribute "CDS_PHYS_NET_NAME" "P3E_CPU0_PE3_OCP_RXP<14>"
					( Origin gPackager )
				)
				( attribute "PNN" "P3E_CPU0_PE3_OCP_RXP<14>"
					( Origin gPackager )
				)
				( objectStatus "P3E_CPU0_PE3_OCP_RXP<14>" )
			)
			( signal "@baseboard_fab2_lib.baseboard_fab2(sch_1):p3e_cpu0_pe3_ocp_rxp(15)"
				( attribute "CDS_PHYS_NET_NAME" "P3E_CPU0_PE3_OCP_RXP<15>"
					( Origin gPackager )
				)
				( attribute "PNN" "P3E_CPU0_PE3_OCP_RXP<15>"
					( Origin gPackager )
				)
				( objectStatus "P3E_CPU0_PE3_OCP_RXP<15>" )
			)
			( signal "@baseboard_fab2_lib.baseboard_fab2(sch_1):p3e_cpu0_pe3_ocp_txn(0)"
				( attribute "CDS_PHYS_NET_NAME" "P3E_CPU0_PE3_OCP_TXN<0>"
					( Origin gPackager )
				)
				( attribute "PNN" "P3E_CPU0_PE3_OCP_TXN<0>"
					( Origin gPackager )
				)
				( objectStatus "P3E_CPU0_PE3_OCP_TXN<0>" )
			)
			( signal "@baseboard_fab2_lib.baseboard_fab2(sch_1):p3e_cpu0_pe3_ocp_txn(1)"
				( attribute "CDS_PHYS_NET_NAME" "P3E_CPU0_PE3_OCP_TXN<1>"
					( Origin gPackager )
				)
				( attribute "PNN" "P3E_CPU0_PE3_OCP_TXN<1>"
					( Origin gPackager )
				)
				( objectStatus "P3E_CPU0_PE3_OCP_TXN<1>" )
			)
			( signal "@baseboard_fab2_lib.baseboard_fab2(sch_1):p3e_cpu0_pe3_ocp_txn(2)"
				( attribute "CDS_PHYS_NET_NAME" "P3E_CPU0_PE3_OCP_TXN<2>"
					( Origin gPackager )
				)
				( attribute "PNN" "P3E_CPU0_PE3_OCP_TXN<2>"
					( Origin gPackager )
				)
				( objectStatus "P3E_CPU0_PE3_OCP_TXN<2>" )
			)
			( signal "@baseboard_fab2_lib.baseboard_fab2(sch_1):p3e_cpu0_pe3_ocp_txn(3)"
				( attribute "CDS_PHYS_NET_NAME" "P3E_CPU0_PE3_OCP_TXN<3>"
					( Origin gPackager )
				)
				( attribute "PNN" "P3E_CPU0_PE3_OCP_TXN<3>"
					( Origin gPackager )
				)
				( objectStatus "P3E_CPU0_PE3_OCP_TXN<3>" )
			)
			( signal "@baseboard_fab2_lib.baseboard_fab2(sch_1):p3e_cpu0_pe3_ocp_txn(4)"
				( attribute "CDS_PHYS_NET_NAME" "P3E_CPU0_PE3_OCP_TXN<4>"
					( Origin gPackager )
				)
				( attribute "PNN" "P3E_CPU0_PE3_OCP_TXN<4>"
					( Origin gPackager )
				)
				( objectStatus "P3E_CPU0_PE3_OCP_TXN<4>" )
			)
			( signal "@baseboard_fab2_lib.baseboard_fab2(sch_1):p3e_cpu0_pe3_ocp_txn(5)"
				( attribute "CDS_PHYS_NET_NAME" "P3E_CPU0_PE3_OCP_TXN<5>"
					( Origin gPackager )
				)
				( attribute "PNN" "P3E_CPU0_PE3_OCP_TXN<5>"
					( Origin gPackager )
				)
				( objectStatus "P3E_CPU0_PE3_OCP_TXN<5>" )
			)
			( signal "@baseboard_fab2_lib.baseboard_fab2(sch_1):p3e_cpu0_pe3_ocp_txn(6)"
				( attribute "CDS_PHYS_NET_NAME" "P3E_CPU0_PE3_OCP_TXN<6>"
					( Origin gPackager )
				)
				( attribute "PNN" "P3E_CPU0_PE3_OCP_TXN<6>"
					( Origin gPackager )
				)
				( objectStatus "P3E_CPU0_PE3_OCP_TXN<6>" )
			)
			( signal "@baseboard_fab2_lib.baseboard_fab2(sch_1):p3e_cpu0_pe3_ocp_txn(7)"
				( attribute "CDS_PHYS_NET_NAME" "P3E_CPU0_PE3_OCP_TXN<7>"
					( Origin gPackager )
				)
				( attribute "PNN" "P3E_CPU0_PE3_OCP_TXN<7>"
					( Origin gPackager )
				)
				( objectStatus "P3E_CPU0_PE3_OCP_TXN<7>" )
			)
			( signal "@baseboard_fab2_lib.baseboard_fab2(sch_1):p3e_cpu0_pe3_ocp_txn(8)"
				( attribute "CDS_PHYS_NET_NAME" "P3E_CPU0_PE3_OCP_TXN<8>"
					( Origin gPackager )
				)
				( attribute "PNN" "P3E_CPU0_PE3_OCP_TXN<8>"
					( Origin gPackager )
				)
				( objectStatus "P3E_CPU0_PE3_OCP_TXN<8>" )
			)
			( signal "@baseboard_fab2_lib.baseboard_fab2(sch_1):p3e_cpu0_pe3_ocp_txn(9)"
				( attribute "CDS_PHYS_NET_NAME" "P3E_CPU0_PE3_OCP_TXN<9>"
					( Origin gPackager )
				)
				( attribute "PNN" "P3E_CPU0_PE3_OCP_TXN<9>"
					( Origin gPackager )
				)
				( objectStatus "P3E_CPU0_PE3_OCP_TXN<9>" )
			)
			( signal "@baseboard_fab2_lib.baseboard_fab2(sch_1):p3e_cpu0_pe3_ocp_txn(10)"
				( attribute "CDS_PHYS_NET_NAME" "P3E_CPU0_PE3_OCP_TXN<10>"
					( Origin gPackager )
				)
				( attribute "PNN" "P3E_CPU0_PE3_OCP_TXN<10>"
					( Origin gPackager )
				)
				( objectStatus "P3E_CPU0_PE3_OCP_TXN<10>" )
			)
			( signal "@baseboard_fab2_lib.baseboard_fab2(sch_1):p3e_cpu0_pe3_ocp_txn(11)"
				( attribute "CDS_PHYS_NET_NAME" "P3E_CPU0_PE3_OCP_TXN<11>"
					( Origin gPackager )
				)
				( attribute "PNN" "P3E_CPU0_PE3_OCP_TXN<11>"
					( Origin gPackager )
				)
				( objectStatus "P3E_CPU0_PE3_OCP_TXN<11>" )
			)
			( signal "@baseboard_fab2_lib.baseboard_fab2(sch_1):p3e_cpu0_pe3_ocp_txn(12)"
				( attribute "CDS_PHYS_NET_NAME" "P3E_CPU0_PE3_OCP_TXN<12>"
					( Origin gPackager )
				)
				( attribute "PNN" "P3E_CPU0_PE3_OCP_TXN<12>"
					( Origin gPackager )
				)
				( objectStatus "P3E_CPU0_PE3_OCP_TXN<12>" )
			)
			( signal "@baseboard_fab2_lib.baseboard_fab2(sch_1):p3e_cpu0_pe3_ocp_txn(13)"
				( attribute "CDS_PHYS_NET_NAME" "P3E_CPU0_PE3_OCP_TXN<13>"
					( Origin gPackager )
				)
				( attribute "PNN" "P3E_CPU0_PE3_OCP_TXN<13>"
					( Origin gPackager )
				)
				( objectStatus "P3E_CPU0_PE3_OCP_TXN<13>" )
			)
			( signal "@baseboard_fab2_lib.baseboard_fab2(sch_1):p3e_cpu0_pe3_ocp_txn(14)"
				( attribute "CDS_PHYS_NET_NAME" "P3E_CPU0_PE3_OCP_TXN<14>"
					( Origin gPackager )
				)
				( attribute "PNN" "P3E_CPU0_PE3_OCP_TXN<14>"
					( Origin gPackager )
				)
				( objectStatus "P3E_CPU0_PE3_OCP_TXN<14>" )
			)
			( signal "@baseboard_fab2_lib.baseboard_fab2(sch_1):p3e_cpu0_pe3_ocp_txn(15)"
				( attribute "CDS_PHYS_NET_NAME" "P3E_CPU0_PE3_OCP_TXN<15>"
					( Origin gPackager )
				)
				( attribute "PNN" "P3E_CPU0_PE3_OCP_TXN<15>"
					( Origin gPackager )
				)
				( objectStatus "P3E_CPU0_PE3_OCP_TXN<15>" )
			)
			( signal "@baseboard_fab2_lib.baseboard_fab2(sch_1):p3e_cpu0_pe3_ocp_txp(0)"
				( attribute "CDS_PHYS_NET_NAME" "P3E_CPU0_PE3_OCP_TXP<0>"
					( Origin gPackager )
				)
				( attribute "PNN" "P3E_CPU0_PE3_OCP_TXP<0>"
					( Origin gPackager )
				)
				( objectStatus "P3E_CPU0_PE3_OCP_TXP<0>" )
			)
			( signal "@baseboard_fab2_lib.baseboard_fab2(sch_1):p3e_cpu0_pe3_ocp_txp(1)"
				( attribute "CDS_PHYS_NET_NAME" "P3E_CPU0_PE3_OCP_TXP<1>"
					( Origin gPackager )
				)
				( attribute "PNN" "P3E_CPU0_PE3_OCP_TXP<1>"
					( Origin gPackager )
				)
				( objectStatus "P3E_CPU0_PE3_OCP_TXP<1>" )
			)
			( signal "@baseboard_fab2_lib.baseboard_fab2(sch_1):p3e_cpu0_pe3_ocp_txp(2)"
				( attribute "CDS_PHYS_NET_NAME" "P3E_CPU0_PE3_OCP_TXP<2>"
					( Origin gPackager )
				)
				( attribute "PNN" "P3E_CPU0_PE3_OCP_TXP<2>"
					( Origin gPackager )
				)
				( objectStatus "P3E_CPU0_PE3_OCP_TXP<2>" )
			)
			( signal "@baseboard_fab2_lib.baseboard_fab2(sch_1):p3e_cpu0_pe3_ocp_txp(3)"
				( attribute "CDS_PHYS_NET_NAME" "P3E_CPU0_PE3_OCP_TXP<3>"
					( Origin gPackager )
				)
				( attribute "PNN" "P3E_CPU0_PE3_OCP_TXP<3>"
					( Origin gPackager )
				)
				( objectStatus "P3E_CPU0_PE3_OCP_TXP<3>" )
			)
			( signal "@baseboard_fab2_lib.baseboard_fab2(sch_1):p3e_cpu0_pe3_ocp_txp(4)"
				( attribute "CDS_PHYS_NET_NAME" "P3E_CPU0_PE3_OCP_TXP<4>"
					( Origin gPackager )
				)
				( attribute "PNN" "P3E_CPU0_PE3_OCP_TXP<4>"
					( Origin gPackager )
				)
				( objectStatus "P3E_CPU0_PE3_OCP_TXP<4>" )
			)
			( signal "@baseboard_fab2_lib.baseboard_fab2(sch_1):p3e_cpu0_pe3_ocp_txp(5)"
				( attribute "CDS_PHYS_NET_NAME" "P3E_CPU0_PE3_OCP_TXP<5>"
					( Origin gPackager )
				)
				( attribute "PNN" "P3E_CPU0_PE3_OCP_TXP<5>"
					( Origin gPackager )
				)
				( objectStatus "P3E_CPU0_PE3_OCP_TXP<5>" )
			)
			( signal "@baseboard_fab2_lib.baseboard_fab2(sch_1):p3e_cpu0_pe3_ocp_txp(6)"
				( attribute "CDS_PHYS_NET_NAME" "P3E_CPU0_PE3_OCP_TXP<6>"
					( Origin gPackager )
				)
				( attribute "PNN" "P3E_CPU0_PE3_OCP_TXP<6>"
					( Origin gPackager )
				)
				( objectStatus "P3E_CPU0_PE3_OCP_TXP<6>" )
			)
			( signal "@baseboard_fab2_lib.baseboard_fab2(sch_1):p3e_cpu0_pe3_ocp_txp(7)"
				( attribute "CDS_PHYS_NET_NAME" "P3E_CPU0_PE3_OCP_TXP<7>"
					( Origin gPackager )
				)
				( attribute "PNN" "P3E_CPU0_PE3_OCP_TXP<7>"
					( Origin gPackager )
				)
				( objectStatus "P3E_CPU0_PE3_OCP_TXP<7>" )
			)
			( signal "@baseboard_fab2_lib.baseboard_fab2(sch_1):p3e_cpu0_pe3_ocp_txp(8)"
				( attribute "CDS_PHYS_NET_NAME" "P3E_CPU0_PE3_OCP_TXP<8>"
					( Origin gPackager )
				)
				( attribute "PNN" "P3E_CPU0_PE3_OCP_TXP<8>"
					( Origin gPackager )
				)
				( objectStatus "P3E_CPU0_PE3_OCP_TXP<8>" )
			)
			( signal "@baseboard_fab2_lib.baseboard_fab2(sch_1):p3e_cpu0_pe3_ocp_txp(9)"
				( attribute "CDS_PHYS_NET_NAME" "P3E_CPU0_PE3_OCP_TXP<9>"
					( Origin gPackager )
				)
				( attribute "PNN" "P3E_CPU0_PE3_OCP_TXP<9>"
					( Origin gPackager )
				)
				( objectStatus "P3E_CPU0_PE3_OCP_TXP<9>" )
			)
			( signal "@baseboard_fab2_lib.baseboard_fab2(sch_1):p3e_cpu0_pe3_ocp_txp(10)"
				( attribute "CDS_PHYS_NET_NAME" "P3E_CPU0_PE3_OCP_TXP<10>"
					( Origin gPackager )
				)
				( attribute "PNN" "P3E_CPU0_PE3_OCP_TXP<10>"
					( Origin gPackager )
				)
				( objectStatus "P3E_CPU0_PE3_OCP_TXP<10>" )
			)
			( signal "@baseboard_fab2_lib.baseboard_fab2(sch_1):p3e_cpu0_pe3_ocp_txp(11)"
				( attribute "CDS_PHYS_NET_NAME" "P3E_CPU0_PE3_OCP_TXP<11>"
					( Origin gPackager )
				)
				( attribute "PNN" "P3E_CPU0_PE3_OCP_TXP<11>"
					( Origin gPackager )
				)
				( objectStatus "P3E_CPU0_PE3_OCP_TXP<11>" )
			)
			( signal "@baseboard_fab2_lib.baseboard_fab2(sch_1):p3e_cpu0_pe3_ocp_txp(12)"
				( attribute "CDS_PHYS_NET_NAME" "P3E_CPU0_PE3_OCP_TXP<12>"
					( Origin gPackager )
				)
				( attribute "PNN" "P3E_CPU0_PE3_OCP_TXP<12>"
					( Origin gPackager )
				)
				( objectStatus "P3E_CPU0_PE3_OCP_TXP<12>" )
			)
			( signal "@baseboard_fab2_lib.baseboard_fab2(sch_1):p3e_cpu0_pe3_ocp_txp(13)"
				( attribute "CDS_PHYS_NET_NAME" "P3E_CPU0_PE3_OCP_TXP<13>"
					( Origin gPackager )
				)
				( attribute "PNN" "P3E_CPU0_PE3_OCP_TXP<13>"
					( Origin gPackager )
				)
				( objectStatus "P3E_CPU0_PE3_OCP_TXP<13>" )
			)
			( signal "@baseboard_fab2_lib.baseboard_fab2(sch_1):p3e_cpu0_pe3_ocp_txp(14)"
				( attribute "CDS_PHYS_NET_NAME" "P3E_CPU0_PE3_OCP_TXP<14>"
					( Origin gPackager )
				)
				( attribute "PNN" "P3E_CPU0_PE3_OCP_TXP<14>"
					( Origin gPackager )
				)
				( objectStatus "P3E_CPU0_PE3_OCP_TXP<14>" )
			)
			( signal "@baseboard_fab2_lib.baseboard_fab2(sch_1):p3e_cpu0_pe3_ocp_txp(15)"
				( attribute "CDS_PHYS_NET_NAME" "P3E_CPU0_PE3_OCP_TXP<15>"
					( Origin gPackager )
				)
				( attribute "PNN" "P3E_CPU0_PE3_OCP_TXP<15>"
					( Origin gPackager )
				)
				( objectStatus "P3E_CPU0_PE3_OCP_TXP<15>" )
			)
			( signal "@baseboard_fab2_lib.baseboard_fab2(sch_1):upi_cpu0_cpu1_p0p0_dn(0)"
				( attribute "CDS_PHYS_NET_NAME" "UPI_CPU0_CPU1_P0P0_DN<0>"
					( Origin gPackager )
				)
				( attribute "PNN" "UPI_CPU0_CPU1_P0P0_DN<0>"
					( Origin gPackager )
				)
				( objectStatus "UPI_CPU0_CPU1_P0P0_DN<0>" )
			)
			( signal "@baseboard_fab2_lib.baseboard_fab2(sch_1):upi_cpu0_cpu1_p0p0_dn(1)"
				( attribute "CDS_PHYS_NET_NAME" "UPI_CPU0_CPU1_P0P0_DN<1>"
					( Origin gPackager )
				)
				( attribute "PNN" "UPI_CPU0_CPU1_P0P0_DN<1>"
					( Origin gPackager )
				)
				( objectStatus "UPI_CPU0_CPU1_P0P0_DN<1>" )
			)
			( signal "@baseboard_fab2_lib.baseboard_fab2(sch_1):upi_cpu0_cpu1_p0p0_dn(2)"
				( attribute "CDS_PHYS_NET_NAME" "UPI_CPU0_CPU1_P0P0_DN<2>"
					( Origin gPackager )
				)
				( attribute "PNN" "UPI_CPU0_CPU1_P0P0_DN<2>"
					( Origin gPackager )
				)
				( objectStatus "UPI_CPU0_CPU1_P0P0_DN<2>" )
			)
			( signal "@baseboard_fab2_lib.baseboard_fab2(sch_1):upi_cpu0_cpu1_p0p0_dn(3)"
				( attribute "CDS_PHYS_NET_NAME" "UPI_CPU0_CPU1_P0P0_DN<3>"
					( Origin gPackager )
				)
				( attribute "PNN" "UPI_CPU0_CPU1_P0P0_DN<3>"
					( Origin gPackager )
				)
				( objectStatus "UPI_CPU0_CPU1_P0P0_DN<3>" )
			)
			( signal "@baseboard_fab2_lib.baseboard_fab2(sch_1):upi_cpu0_cpu1_p0p0_dn(4)"
				( attribute "CDS_PHYS_NET_NAME" "UPI_CPU0_CPU1_P0P0_DN<4>"
					( Origin gPackager )
				)
				( attribute "PNN" "UPI_CPU0_CPU1_P0P0_DN<4>"
					( Origin gPackager )
				)
				( objectStatus "UPI_CPU0_CPU1_P0P0_DN<4>" )
			)
			( signal "@baseboard_fab2_lib.baseboard_fab2(sch_1):upi_cpu0_cpu1_p0p0_dn(5)"
				( attribute "CDS_PHYS_NET_NAME" "UPI_CPU0_CPU1_P0P0_DN<5>"
					( Origin gPackager )
				)
				( attribute "PNN" "UPI_CPU0_CPU1_P0P0_DN<5>"
					( Origin gPackager )
				)
				( objectStatus "UPI_CPU0_CPU1_P0P0_DN<5>" )
			)
			( signal "@baseboard_fab2_lib.baseboard_fab2(sch_1):upi_cpu0_cpu1_p0p0_dn(6)"
				( attribute "CDS_PHYS_NET_NAME" "UPI_CPU0_CPU1_P0P0_DN<6>"
					( Origin gPackager )
				)
				( attribute "PNN" "UPI_CPU0_CPU1_P0P0_DN<6>"
					( Origin gPackager )
				)
				( objectStatus "UPI_CPU0_CPU1_P0P0_DN<6>" )
			)
			( signal "@baseboard_fab2_lib.baseboard_fab2(sch_1):upi_cpu0_cpu1_p0p0_dn(7)"
				( attribute "CDS_PHYS_NET_NAME" "UPI_CPU0_CPU1_P0P0_DN<7>"
					( Origin gPackager )
				)
				( attribute "PNN" "UPI_CPU0_CPU1_P0P0_DN<7>"
					( Origin gPackager )
				)
				( objectStatus "UPI_CPU0_CPU1_P0P0_DN<7>" )
			)
			( signal "@baseboard_fab2_lib.baseboard_fab2(sch_1):upi_cpu0_cpu1_p0p0_dn(8)"
				( attribute "CDS_PHYS_NET_NAME" "UPI_CPU0_CPU1_P0P0_DN<8>"
					( Origin gPackager )
				)
				( attribute "PNN" "UPI_CPU0_CPU1_P0P0_DN<8>"
					( Origin gPackager )
				)
				( objectStatus "UPI_CPU0_CPU1_P0P0_DN<8>" )
			)
			( signal "@baseboard_fab2_lib.baseboard_fab2(sch_1):upi_cpu0_cpu1_p0p0_dn(9)"
				( attribute "CDS_PHYS_NET_NAME" "UPI_CPU0_CPU1_P0P0_DN<9>"
					( Origin gPackager )
				)
				( attribute "PNN" "UPI_CPU0_CPU1_P0P0_DN<9>"
					( Origin gPackager )
				)
				( objectStatus "UPI_CPU0_CPU1_P0P0_DN<9>" )
			)
			( signal "@baseboard_fab2_lib.baseboard_fab2(sch_1):upi_cpu0_cpu1_p0p0_dn(10)"
				( attribute "CDS_PHYS_NET_NAME" "UPI_CPU0_CPU1_P0P0_DN<10>"
					( Origin gPackager )
				)
				( attribute "PNN" "UPI_CPU0_CPU1_P0P0_DN<10>"
					( Origin gPackager )
				)
				( objectStatus "UPI_CPU0_CPU1_P0P0_DN<10>" )
			)
			( signal "@baseboard_fab2_lib.baseboard_fab2(sch_1):upi_cpu0_cpu1_p0p0_dn(11)"
				( attribute "CDS_PHYS_NET_NAME" "UPI_CPU0_CPU1_P0P0_DN<11>"
					( Origin gPackager )
				)
				( attribute "PNN" "UPI_CPU0_CPU1_P0P0_DN<11>"
					( Origin gPackager )
				)
				( objectStatus "UPI_CPU0_CPU1_P0P0_DN<11>" )
			)
			( signal "@baseboard_fab2_lib.baseboard_fab2(sch_1):upi_cpu0_cpu1_p0p0_dn(12)"
				( attribute "CDS_PHYS_NET_NAME" "UPI_CPU0_CPU1_P0P0_DN<12>"
					( Origin gPackager )
				)
				( attribute "PNN" "UPI_CPU0_CPU1_P0P0_DN<12>"
					( Origin gPackager )
				)
				( objectStatus "UPI_CPU0_CPU1_P0P0_DN<12>" )
			)
			( signal "@baseboard_fab2_lib.baseboard_fab2(sch_1):upi_cpu0_cpu1_p0p0_dn(13)"
				( attribute "CDS_PHYS_NET_NAME" "UPI_CPU0_CPU1_P0P0_DN<13>"
					( Origin gPackager )
				)
				( attribute "PNN" "UPI_CPU0_CPU1_P0P0_DN<13>"
					( Origin gPackager )
				)
				( objectStatus "UPI_CPU0_CPU1_P0P0_DN<13>" )
			)
			( signal "@baseboard_fab2_lib.baseboard_fab2(sch_1):upi_cpu0_cpu1_p0p0_dn(14)"
				( attribute "CDS_PHYS_NET_NAME" "UPI_CPU0_CPU1_P0P0_DN<14>"
					( Origin gPackager )
				)
				( attribute "PNN" "UPI_CPU0_CPU1_P0P0_DN<14>"
					( Origin gPackager )
				)
				( objectStatus "UPI_CPU0_CPU1_P0P0_DN<14>" )
			)
			( signal "@baseboard_fab2_lib.baseboard_fab2(sch_1):upi_cpu0_cpu1_p0p0_dn(15)"
				( attribute "CDS_PHYS_NET_NAME" "UPI_CPU0_CPU1_P0P0_DN<15>"
					( Origin gPackager )
				)
				( attribute "PNN" "UPI_CPU0_CPU1_P0P0_DN<15>"
					( Origin gPackager )
				)
				( objectStatus "UPI_CPU0_CPU1_P0P0_DN<15>" )
			)
			( signal "@baseboard_fab2_lib.baseboard_fab2(sch_1):upi_cpu0_cpu1_p0p0_dn(16)"
				( attribute "CDS_PHYS_NET_NAME" "UPI_CPU0_CPU1_P0P0_DN<16>"
					( Origin gPackager )
				)
				( attribute "PNN" "UPI_CPU0_CPU1_P0P0_DN<16>"
					( Origin gPackager )
				)
				( objectStatus "UPI_CPU0_CPU1_P0P0_DN<16>" )
			)
			( signal "@baseboard_fab2_lib.baseboard_fab2(sch_1):upi_cpu0_cpu1_p0p0_dn(17)"
				( attribute "CDS_PHYS_NET_NAME" "UPI_CPU0_CPU1_P0P0_DN<17>"
					( Origin gPackager )
				)
				( attribute "PNN" "UPI_CPU0_CPU1_P0P0_DN<17>"
					( Origin gPackager )
				)
				( objectStatus "UPI_CPU0_CPU1_P0P0_DN<17>" )
			)
			( signal "@baseboard_fab2_lib.baseboard_fab2(sch_1):upi_cpu0_cpu1_p0p0_dn(18)"
				( attribute "CDS_PHYS_NET_NAME" "UPI_CPU0_CPU1_P0P0_DN<18>"
					( Origin gPackager )
				)
				( attribute "PNN" "UPI_CPU0_CPU1_P0P0_DN<18>"
					( Origin gPackager )
				)
				( objectStatus "UPI_CPU0_CPU1_P0P0_DN<18>" )
			)
			( signal "@baseboard_fab2_lib.baseboard_fab2(sch_1):upi_cpu0_cpu1_p0p0_dn(19)"
				( attribute "CDS_PHYS_NET_NAME" "UPI_CPU0_CPU1_P0P0_DN<19>"
					( Origin gPackager )
				)
				( attribute "PNN" "UPI_CPU0_CPU1_P0P0_DN<19>"
					( Origin gPackager )
				)
				( objectStatus "UPI_CPU0_CPU1_P0P0_DN<19>" )
			)
			( signal "@baseboard_fab2_lib.baseboard_fab2(sch_1):upi_cpu0_cpu1_p0p0_dp(0)"
				( attribute "CDS_PHYS_NET_NAME" "UPI_CPU0_CPU1_P0P0_DP<0>"
					( Origin gPackager )
				)
				( attribute "PNN" "UPI_CPU0_CPU1_P0P0_DP<0>"
					( Origin gPackager )
				)
				( objectStatus "UPI_CPU0_CPU1_P0P0_DP<0>" )
			)
			( signal "@baseboard_fab2_lib.baseboard_fab2(sch_1):upi_cpu0_cpu1_p0p0_dp(1)"
				( attribute "CDS_PHYS_NET_NAME" "UPI_CPU0_CPU1_P0P0_DP<1>"
					( Origin gPackager )
				)
				( attribute "PNN" "UPI_CPU0_CPU1_P0P0_DP<1>"
					( Origin gPackager )
				)
				( objectStatus "UPI_CPU0_CPU1_P0P0_DP<1>" )
			)
			( signal "@baseboard_fab2_lib.baseboard_fab2(sch_1):upi_cpu0_cpu1_p0p0_dp(2)"
				( attribute "CDS_PHYS_NET_NAME" "UPI_CPU0_CPU1_P0P0_DP<2>"
					( Origin gPackager )
				)
				( attribute "PNN" "UPI_CPU0_CPU1_P0P0_DP<2>"
					( Origin gPackager )
				)
				( objectStatus "UPI_CPU0_CPU1_P0P0_DP<2>" )
			)
			( signal "@baseboard_fab2_lib.baseboard_fab2(sch_1):upi_cpu0_cpu1_p0p0_dp(3)"
				( attribute "CDS_PHYS_NET_NAME" "UPI_CPU0_CPU1_P0P0_DP<3>"
					( Origin gPackager )
				)
				( attribute "PNN" "UPI_CPU0_CPU1_P0P0_DP<3>"
					( Origin gPackager )
				)
				( objectStatus "UPI_CPU0_CPU1_P0P0_DP<3>" )
			)
			( signal "@baseboard_fab2_lib.baseboard_fab2(sch_1):upi_cpu0_cpu1_p0p0_dp(4)"
				( attribute "CDS_PHYS_NET_NAME" "UPI_CPU0_CPU1_P0P0_DP<4>"
					( Origin gPackager )
				)
				( attribute "PNN" "UPI_CPU0_CPU1_P0P0_DP<4>"
					( Origin gPackager )
				)
				( objectStatus "UPI_CPU0_CPU1_P0P0_DP<4>" )
			)
			( signal "@baseboard_fab2_lib.baseboard_fab2(sch_1):upi_cpu0_cpu1_p0p0_dp(5)"
				( attribute "CDS_PHYS_NET_NAME" "UPI_CPU0_CPU1_P0P0_DP<5>"
					( Origin gPackager )
				)
				( attribute "PNN" "UPI_CPU0_CPU1_P0P0_DP<5>"
					( Origin gPackager )
				)
				( objectStatus "UPI_CPU0_CPU1_P0P0_DP<5>" )
			)
			( signal "@baseboard_fab2_lib.baseboard_fab2(sch_1):upi_cpu0_cpu1_p0p0_dp(6)"
				( attribute "CDS_PHYS_NET_NAME" "UPI_CPU0_CPU1_P0P0_DP<6>"
					( Origin gPackager )
				)
				( attribute "PNN" "UPI_CPU0_CPU1_P0P0_DP<6>"
					( Origin gPackager )
				)
				( objectStatus "UPI_CPU0_CPU1_P0P0_DP<6>" )
			)
			( signal "@baseboard_fab2_lib.baseboard_fab2(sch_1):upi_cpu0_cpu1_p0p0_dp(7)"
				( attribute "CDS_PHYS_NET_NAME" "UPI_CPU0_CPU1_P0P0_DP<7>"
					( Origin gPackager )
				)
				( attribute "PNN" "UPI_CPU0_CPU1_P0P0_DP<7>"
					( Origin gPackager )
				)
				( objectStatus "UPI_CPU0_CPU1_P0P0_DP<7>" )
			)
			( signal "@baseboard_fab2_lib.baseboard_fab2(sch_1):upi_cpu0_cpu1_p0p0_dp(8)"
				( attribute "CDS_PHYS_NET_NAME" "UPI_CPU0_CPU1_P0P0_DP<8>"
					( Origin gPackager )
				)
				( attribute "PNN" "UPI_CPU0_CPU1_P0P0_DP<8>"
					( Origin gPackager )
				)
				( objectStatus "UPI_CPU0_CPU1_P0P0_DP<8>" )
			)
			( signal "@baseboard_fab2_lib.baseboard_fab2(sch_1):upi_cpu0_cpu1_p0p0_dp(9)"
				( attribute "CDS_PHYS_NET_NAME" "UPI_CPU0_CPU1_P0P0_DP<9>"
					( Origin gPackager )
				)
				( attribute "PNN" "UPI_CPU0_CPU1_P0P0_DP<9>"
					( Origin gPackager )
				)
				( objectStatus "UPI_CPU0_CPU1_P0P0_DP<9>" )
			)
			( signal "@baseboard_fab2_lib.baseboard_fab2(sch_1):upi_cpu0_cpu1_p0p0_dp(10)"
				( attribute "CDS_PHYS_NET_NAME" "UPI_CPU0_CPU1_P0P0_DP<10>"
					( Origin gPackager )
				)
				( attribute "PNN" "UPI_CPU0_CPU1_P0P0_DP<10>"
					( Origin gPackager )
				)
				( objectStatus "UPI_CPU0_CPU1_P0P0_DP<10>" )
			)
			( signal "@baseboard_fab2_lib.baseboard_fab2(sch_1):upi_cpu0_cpu1_p0p0_dp(11)"
				( attribute "CDS_PHYS_NET_NAME" "UPI_CPU0_CPU1_P0P0_DP<11>"
					( Origin gPackager )
				)
				( attribute "PNN" "UPI_CPU0_CPU1_P0P0_DP<11>"
					( Origin gPackager )
				)
				( objectStatus "UPI_CPU0_CPU1_P0P0_DP<11>" )
			)
			( signal "@baseboard_fab2_lib.baseboard_fab2(sch_1):upi_cpu0_cpu1_p0p0_dp(12)"
				( attribute "CDS_PHYS_NET_NAME" "UPI_CPU0_CPU1_P0P0_DP<12>"
					( Origin gPackager )
				)
				( attribute "PNN" "UPI_CPU0_CPU1_P0P0_DP<12>"
					( Origin gPackager )
				)
				( objectStatus "UPI_CPU0_CPU1_P0P0_DP<12>" )
			)
			( signal "@baseboard_fab2_lib.baseboard_fab2(sch_1):upi_cpu0_cpu1_p0p0_dp(13)"
				( attribute "CDS_PHYS_NET_NAME" "UPI_CPU0_CPU1_P0P0_DP<13>"
					( Origin gPackager )
				)
				( attribute "PNN" "UPI_CPU0_CPU1_P0P0_DP<13>"
					( Origin gPackager )
				)
				( objectStatus "UPI_CPU0_CPU1_P0P0_DP<13>" )
			)
			( signal "@baseboard_fab2_lib.baseboard_fab2(sch_1):upi_cpu0_cpu1_p0p0_dp(14)"
				( attribute "CDS_PHYS_NET_NAME" "UPI_CPU0_CPU1_P0P0_DP<14>"
					( Origin gPackager )
				)
				( attribute "PNN" "UPI_CPU0_CPU1_P0P0_DP<14>"
					( Origin gPackager )
				)
				( objectStatus "UPI_CPU0_CPU1_P0P0_DP<14>" )
			)
			( signal "@baseboard_fab2_lib.baseboard_fab2(sch_1):upi_cpu0_cpu1_p0p0_dp(15)"
				( attribute "CDS_PHYS_NET_NAME" "UPI_CPU0_CPU1_P0P0_DP<15>"
					( Origin gPackager )
				)
				( attribute "PNN" "UPI_CPU0_CPU1_P0P0_DP<15>"
					( Origin gPackager )
				)
				( objectStatus "UPI_CPU0_CPU1_P0P0_DP<15>" )
			)
			( signal "@baseboard_fab2_lib.baseboard_fab2(sch_1):upi_cpu0_cpu1_p0p0_dp(16)"
				( attribute "CDS_PHYS_NET_NAME" "UPI_CPU0_CPU1_P0P0_DP<16>"
					( Origin gPackager )
				)
				( attribute "PNN" "UPI_CPU0_CPU1_P0P0_DP<16>"
					( Origin gPackager )
				)
				( objectStatus "UPI_CPU0_CPU1_P0P0_DP<16>" )
			)
			( signal "@baseboard_fab2_lib.baseboard_fab2(sch_1):upi_cpu0_cpu1_p0p0_dp(17)"
				( attribute "CDS_PHYS_NET_NAME" "UPI_CPU0_CPU1_P0P0_DP<17>"
					( Origin gPackager )
				)
				( attribute "PNN" "UPI_CPU0_CPU1_P0P0_DP<17>"
					( Origin gPackager )
				)
				( objectStatus "UPI_CPU0_CPU1_P0P0_DP<17>" )
			)
			( signal "@baseboard_fab2_lib.baseboard_fab2(sch_1):upi_cpu0_cpu1_p0p0_dp(18)"
				( attribute "CDS_PHYS_NET_NAME" "UPI_CPU0_CPU1_P0P0_DP<18>"
					( Origin gPackager )
				)
				( attribute "PNN" "UPI_CPU0_CPU1_P0P0_DP<18>"
					( Origin gPackager )
				)
				( objectStatus "UPI_CPU0_CPU1_P0P0_DP<18>" )
			)
			( signal "@baseboard_fab2_lib.baseboard_fab2(sch_1):upi_cpu0_cpu1_p0p0_dp(19)"
				( attribute "CDS_PHYS_NET_NAME" "UPI_CPU0_CPU1_P0P0_DP<19>"
					( Origin gPackager )
				)
				( attribute "PNN" "UPI_CPU0_CPU1_P0P0_DP<19>"
					( Origin gPackager )
				)
				( objectStatus "UPI_CPU0_CPU1_P0P0_DP<19>" )
			)
			( signal "@baseboard_fab2_lib.baseboard_fab2(sch_1):upi_cpu1_cpu0_p0p0_dn(0)"
				( attribute "CDS_PHYS_NET_NAME" "UPI_CPU1_CPU0_P0P0_DN<0>"
					( Origin gPackager )
				)
				( attribute "PNN" "UPI_CPU1_CPU0_P0P0_DN<0>"
					( Origin gPackager )
				)
				( objectStatus "UPI_CPU1_CPU0_P0P0_DN<0>" )
			)
			( signal "@baseboard_fab2_lib.baseboard_fab2(sch_1):upi_cpu1_cpu0_p0p0_dn(1)"
				( attribute "CDS_PHYS_NET_NAME" "UPI_CPU1_CPU0_P0P0_DN<1>"
					( Origin gPackager )
				)
				( attribute "PNN" "UPI_CPU1_CPU0_P0P0_DN<1>"
					( Origin gPackager )
				)
				( objectStatus "UPI_CPU1_CPU0_P0P0_DN<1>" )
			)
			( signal "@baseboard_fab2_lib.baseboard_fab2(sch_1):upi_cpu1_cpu0_p0p0_dn(2)"
				( attribute "CDS_PHYS_NET_NAME" "UPI_CPU1_CPU0_P0P0_DN<2>"
					( Origin gPackager )
				)
				( attribute "PNN" "UPI_CPU1_CPU0_P0P0_DN<2>"
					( Origin gPackager )
				)
				( objectStatus "UPI_CPU1_CPU0_P0P0_DN<2>" )
			)
			( signal "@baseboard_fab2_lib.baseboard_fab2(sch_1):upi_cpu1_cpu0_p0p0_dn(3)"
				( attribute "CDS_PHYS_NET_NAME" "UPI_CPU1_CPU0_P0P0_DN<3>"
					( Origin gPackager )
				)
				( attribute "PNN" "UPI_CPU1_CPU0_P0P0_DN<3>"
					( Origin gPackager )
				)
				( objectStatus "UPI_CPU1_CPU0_P0P0_DN<3>" )
			)
			( signal "@baseboard_fab2_lib.baseboard_fab2(sch_1):upi_cpu1_cpu0_p0p0_dn(4)"
				( attribute "CDS_PHYS_NET_NAME" "UPI_CPU1_CPU0_P0P0_DN<4>"
					( Origin gPackager )
				)
				( attribute "PNN" "UPI_CPU1_CPU0_P0P0_DN<4>"
					( Origin gPackager )
				)
				( objectStatus "UPI_CPU1_CPU0_P0P0_DN<4>" )
			)
			( signal "@baseboard_fab2_lib.baseboard_fab2(sch_1):upi_cpu1_cpu0_p0p0_dn(5)"
				( attribute "CDS_PHYS_NET_NAME" "UPI_CPU1_CPU0_P0P0_DN<5>"
					( Origin gPackager )
				)
				( attribute "PNN" "UPI_CPU1_CPU0_P0P0_DN<5>"
					( Origin gPackager )
				)
				( objectStatus "UPI_CPU1_CPU0_P0P0_DN<5>" )
			)
			( signal "@baseboard_fab2_lib.baseboard_fab2(sch_1):upi_cpu1_cpu0_p0p0_dn(6)"
				( attribute "CDS_PHYS_NET_NAME" "UPI_CPU1_CPU0_P0P0_DN<6>"
					( Origin gPackager )
				)
				( attribute "PNN" "UPI_CPU1_CPU0_P0P0_DN<6>"
					( Origin gPackager )
				)
				( objectStatus "UPI_CPU1_CPU0_P0P0_DN<6>" )
			)
			( signal "@baseboard_fab2_lib.baseboard_fab2(sch_1):upi_cpu1_cpu0_p0p0_dn(7)"
				( attribute "CDS_PHYS_NET_NAME" "UPI_CPU1_CPU0_P0P0_DN<7>"
					( Origin gPackager )
				)
				( attribute "PNN" "UPI_CPU1_CPU0_P0P0_DN<7>"
					( Origin gPackager )
				)
				( objectStatus "UPI_CPU1_CPU0_P0P0_DN<7>" )
			)
			( signal "@baseboard_fab2_lib.baseboard_fab2(sch_1):upi_cpu1_cpu0_p0p0_dn(8)"
				( attribute "CDS_PHYS_NET_NAME" "UPI_CPU1_CPU0_P0P0_DN<8>"
					( Origin gPackager )
				)
				( attribute "PNN" "UPI_CPU1_CPU0_P0P0_DN<8>"
					( Origin gPackager )
				)
				( objectStatus "UPI_CPU1_CPU0_P0P0_DN<8>" )
			)
			( signal "@baseboard_fab2_lib.baseboard_fab2(sch_1):upi_cpu1_cpu0_p0p0_dn(9)"
				( attribute "CDS_PHYS_NET_NAME" "UPI_CPU1_CPU0_P0P0_DN<9>"
					( Origin gPackager )
				)
				( attribute "PNN" "UPI_CPU1_CPU0_P0P0_DN<9>"
					( Origin gPackager )
				)
				( objectStatus "UPI_CPU1_CPU0_P0P0_DN<9>" )
			)
			( signal "@baseboard_fab2_lib.baseboard_fab2(sch_1):upi_cpu1_cpu0_p0p0_dn(10)"
				( attribute "CDS_PHYS_NET_NAME" "UPI_CPU1_CPU0_P0P0_DN<10>"
					( Origin gPackager )
				)
				( attribute "PNN" "UPI_CPU1_CPU0_P0P0_DN<10>"
					( Origin gPackager )
				)
				( objectStatus "UPI_CPU1_CPU0_P0P0_DN<10>" )
			)
			( signal "@baseboard_fab2_lib.baseboard_fab2(sch_1):upi_cpu1_cpu0_p0p0_dn(11)"
				( attribute "CDS_PHYS_NET_NAME" "UPI_CPU1_CPU0_P0P0_DN<11>"
					( Origin gPackager )
				)
				( attribute "PNN" "UPI_CPU1_CPU0_P0P0_DN<11>"
					( Origin gPackager )
				)
				( objectStatus "UPI_CPU1_CPU0_P0P0_DN<11>" )
			)
			( signal "@baseboard_fab2_lib.baseboard_fab2(sch_1):upi_cpu1_cpu0_p0p0_dn(12)"
				( attribute "CDS_PHYS_NET_NAME" "UPI_CPU1_CPU0_P0P0_DN<12>"
					( Origin gPackager )
				)
				( attribute "PNN" "UPI_CPU1_CPU0_P0P0_DN<12>"
					( Origin gPackager )
				)
				( objectStatus "UPI_CPU1_CPU0_P0P0_DN<12>" )
			)
			( signal "@baseboard_fab2_lib.baseboard_fab2(sch_1):upi_cpu1_cpu0_p0p0_dn(13)"
				( attribute "CDS_PHYS_NET_NAME" "UPI_CPU1_CPU0_P0P0_DN<13>"
					( Origin gPackager )
				)
				( attribute "PNN" "UPI_CPU1_CPU0_P0P0_DN<13>"
					( Origin gPackager )
				)
				( objectStatus "UPI_CPU1_CPU0_P0P0_DN<13>" )
			)
			( signal "@baseboard_fab2_lib.baseboard_fab2(sch_1):upi_cpu1_cpu0_p0p0_dn(14)"
				( attribute "CDS_PHYS_NET_NAME" "UPI_CPU1_CPU0_P0P0_DN<14>"
					( Origin gPackager )
				)
				( attribute "PNN" "UPI_CPU1_CPU0_P0P0_DN<14>"
					( Origin gPackager )
				)
				( objectStatus "UPI_CPU1_CPU0_P0P0_DN<14>" )
			)
			( signal "@baseboard_fab2_lib.baseboard_fab2(sch_1):upi_cpu1_cpu0_p0p0_dn(15)"
				( attribute "CDS_PHYS_NET_NAME" "UPI_CPU1_CPU0_P0P0_DN<15>"
					( Origin gPackager )
				)
				( attribute "PNN" "UPI_CPU1_CPU0_P0P0_DN<15>"
					( Origin gPackager )
				)
				( objectStatus "UPI_CPU1_CPU0_P0P0_DN<15>" )
			)
			( signal "@baseboard_fab2_lib.baseboard_fab2(sch_1):upi_cpu1_cpu0_p0p0_dn(16)"
				( attribute "CDS_PHYS_NET_NAME" "UPI_CPU1_CPU0_P0P0_DN<16>"
					( Origin gPackager )
				)
				( attribute "PNN" "UPI_CPU1_CPU0_P0P0_DN<16>"
					( Origin gPackager )
				)
				( objectStatus "UPI_CPU1_CPU0_P0P0_DN<16>" )
			)
			( signal "@baseboard_fab2_lib.baseboard_fab2(sch_1):upi_cpu1_cpu0_p0p0_dn(17)"
				( attribute "CDS_PHYS_NET_NAME" "UPI_CPU1_CPU0_P0P0_DN<17>"
					( Origin gPackager )
				)
				( attribute "PNN" "UPI_CPU1_CPU0_P0P0_DN<17>"
					( Origin gPackager )
				)
				( objectStatus "UPI_CPU1_CPU0_P0P0_DN<17>" )
			)
			( signal "@baseboard_fab2_lib.baseboard_fab2(sch_1):upi_cpu1_cpu0_p0p0_dn(18)"
				( attribute "CDS_PHYS_NET_NAME" "UPI_CPU1_CPU0_P0P0_DN<18>"
					( Origin gPackager )
				)
				( attribute "PNN" "UPI_CPU1_CPU0_P0P0_DN<18>"
					( Origin gPackager )
				)
				( objectStatus "UPI_CPU1_CPU0_P0P0_DN<18>" )
			)
			( signal "@baseboard_fab2_lib.baseboard_fab2(sch_1):upi_cpu1_cpu0_p0p0_dn(19)"
				( attribute "CDS_PHYS_NET_NAME" "UPI_CPU1_CPU0_P0P0_DN<19>"
					( Origin gPackager )
				)
				( attribute "PNN" "UPI_CPU1_CPU0_P0P0_DN<19>"
					( Origin gPackager )
				)
				( objectStatus "UPI_CPU1_CPU0_P0P0_DN<19>" )
			)
			( signal "@baseboard_fab2_lib.baseboard_fab2(sch_1):upi_cpu1_cpu0_p0p0_dp(0)"
				( attribute "CDS_PHYS_NET_NAME" "UPI_CPU1_CPU0_P0P0_DP<0>"
					( Origin gPackager )
				)
				( attribute "PNN" "UPI_CPU1_CPU0_P0P0_DP<0>"
					( Origin gPackager )
				)
				( objectStatus "UPI_CPU1_CPU0_P0P0_DP<0>" )
			)
			( signal "@baseboard_fab2_lib.baseboard_fab2(sch_1):upi_cpu1_cpu0_p0p0_dp(1)"
				( attribute "CDS_PHYS_NET_NAME" "UPI_CPU1_CPU0_P0P0_DP<1>"
					( Origin gPackager )
				)
				( attribute "PNN" "UPI_CPU1_CPU0_P0P0_DP<1>"
					( Origin gPackager )
				)
				( objectStatus "UPI_CPU1_CPU0_P0P0_DP<1>" )
			)
			( signal "@baseboard_fab2_lib.baseboard_fab2(sch_1):upi_cpu1_cpu0_p0p0_dp(2)"
				( attribute "CDS_PHYS_NET_NAME" "UPI_CPU1_CPU0_P0P0_DP<2>"
					( Origin gPackager )
				)
				( attribute "PNN" "UPI_CPU1_CPU0_P0P0_DP<2>"
					( Origin gPackager )
				)
				( objectStatus "UPI_CPU1_CPU0_P0P0_DP<2>" )
			)
			( signal "@baseboard_fab2_lib.baseboard_fab2(sch_1):upi_cpu1_cpu0_p0p0_dp(3)"
				( attribute "CDS_PHYS_NET_NAME" "UPI_CPU1_CPU0_P0P0_DP<3>"
					( Origin gPackager )
				)
				( attribute "PNN" "UPI_CPU1_CPU0_P0P0_DP<3>"
					( Origin gPackager )
				)
				( objectStatus "UPI_CPU1_CPU0_P0P0_DP<3>" )
			)
			( signal "@baseboard_fab2_lib.baseboard_fab2(sch_1):upi_cpu1_cpu0_p0p0_dp(4)"
				( attribute "CDS_PHYS_NET_NAME" "UPI_CPU1_CPU0_P0P0_DP<4>"
					( Origin gPackager )
				)
				( attribute "PNN" "UPI_CPU1_CPU0_P0P0_DP<4>"
					( Origin gPackager )
				)
				( objectStatus "UPI_CPU1_CPU0_P0P0_DP<4>" )
			)
			( signal "@baseboard_fab2_lib.baseboard_fab2(sch_1):upi_cpu1_cpu0_p0p0_dp(5)"
				( attribute "CDS_PHYS_NET_NAME" "UPI_CPU1_CPU0_P0P0_DP<5>"
					( Origin gPackager )
				)
				( attribute "PNN" "UPI_CPU1_CPU0_P0P0_DP<5>"
					( Origin gPackager )
				)
				( objectStatus "UPI_CPU1_CPU0_P0P0_DP<5>" )
			)
			( signal "@baseboard_fab2_lib.baseboard_fab2(sch_1):upi_cpu1_cpu0_p0p0_dp(6)"
				( attribute "CDS_PHYS_NET_NAME" "UPI_CPU1_CPU0_P0P0_DP<6>"
					( Origin gPackager )
				)
				( attribute "PNN" "UPI_CPU1_CPU0_P0P0_DP<6>"
					( Origin gPackager )
				)
				( objectStatus "UPI_CPU1_CPU0_P0P0_DP<6>" )
			)
			( signal "@baseboard_fab2_lib.baseboard_fab2(sch_1):upi_cpu1_cpu0_p0p0_dp(7)"
				( attribute "CDS_PHYS_NET_NAME" "UPI_CPU1_CPU0_P0P0_DP<7>"
					( Origin gPackager )
				)
				( attribute "PNN" "UPI_CPU1_CPU0_P0P0_DP<7>"
					( Origin gPackager )
				)
				( objectStatus "UPI_CPU1_CPU0_P0P0_DP<7>" )
			)
			( signal "@baseboard_fab2_lib.baseboard_fab2(sch_1):upi_cpu1_cpu0_p0p0_dp(8)"
				( attribute "CDS_PHYS_NET_NAME" "UPI_CPU1_CPU0_P0P0_DP<8>"
					( Origin gPackager )
				)
				( attribute "PNN" "UPI_CPU1_CPU0_P0P0_DP<8>"
					( Origin gPackager )
				)
				( objectStatus "UPI_CPU1_CPU0_P0P0_DP<8>" )
			)
			( signal "@baseboard_fab2_lib.baseboard_fab2(sch_1):upi_cpu1_cpu0_p0p0_dp(9)"
				( attribute "CDS_PHYS_NET_NAME" "UPI_CPU1_CPU0_P0P0_DP<9>"
					( Origin gPackager )
				)
				( attribute "PNN" "UPI_CPU1_CPU0_P0P0_DP<9>"
					( Origin gPackager )
				)
				( objectStatus "UPI_CPU1_CPU0_P0P0_DP<9>" )
			)
			( signal "@baseboard_fab2_lib.baseboard_fab2(sch_1):upi_cpu1_cpu0_p0p0_dp(10)"
				( attribute "CDS_PHYS_NET_NAME" "UPI_CPU1_CPU0_P0P0_DP<10>"
					( Origin gPackager )
				)
				( attribute "PNN" "UPI_CPU1_CPU0_P0P0_DP<10>"
					( Origin gPackager )
				)
				( objectStatus "UPI_CPU1_CPU0_P0P0_DP<10>" )
			)
			( signal "@baseboard_fab2_lib.baseboard_fab2(sch_1):upi_cpu1_cpu0_p0p0_dp(11)"
				( attribute "CDS_PHYS_NET_NAME" "UPI_CPU1_CPU0_P0P0_DP<11>"
					( Origin gPackager )
				)
				( attribute "PNN" "UPI_CPU1_CPU0_P0P0_DP<11>"
					( Origin gPackager )
				)
				( objectStatus "UPI_CPU1_CPU0_P0P0_DP<11>" )
			)
			( signal "@baseboard_fab2_lib.baseboard_fab2(sch_1):upi_cpu1_cpu0_p0p0_dp(12)"
				( attribute "CDS_PHYS_NET_NAME" "UPI_CPU1_CPU0_P0P0_DP<12>"
					( Origin gPackager )
				)
				( attribute "PNN" "UPI_CPU1_CPU0_P0P0_DP<12>"
					( Origin gPackager )
				)
				( objectStatus "UPI_CPU1_CPU0_P0P0_DP<12>" )
			)
			( signal "@baseboard_fab2_lib.baseboard_fab2(sch_1):upi_cpu1_cpu0_p0p0_dp(13)"
				( attribute "CDS_PHYS_NET_NAME" "UPI_CPU1_CPU0_P0P0_DP<13>"
					( Origin gPackager )
				)
				( attribute "PNN" "UPI_CPU1_CPU0_P0P0_DP<13>"
					( Origin gPackager )
				)
				( objectStatus "UPI_CPU1_CPU0_P0P0_DP<13>" )
			)
			( signal "@baseboard_fab2_lib.baseboard_fab2(sch_1):upi_cpu1_cpu0_p0p0_dp(14)"
				( attribute "CDS_PHYS_NET_NAME" "UPI_CPU1_CPU0_P0P0_DP<14>"
					( Origin gPackager )
				)
				( attribute "PNN" "UPI_CPU1_CPU0_P0P0_DP<14>"
					( Origin gPackager )
				)
				( objectStatus "UPI_CPU1_CPU0_P0P0_DP<14>" )
			)
			( signal "@baseboard_fab2_lib.baseboard_fab2(sch_1):upi_cpu1_cpu0_p0p0_dp(15)"
				( attribute "CDS_PHYS_NET_NAME" "UPI_CPU1_CPU0_P0P0_DP<15>"
					( Origin gPackager )
				)
				( attribute "PNN" "UPI_CPU1_CPU0_P0P0_DP<15>"
					( Origin gPackager )
				)
				( objectStatus "UPI_CPU1_CPU0_P0P0_DP<15>" )
			)
			( signal "@baseboard_fab2_lib.baseboard_fab2(sch_1):upi_cpu1_cpu0_p0p0_dp(16)"
				( attribute "CDS_PHYS_NET_NAME" "UPI_CPU1_CPU0_P0P0_DP<16>"
					( Origin gPackager )
				)
				( attribute "PNN" "UPI_CPU1_CPU0_P0P0_DP<16>"
					( Origin gPackager )
				)
				( objectStatus "UPI_CPU1_CPU0_P0P0_DP<16>" )
			)
			( signal "@baseboard_fab2_lib.baseboard_fab2(sch_1):upi_cpu1_cpu0_p0p0_dp(17)"
				( attribute "CDS_PHYS_NET_NAME" "UPI_CPU1_CPU0_P0P0_DP<17>"
					( Origin gPackager )
				)
				( attribute "PNN" "UPI_CPU1_CPU0_P0P0_DP<17>"
					( Origin gPackager )
				)
				( objectStatus "UPI_CPU1_CPU0_P0P0_DP<17>" )
			)
			( signal "@baseboard_fab2_lib.baseboard_fab2(sch_1):upi_cpu1_cpu0_p0p0_dp(18)"
				( attribute "CDS_PHYS_NET_NAME" "UPI_CPU1_CPU0_P0P0_DP<18>"
					( Origin gPackager )
				)
				( attribute "PNN" "UPI_CPU1_CPU0_P0P0_DP<18>"
					( Origin gPackager )
				)
				( objectStatus "UPI_CPU1_CPU0_P0P0_DP<18>" )
			)
			( signal "@baseboard_fab2_lib.baseboard_fab2(sch_1):upi_cpu1_cpu0_p0p0_dp(19)"
				( attribute "CDS_PHYS_NET_NAME" "UPI_CPU1_CPU0_P0P0_DP<19>"
					( Origin gPackager )
				)
				( attribute "PNN" "UPI_CPU1_CPU0_P0P0_DP<19>"
					( Origin gPackager )
				)
				( objectStatus "UPI_CPU1_CPU0_P0P0_DP<19>" )
			)
			( signal "@baseboard_fab2_lib.baseboard_fab2(sch_1):upi_cpu0_cpu1_p1p1_dn(0)"
				( attribute "CDS_PHYS_NET_NAME" "UPI_CPU0_CPU1_P1P1_DN<0>"
					( Origin gPackager )
				)
				( attribute "PNN" "UPI_CPU0_CPU1_P1P1_DN<0>"
					( Origin gPackager )
				)
				( objectStatus "UPI_CPU0_CPU1_P1P1_DN<0>" )
			)
			( signal "@baseboard_fab2_lib.baseboard_fab2(sch_1):upi_cpu0_cpu1_p1p1_dn(1)"
				( attribute "CDS_PHYS_NET_NAME" "UPI_CPU0_CPU1_P1P1_DN<1>"
					( Origin gPackager )
				)
				( attribute "PNN" "UPI_CPU0_CPU1_P1P1_DN<1>"
					( Origin gPackager )
				)
				( objectStatus "UPI_CPU0_CPU1_P1P1_DN<1>" )
			)
			( signal "@baseboard_fab2_lib.baseboard_fab2(sch_1):upi_cpu0_cpu1_p1p1_dn(2)"
				( attribute "CDS_PHYS_NET_NAME" "UPI_CPU0_CPU1_P1P1_DN<2>"
					( Origin gPackager )
				)
				( attribute "PNN" "UPI_CPU0_CPU1_P1P1_DN<2>"
					( Origin gPackager )
				)
				( objectStatus "UPI_CPU0_CPU1_P1P1_DN<2>" )
			)
			( signal "@baseboard_fab2_lib.baseboard_fab2(sch_1):upi_cpu0_cpu1_p1p1_dn(3)"
				( attribute "CDS_PHYS_NET_NAME" "UPI_CPU0_CPU1_P1P1_DN<3>"
					( Origin gPackager )
				)
				( attribute "PNN" "UPI_CPU0_CPU1_P1P1_DN<3>"
					( Origin gPackager )
				)
				( objectStatus "UPI_CPU0_CPU1_P1P1_DN<3>" )
			)
			( signal "@baseboard_fab2_lib.baseboard_fab2(sch_1):upi_cpu0_cpu1_p1p1_dn(4)"
				( attribute "CDS_PHYS_NET_NAME" "UPI_CPU0_CPU1_P1P1_DN<4>"
					( Origin gPackager )
				)
				( attribute "PNN" "UPI_CPU0_CPU1_P1P1_DN<4>"
					( Origin gPackager )
				)
				( objectStatus "UPI_CPU0_CPU1_P1P1_DN<4>" )
			)
			( signal "@baseboard_fab2_lib.baseboard_fab2(sch_1):upi_cpu0_cpu1_p1p1_dn(5)"
				( attribute "CDS_PHYS_NET_NAME" "UPI_CPU0_CPU1_P1P1_DN<5>"
					( Origin gPackager )
				)
				( attribute "PNN" "UPI_CPU0_CPU1_P1P1_DN<5>"
					( Origin gPackager )
				)
				( objectStatus "UPI_CPU0_CPU1_P1P1_DN<5>" )
			)
			( signal "@baseboard_fab2_lib.baseboard_fab2(sch_1):upi_cpu0_cpu1_p1p1_dn(6)"
				( attribute "CDS_PHYS_NET_NAME" "UPI_CPU0_CPU1_P1P1_DN<6>"
					( Origin gPackager )
				)
				( attribute "PNN" "UPI_CPU0_CPU1_P1P1_DN<6>"
					( Origin gPackager )
				)
				( objectStatus "UPI_CPU0_CPU1_P1P1_DN<6>" )
			)
			( signal "@baseboard_fab2_lib.baseboard_fab2(sch_1):upi_cpu0_cpu1_p1p1_dn(7)"
				( attribute "CDS_PHYS_NET_NAME" "UPI_CPU0_CPU1_P1P1_DN<7>"
					( Origin gPackager )
				)
				( attribute "PNN" "UPI_CPU0_CPU1_P1P1_DN<7>"
					( Origin gPackager )
				)
				( objectStatus "UPI_CPU0_CPU1_P1P1_DN<7>" )
			)
			( signal "@baseboard_fab2_lib.baseboard_fab2(sch_1):upi_cpu0_cpu1_p1p1_dn(8)"
				( attribute "CDS_PHYS_NET_NAME" "UPI_CPU0_CPU1_P1P1_DN<8>"
					( Origin gPackager )
				)
				( attribute "PNN" "UPI_CPU0_CPU1_P1P1_DN<8>"
					( Origin gPackager )
				)
				( objectStatus "UPI_CPU0_CPU1_P1P1_DN<8>" )
			)
			( signal "@baseboard_fab2_lib.baseboard_fab2(sch_1):upi_cpu0_cpu1_p1p1_dn(9)"
				( attribute "CDS_PHYS_NET_NAME" "UPI_CPU0_CPU1_P1P1_DN<9>"
					( Origin gPackager )
				)
				( attribute "PNN" "UPI_CPU0_CPU1_P1P1_DN<9>"
					( Origin gPackager )
				)
				( objectStatus "UPI_CPU0_CPU1_P1P1_DN<9>" )
			)
			( signal "@baseboard_fab2_lib.baseboard_fab2(sch_1):upi_cpu0_cpu1_p1p1_dn(10)"
				( attribute "CDS_PHYS_NET_NAME" "UPI_CPU0_CPU1_P1P1_DN<10>"
					( Origin gPackager )
				)
				( attribute "PNN" "UPI_CPU0_CPU1_P1P1_DN<10>"
					( Origin gPackager )
				)
				( objectStatus "UPI_CPU0_CPU1_P1P1_DN<10>" )
			)
			( signal "@baseboard_fab2_lib.baseboard_fab2(sch_1):upi_cpu0_cpu1_p1p1_dn(11)"
				( attribute "CDS_PHYS_NET_NAME" "UPI_CPU0_CPU1_P1P1_DN<11>"
					( Origin gPackager )
				)
				( attribute "PNN" "UPI_CPU0_CPU1_P1P1_DN<11>"
					( Origin gPackager )
				)
				( objectStatus "UPI_CPU0_CPU1_P1P1_DN<11>" )
			)
			( signal "@baseboard_fab2_lib.baseboard_fab2(sch_1):upi_cpu0_cpu1_p1p1_dn(12)"
				( attribute "CDS_PHYS_NET_NAME" "UPI_CPU0_CPU1_P1P1_DN<12>"
					( Origin gPackager )
				)
				( attribute "PNN" "UPI_CPU0_CPU1_P1P1_DN<12>"
					( Origin gPackager )
				)
				( objectStatus "UPI_CPU0_CPU1_P1P1_DN<12>" )
			)
			( signal "@baseboard_fab2_lib.baseboard_fab2(sch_1):upi_cpu0_cpu1_p1p1_dn(13)"
				( attribute "CDS_PHYS_NET_NAME" "UPI_CPU0_CPU1_P1P1_DN<13>"
					( Origin gPackager )
				)
				( attribute "PNN" "UPI_CPU0_CPU1_P1P1_DN<13>"
					( Origin gPackager )
				)
				( objectStatus "UPI_CPU0_CPU1_P1P1_DN<13>" )
			)
			( signal "@baseboard_fab2_lib.baseboard_fab2(sch_1):upi_cpu0_cpu1_p1p1_dn(14)"
				( attribute "CDS_PHYS_NET_NAME" "UPI_CPU0_CPU1_P1P1_DN<14>"
					( Origin gPackager )
				)
				( attribute "PNN" "UPI_CPU0_CPU1_P1P1_DN<14>"
					( Origin gPackager )
				)
				( objectStatus "UPI_CPU0_CPU1_P1P1_DN<14>" )
			)
			( signal "@baseboard_fab2_lib.baseboard_fab2(sch_1):upi_cpu0_cpu1_p1p1_dn(15)"
				( attribute "CDS_PHYS_NET_NAME" "UPI_CPU0_CPU1_P1P1_DN<15>"
					( Origin gPackager )
				)
				( attribute "PNN" "UPI_CPU0_CPU1_P1P1_DN<15>"
					( Origin gPackager )
				)
				( objectStatus "UPI_CPU0_CPU1_P1P1_DN<15>" )
			)
			( signal "@baseboard_fab2_lib.baseboard_fab2(sch_1):upi_cpu0_cpu1_p1p1_dn(16)"
				( attribute "CDS_PHYS_NET_NAME" "UPI_CPU0_CPU1_P1P1_DN<16>"
					( Origin gPackager )
				)
				( attribute "PNN" "UPI_CPU0_CPU1_P1P1_DN<16>"
					( Origin gPackager )
				)
				( objectStatus "UPI_CPU0_CPU1_P1P1_DN<16>" )
			)
			( signal "@baseboard_fab2_lib.baseboard_fab2(sch_1):upi_cpu0_cpu1_p1p1_dn(17)"
				( attribute "CDS_PHYS_NET_NAME" "UPI_CPU0_CPU1_P1P1_DN<17>"
					( Origin gPackager )
				)
				( attribute "PNN" "UPI_CPU0_CPU1_P1P1_DN<17>"
					( Origin gPackager )
				)
				( objectStatus "UPI_CPU0_CPU1_P1P1_DN<17>" )
			)
			( signal "@baseboard_fab2_lib.baseboard_fab2(sch_1):upi_cpu0_cpu1_p1p1_dn(18)"
				( attribute "CDS_PHYS_NET_NAME" "UPI_CPU0_CPU1_P1P1_DN<18>"
					( Origin gPackager )
				)
				( attribute "PNN" "UPI_CPU0_CPU1_P1P1_DN<18>"
					( Origin gPackager )
				)
				( objectStatus "UPI_CPU0_CPU1_P1P1_DN<18>" )
			)
			( signal "@baseboard_fab2_lib.baseboard_fab2(sch_1):upi_cpu0_cpu1_p1p1_dn(19)"
				( attribute "CDS_PHYS_NET_NAME" "UPI_CPU0_CPU1_P1P1_DN<19>"
					( Origin gPackager )
				)
				( attribute "PNN" "UPI_CPU0_CPU1_P1P1_DN<19>"
					( Origin gPackager )
				)
				( objectStatus "UPI_CPU0_CPU1_P1P1_DN<19>" )
			)
			( signal "@baseboard_fab2_lib.baseboard_fab2(sch_1):upi_cpu0_cpu1_p1p1_dp(0)"
				( attribute "CDS_PHYS_NET_NAME" "UPI_CPU0_CPU1_P1P1_DP<0>"
					( Origin gPackager )
				)
				( attribute "PNN" "UPI_CPU0_CPU1_P1P1_DP<0>"
					( Origin gPackager )
				)
				( objectStatus "UPI_CPU0_CPU1_P1P1_DP<0>" )
			)
			( signal "@baseboard_fab2_lib.baseboard_fab2(sch_1):upi_cpu0_cpu1_p1p1_dp(1)"
				( attribute "CDS_PHYS_NET_NAME" "UPI_CPU0_CPU1_P1P1_DP<1>"
					( Origin gPackager )
				)
				( attribute "PNN" "UPI_CPU0_CPU1_P1P1_DP<1>"
					( Origin gPackager )
				)
				( objectStatus "UPI_CPU0_CPU1_P1P1_DP<1>" )
			)
			( signal "@baseboard_fab2_lib.baseboard_fab2(sch_1):upi_cpu0_cpu1_p1p1_dp(2)"
				( attribute "CDS_PHYS_NET_NAME" "UPI_CPU0_CPU1_P1P1_DP<2>"
					( Origin gPackager )
				)
				( attribute "PNN" "UPI_CPU0_CPU1_P1P1_DP<2>"
					( Origin gPackager )
				)
				( objectStatus "UPI_CPU0_CPU1_P1P1_DP<2>" )
			)
			( signal "@baseboard_fab2_lib.baseboard_fab2(sch_1):upi_cpu0_cpu1_p1p1_dp(3)"
				( attribute "CDS_PHYS_NET_NAME" "UPI_CPU0_CPU1_P1P1_DP<3>"
					( Origin gPackager )
				)
				( attribute "PNN" "UPI_CPU0_CPU1_P1P1_DP<3>"
					( Origin gPackager )
				)
				( objectStatus "UPI_CPU0_CPU1_P1P1_DP<3>" )
			)
			( signal "@baseboard_fab2_lib.baseboard_fab2(sch_1):upi_cpu0_cpu1_p1p1_dp(4)"
				( attribute "CDS_PHYS_NET_NAME" "UPI_CPU0_CPU1_P1P1_DP<4>"
					( Origin gPackager )
				)
				( attribute "PNN" "UPI_CPU0_CPU1_P1P1_DP<4>"
					( Origin gPackager )
				)
				( objectStatus "UPI_CPU0_CPU1_P1P1_DP<4>" )
			)
			( signal "@baseboard_fab2_lib.baseboard_fab2(sch_1):upi_cpu0_cpu1_p1p1_dp(5)"
				( attribute "CDS_PHYS_NET_NAME" "UPI_CPU0_CPU1_P1P1_DP<5>"
					( Origin gPackager )
				)
				( attribute "PNN" "UPI_CPU0_CPU1_P1P1_DP<5>"
					( Origin gPackager )
				)
				( objectStatus "UPI_CPU0_CPU1_P1P1_DP<5>" )
			)
			( signal "@baseboard_fab2_lib.baseboard_fab2(sch_1):upi_cpu0_cpu1_p1p1_dp(6)"
				( attribute "CDS_PHYS_NET_NAME" "UPI_CPU0_CPU1_P1P1_DP<6>"
					( Origin gPackager )
				)
				( attribute "PNN" "UPI_CPU0_CPU1_P1P1_DP<6>"
					( Origin gPackager )
				)
				( objectStatus "UPI_CPU0_CPU1_P1P1_DP<6>" )
			)
			( signal "@baseboard_fab2_lib.baseboard_fab2(sch_1):upi_cpu0_cpu1_p1p1_dp(7)"
				( attribute "CDS_PHYS_NET_NAME" "UPI_CPU0_CPU1_P1P1_DP<7>"
					( Origin gPackager )
				)
				( attribute "PNN" "UPI_CPU0_CPU1_P1P1_DP<7>"
					( Origin gPackager )
				)
				( objectStatus "UPI_CPU0_CPU1_P1P1_DP<7>" )
			)
			( signal "@baseboard_fab2_lib.baseboard_fab2(sch_1):upi_cpu0_cpu1_p1p1_dp(8)"
				( attribute "CDS_PHYS_NET_NAME" "UPI_CPU0_CPU1_P1P1_DP<8>"
					( Origin gPackager )
				)
				( attribute "PNN" "UPI_CPU0_CPU1_P1P1_DP<8>"
					( Origin gPackager )
				)
				( objectStatus "UPI_CPU0_CPU1_P1P1_DP<8>" )
			)
			( signal "@baseboard_fab2_lib.baseboard_fab2(sch_1):upi_cpu0_cpu1_p1p1_dp(9)"
				( attribute "CDS_PHYS_NET_NAME" "UPI_CPU0_CPU1_P1P1_DP<9>"
					( Origin gPackager )
				)
				( attribute "PNN" "UPI_CPU0_CPU1_P1P1_DP<9>"
					( Origin gPackager )
				)
				( objectStatus "UPI_CPU0_CPU1_P1P1_DP<9>" )
			)
			( signal "@baseboard_fab2_lib.baseboard_fab2(sch_1):upi_cpu0_cpu1_p1p1_dp(10)"
				( attribute "CDS_PHYS_NET_NAME" "UPI_CPU0_CPU1_P1P1_DP<10>"
					( Origin gPackager )
				)
				( attribute "PNN" "UPI_CPU0_CPU1_P1P1_DP<10>"
					( Origin gPackager )
				)
				( objectStatus "UPI_CPU0_CPU1_P1P1_DP<10>" )
			)
			( signal "@baseboard_fab2_lib.baseboard_fab2(sch_1):upi_cpu0_cpu1_p1p1_dp(11)"
				( attribute "CDS_PHYS_NET_NAME" "UPI_CPU0_CPU1_P1P1_DP<11>"
					( Origin gPackager )
				)
				( attribute "PNN" "UPI_CPU0_CPU1_P1P1_DP<11>"
					( Origin gPackager )
				)
				( objectStatus "UPI_CPU0_CPU1_P1P1_DP<11>" )
			)
			( signal "@baseboard_fab2_lib.baseboard_fab2(sch_1):upi_cpu0_cpu1_p1p1_dp(12)"
				( attribute "CDS_PHYS_NET_NAME" "UPI_CPU0_CPU1_P1P1_DP<12>"
					( Origin gPackager )
				)
				( attribute "PNN" "UPI_CPU0_CPU1_P1P1_DP<12>"
					( Origin gPackager )
				)
				( objectStatus "UPI_CPU0_CPU1_P1P1_DP<12>" )
			)
			( signal "@baseboard_fab2_lib.baseboard_fab2(sch_1):upi_cpu0_cpu1_p1p1_dp(13)"
				( attribute "CDS_PHYS_NET_NAME" "UPI_CPU0_CPU1_P1P1_DP<13>"
					( Origin gPackager )
				)
				( attribute "PNN" "UPI_CPU0_CPU1_P1P1_DP<13>"
					( Origin gPackager )
				)
				( objectStatus "UPI_CPU0_CPU1_P1P1_DP<13>" )
			)
			( signal "@baseboard_fab2_lib.baseboard_fab2(sch_1):upi_cpu0_cpu1_p1p1_dp(14)"
				( attribute "CDS_PHYS_NET_NAME" "UPI_CPU0_CPU1_P1P1_DP<14>"
					( Origin gPackager )
				)
				( attribute "PNN" "UPI_CPU0_CPU1_P1P1_DP<14>"
					( Origin gPackager )
				)
				( objectStatus "UPI_CPU0_CPU1_P1P1_DP<14>" )
			)
			( signal "@baseboard_fab2_lib.baseboard_fab2(sch_1):upi_cpu0_cpu1_p1p1_dp(15)"
				( attribute "CDS_PHYS_NET_NAME" "UPI_CPU0_CPU1_P1P1_DP<15>"
					( Origin gPackager )
				)
				( attribute "PNN" "UPI_CPU0_CPU1_P1P1_DP<15>"
					( Origin gPackager )
				)
				( objectStatus "UPI_CPU0_CPU1_P1P1_DP<15>" )
			)
			( signal "@baseboard_fab2_lib.baseboard_fab2(sch_1):upi_cpu0_cpu1_p1p1_dp(16)"
				( attribute "CDS_PHYS_NET_NAME" "UPI_CPU0_CPU1_P1P1_DP<16>"
					( Origin gPackager )
				)
				( attribute "PNN" "UPI_CPU0_CPU1_P1P1_DP<16>"
					( Origin gPackager )
				)
				( objectStatus "UPI_CPU0_CPU1_P1P1_DP<16>" )
			)
			( signal "@baseboard_fab2_lib.baseboard_fab2(sch_1):upi_cpu0_cpu1_p1p1_dp(17)"
				( attribute "CDS_PHYS_NET_NAME" "UPI_CPU0_CPU1_P1P1_DP<17>"
					( Origin gPackager )
				)
				( attribute "PNN" "UPI_CPU0_CPU1_P1P1_DP<17>"
					( Origin gPackager )
				)
				( objectStatus "UPI_CPU0_CPU1_P1P1_DP<17>" )
			)
			( signal "@baseboard_fab2_lib.baseboard_fab2(sch_1):upi_cpu0_cpu1_p1p1_dp(18)"
				( attribute "CDS_PHYS_NET_NAME" "UPI_CPU0_CPU1_P1P1_DP<18>"
					( Origin gPackager )
				)
				( attribute "PNN" "UPI_CPU0_CPU1_P1P1_DP<18>"
					( Origin gPackager )
				)
				( objectStatus "UPI_CPU0_CPU1_P1P1_DP<18>" )
			)
			( signal "@baseboard_fab2_lib.baseboard_fab2(sch_1):upi_cpu0_cpu1_p1p1_dp(19)"
				( attribute "CDS_PHYS_NET_NAME" "UPI_CPU0_CPU1_P1P1_DP<19>"
					( Origin gPackager )
				)
				( attribute "PNN" "UPI_CPU0_CPU1_P1P1_DP<19>"
					( Origin gPackager )
				)
				( objectStatus "UPI_CPU0_CPU1_P1P1_DP<19>" )
			)
			( signal "@baseboard_fab2_lib.baseboard_fab2(sch_1):upi_cpu1_cpu0_p1p1_dn(0)"
				( attribute "CDS_PHYS_NET_NAME" "UPI_CPU1_CPU0_P1P1_DN<0>"
					( Origin gPackager )
				)
				( attribute "PNN" "UPI_CPU1_CPU0_P1P1_DN<0>"
					( Origin gPackager )
				)
				( objectStatus "UPI_CPU1_CPU0_P1P1_DN<0>" )
			)
			( signal "@baseboard_fab2_lib.baseboard_fab2(sch_1):upi_cpu1_cpu0_p1p1_dn(1)"
				( attribute "CDS_PHYS_NET_NAME" "UPI_CPU1_CPU0_P1P1_DN<1>"
					( Origin gPackager )
				)
				( attribute "PNN" "UPI_CPU1_CPU0_P1P1_DN<1>"
					( Origin gPackager )
				)
				( objectStatus "UPI_CPU1_CPU0_P1P1_DN<1>" )
			)
			( signal "@baseboard_fab2_lib.baseboard_fab2(sch_1):upi_cpu1_cpu0_p1p1_dn(2)"
				( attribute "CDS_PHYS_NET_NAME" "UPI_CPU1_CPU0_P1P1_DN<2>"
					( Origin gPackager )
				)
				( attribute "PNN" "UPI_CPU1_CPU0_P1P1_DN<2>"
					( Origin gPackager )
				)
				( objectStatus "UPI_CPU1_CPU0_P1P1_DN<2>" )
			)
			( signal "@baseboard_fab2_lib.baseboard_fab2(sch_1):upi_cpu1_cpu0_p1p1_dn(3)"
				( attribute "CDS_PHYS_NET_NAME" "UPI_CPU1_CPU0_P1P1_DN<3>"
					( Origin gPackager )
				)
				( attribute "PNN" "UPI_CPU1_CPU0_P1P1_DN<3>"
					( Origin gPackager )
				)
				( objectStatus "UPI_CPU1_CPU0_P1P1_DN<3>" )
			)
			( signal "@baseboard_fab2_lib.baseboard_fab2(sch_1):upi_cpu1_cpu0_p1p1_dn(4)"
				( attribute "CDS_PHYS_NET_NAME" "UPI_CPU1_CPU0_P1P1_DN<4>"
					( Origin gPackager )
				)
				( attribute "PNN" "UPI_CPU1_CPU0_P1P1_DN<4>"
					( Origin gPackager )
				)
				( objectStatus "UPI_CPU1_CPU0_P1P1_DN<4>" )
			)
			( signal "@baseboard_fab2_lib.baseboard_fab2(sch_1):upi_cpu1_cpu0_p1p1_dn(5)"
				( attribute "CDS_PHYS_NET_NAME" "UPI_CPU1_CPU0_P1P1_DN<5>"
					( Origin gPackager )
				)
				( attribute "PNN" "UPI_CPU1_CPU0_P1P1_DN<5>"
					( Origin gPackager )
				)
				( objectStatus "UPI_CPU1_CPU0_P1P1_DN<5>" )
			)
			( signal "@baseboard_fab2_lib.baseboard_fab2(sch_1):upi_cpu1_cpu0_p1p1_dn(6)"
				( attribute "CDS_PHYS_NET_NAME" "UPI_CPU1_CPU0_P1P1_DN<6>"
					( Origin gPackager )
				)
				( attribute "PNN" "UPI_CPU1_CPU0_P1P1_DN<6>"
					( Origin gPackager )
				)
				( objectStatus "UPI_CPU1_CPU0_P1P1_DN<6>" )
			)
			( signal "@baseboard_fab2_lib.baseboard_fab2(sch_1):upi_cpu1_cpu0_p1p1_dn(7)"
				( attribute "CDS_PHYS_NET_NAME" "UPI_CPU1_CPU0_P1P1_DN<7>"
					( Origin gPackager )
				)
				( attribute "PNN" "UPI_CPU1_CPU0_P1P1_DN<7>"
					( Origin gPackager )
				)
				( objectStatus "UPI_CPU1_CPU0_P1P1_DN<7>" )
			)
			( signal "@baseboard_fab2_lib.baseboard_fab2(sch_1):upi_cpu1_cpu0_p1p1_dn(8)"
				( attribute "CDS_PHYS_NET_NAME" "UPI_CPU1_CPU0_P1P1_DN<8>"
					( Origin gPackager )
				)
				( attribute "PNN" "UPI_CPU1_CPU0_P1P1_DN<8>"
					( Origin gPackager )
				)
				( objectStatus "UPI_CPU1_CPU0_P1P1_DN<8>" )
			)
			( signal "@baseboard_fab2_lib.baseboard_fab2(sch_1):upi_cpu1_cpu0_p1p1_dn(9)"
				( attribute "CDS_PHYS_NET_NAME" "UPI_CPU1_CPU0_P1P1_DN<9>"
					( Origin gPackager )
				)
				( attribute "PNN" "UPI_CPU1_CPU0_P1P1_DN<9>"
					( Origin gPackager )
				)
				( objectStatus "UPI_CPU1_CPU0_P1P1_DN<9>" )
			)
			( signal "@baseboard_fab2_lib.baseboard_fab2(sch_1):upi_cpu1_cpu0_p1p1_dn(10)"
				( attribute "CDS_PHYS_NET_NAME" "UPI_CPU1_CPU0_P1P1_DN<10>"
					( Origin gPackager )
				)
				( attribute "PNN" "UPI_CPU1_CPU0_P1P1_DN<10>"
					( Origin gPackager )
				)
				( objectStatus "UPI_CPU1_CPU0_P1P1_DN<10>" )
			)
			( signal "@baseboard_fab2_lib.baseboard_fab2(sch_1):upi_cpu1_cpu0_p1p1_dn(11)"
				( attribute "CDS_PHYS_NET_NAME" "UPI_CPU1_CPU0_P1P1_DN<11>"
					( Origin gPackager )
				)
				( attribute "PNN" "UPI_CPU1_CPU0_P1P1_DN<11>"
					( Origin gPackager )
				)
				( objectStatus "UPI_CPU1_CPU0_P1P1_DN<11>" )
			)
			( signal "@baseboard_fab2_lib.baseboard_fab2(sch_1):upi_cpu1_cpu0_p1p1_dn(12)"
				( attribute "CDS_PHYS_NET_NAME" "UPI_CPU1_CPU0_P1P1_DN<12>"
					( Origin gPackager )
				)
				( attribute "PNN" "UPI_CPU1_CPU0_P1P1_DN<12>"
					( Origin gPackager )
				)
				( objectStatus "UPI_CPU1_CPU0_P1P1_DN<12>" )
			)
			( signal "@baseboard_fab2_lib.baseboard_fab2(sch_1):upi_cpu1_cpu0_p1p1_dn(13)"
				( attribute "CDS_PHYS_NET_NAME" "UPI_CPU1_CPU0_P1P1_DN<13>"
					( Origin gPackager )
				)
				( attribute "PNN" "UPI_CPU1_CPU0_P1P1_DN<13>"
					( Origin gPackager )
				)
				( objectStatus "UPI_CPU1_CPU0_P1P1_DN<13>" )
			)
			( signal "@baseboard_fab2_lib.baseboard_fab2(sch_1):upi_cpu1_cpu0_p1p1_dn(14)"
				( attribute "CDS_PHYS_NET_NAME" "UPI_CPU1_CPU0_P1P1_DN<14>"
					( Origin gPackager )
				)
				( attribute "PNN" "UPI_CPU1_CPU0_P1P1_DN<14>"
					( Origin gPackager )
				)
				( objectStatus "UPI_CPU1_CPU0_P1P1_DN<14>" )
			)
			( signal "@baseboard_fab2_lib.baseboard_fab2(sch_1):upi_cpu1_cpu0_p1p1_dn(15)"
				( attribute "CDS_PHYS_NET_NAME" "UPI_CPU1_CPU0_P1P1_DN<15>"
					( Origin gPackager )
				)
				( attribute "PNN" "UPI_CPU1_CPU0_P1P1_DN<15>"
					( Origin gPackager )
				)
				( objectStatus "UPI_CPU1_CPU0_P1P1_DN<15>" )
			)
			( signal "@baseboard_fab2_lib.baseboard_fab2(sch_1):upi_cpu1_cpu0_p1p1_dn(16)"
				( attribute "CDS_PHYS_NET_NAME" "UPI_CPU1_CPU0_P1P1_DN<16>"
					( Origin gPackager )
				)
				( attribute "PNN" "UPI_CPU1_CPU0_P1P1_DN<16>"
					( Origin gPackager )
				)
				( objectStatus "UPI_CPU1_CPU0_P1P1_DN<16>" )
			)
			( signal "@baseboard_fab2_lib.baseboard_fab2(sch_1):upi_cpu1_cpu0_p1p1_dn(17)"
				( attribute "CDS_PHYS_NET_NAME" "UPI_CPU1_CPU0_P1P1_DN<17>"
					( Origin gPackager )
				)
				( attribute "PNN" "UPI_CPU1_CPU0_P1P1_DN<17>"
					( Origin gPackager )
				)
				( objectStatus "UPI_CPU1_CPU0_P1P1_DN<17>" )
			)
			( signal "@baseboard_fab2_lib.baseboard_fab2(sch_1):upi_cpu1_cpu0_p1p1_dn(18)"
				( attribute "CDS_PHYS_NET_NAME" "UPI_CPU1_CPU0_P1P1_DN<18>"
					( Origin gPackager )
				)
				( attribute "PNN" "UPI_CPU1_CPU0_P1P1_DN<18>"
					( Origin gPackager )
				)
				( objectStatus "UPI_CPU1_CPU0_P1P1_DN<18>" )
			)
			( signal "@baseboard_fab2_lib.baseboard_fab2(sch_1):upi_cpu1_cpu0_p1p1_dn(19)"
				( attribute "CDS_PHYS_NET_NAME" "UPI_CPU1_CPU0_P1P1_DN<19>"
					( Origin gPackager )
				)
				( attribute "PNN" "UPI_CPU1_CPU0_P1P1_DN<19>"
					( Origin gPackager )
				)
				( objectStatus "UPI_CPU1_CPU0_P1P1_DN<19>" )
			)
			( signal "@baseboard_fab2_lib.baseboard_fab2(sch_1):upi_cpu1_cpu0_p1p1_dp(0)"
				( attribute "CDS_PHYS_NET_NAME" "UPI_CPU1_CPU0_P1P1_DP<0>"
					( Origin gPackager )
				)
				( attribute "PNN" "UPI_CPU1_CPU0_P1P1_DP<0>"
					( Origin gPackager )
				)
				( objectStatus "UPI_CPU1_CPU0_P1P1_DP<0>" )
			)
			( signal "@baseboard_fab2_lib.baseboard_fab2(sch_1):upi_cpu1_cpu0_p1p1_dp(1)"
				( attribute "CDS_PHYS_NET_NAME" "UPI_CPU1_CPU0_P1P1_DP<1>"
					( Origin gPackager )
				)
				( attribute "PNN" "UPI_CPU1_CPU0_P1P1_DP<1>"
					( Origin gPackager )
				)
				( objectStatus "UPI_CPU1_CPU0_P1P1_DP<1>" )
			)
			( signal "@baseboard_fab2_lib.baseboard_fab2(sch_1):upi_cpu1_cpu0_p1p1_dp(2)"
				( attribute "CDS_PHYS_NET_NAME" "UPI_CPU1_CPU0_P1P1_DP<2>"
					( Origin gPackager )
				)
				( attribute "PNN" "UPI_CPU1_CPU0_P1P1_DP<2>"
					( Origin gPackager )
				)
				( objectStatus "UPI_CPU1_CPU0_P1P1_DP<2>" )
			)
			( signal "@baseboard_fab2_lib.baseboard_fab2(sch_1):upi_cpu1_cpu0_p1p1_dp(3)"
				( attribute "CDS_PHYS_NET_NAME" "UPI_CPU1_CPU0_P1P1_DP<3>"
					( Origin gPackager )
				)
				( attribute "PNN" "UPI_CPU1_CPU0_P1P1_DP<3>"
					( Origin gPackager )
				)
				( objectStatus "UPI_CPU1_CPU0_P1P1_DP<3>" )
			)
			( signal "@baseboard_fab2_lib.baseboard_fab2(sch_1):upi_cpu1_cpu0_p1p1_dp(4)"
				( attribute "CDS_PHYS_NET_NAME" "UPI_CPU1_CPU0_P1P1_DP<4>"
					( Origin gPackager )
				)
				( attribute "PNN" "UPI_CPU1_CPU0_P1P1_DP<4>"
					( Origin gPackager )
				)
				( objectStatus "UPI_CPU1_CPU0_P1P1_DP<4>" )
			)
			( signal "@baseboard_fab2_lib.baseboard_fab2(sch_1):upi_cpu1_cpu0_p1p1_dp(5)"
				( attribute "CDS_PHYS_NET_NAME" "UPI_CPU1_CPU0_P1P1_DP<5>"
					( Origin gPackager )
				)
				( attribute "PNN" "UPI_CPU1_CPU0_P1P1_DP<5>"
					( Origin gPackager )
				)
				( objectStatus "UPI_CPU1_CPU0_P1P1_DP<5>" )
			)
			( signal "@baseboard_fab2_lib.baseboard_fab2(sch_1):upi_cpu1_cpu0_p1p1_dp(6)"
				( attribute "CDS_PHYS_NET_NAME" "UPI_CPU1_CPU0_P1P1_DP<6>"
					( Origin gPackager )
				)
				( attribute "PNN" "UPI_CPU1_CPU0_P1P1_DP<6>"
					( Origin gPackager )
				)
				( objectStatus "UPI_CPU1_CPU0_P1P1_DP<6>" )
			)
			( signal "@baseboard_fab2_lib.baseboard_fab2(sch_1):upi_cpu1_cpu0_p1p1_dp(7)"
				( attribute "CDS_PHYS_NET_NAME" "UPI_CPU1_CPU0_P1P1_DP<7>"
					( Origin gPackager )
				)
				( attribute "PNN" "UPI_CPU1_CPU0_P1P1_DP<7>"
					( Origin gPackager )
				)
				( objectStatus "UPI_CPU1_CPU0_P1P1_DP<7>" )
			)
			( signal "@baseboard_fab2_lib.baseboard_fab2(sch_1):upi_cpu1_cpu0_p1p1_dp(8)"
				( attribute "CDS_PHYS_NET_NAME" "UPI_CPU1_CPU0_P1P1_DP<8>"
					( Origin gPackager )
				)
				( attribute "PNN" "UPI_CPU1_CPU0_P1P1_DP<8>"
					( Origin gPackager )
				)
				( objectStatus "UPI_CPU1_CPU0_P1P1_DP<8>" )
			)
			( signal "@baseboard_fab2_lib.baseboard_fab2(sch_1):upi_cpu1_cpu0_p1p1_dp(9)"
				( attribute "CDS_PHYS_NET_NAME" "UPI_CPU1_CPU0_P1P1_DP<9>"
					( Origin gPackager )
				)
				( attribute "PNN" "UPI_CPU1_CPU0_P1P1_DP<9>"
					( Origin gPackager )
				)
				( objectStatus "UPI_CPU1_CPU0_P1P1_DP<9>" )
			)
			( signal "@baseboard_fab2_lib.baseboard_fab2(sch_1):upi_cpu1_cpu0_p1p1_dp(10)"
				( attribute "CDS_PHYS_NET_NAME" "UPI_CPU1_CPU0_P1P1_DP<10>"
					( Origin gPackager )
				)
				( attribute "PNN" "UPI_CPU1_CPU0_P1P1_DP<10>"
					( Origin gPackager )
				)
				( objectStatus "UPI_CPU1_CPU0_P1P1_DP<10>" )
			)
			( signal "@baseboard_fab2_lib.baseboard_fab2(sch_1):upi_cpu1_cpu0_p1p1_dp(11)"
				( attribute "CDS_PHYS_NET_NAME" "UPI_CPU1_CPU0_P1P1_DP<11>"
					( Origin gPackager )
				)
				( attribute "PNN" "UPI_CPU1_CPU0_P1P1_DP<11>"
					( Origin gPackager )
				)
				( objectStatus "UPI_CPU1_CPU0_P1P1_DP<11>" )
			)
			( signal "@baseboard_fab2_lib.baseboard_fab2(sch_1):upi_cpu1_cpu0_p1p1_dp(12)"
				( attribute "CDS_PHYS_NET_NAME" "UPI_CPU1_CPU0_P1P1_DP<12>"
					( Origin gPackager )
				)
				( attribute "PNN" "UPI_CPU1_CPU0_P1P1_DP<12>"
					( Origin gPackager )
				)
				( objectStatus "UPI_CPU1_CPU0_P1P1_DP<12>" )
			)
			( signal "@baseboard_fab2_lib.baseboard_fab2(sch_1):upi_cpu1_cpu0_p1p1_dp(13)"
				( attribute "CDS_PHYS_NET_NAME" "UPI_CPU1_CPU0_P1P1_DP<13>"
					( Origin gPackager )
				)
				( attribute "PNN" "UPI_CPU1_CPU0_P1P1_DP<13>"
					( Origin gPackager )
				)
				( objectStatus "UPI_CPU1_CPU0_P1P1_DP<13>" )
			)
			( signal "@baseboard_fab2_lib.baseboard_fab2(sch_1):upi_cpu1_cpu0_p1p1_dp(14)"
				( attribute "CDS_PHYS_NET_NAME" "UPI_CPU1_CPU0_P1P1_DP<14>"
					( Origin gPackager )
				)
				( attribute "PNN" "UPI_CPU1_CPU0_P1P1_DP<14>"
					( Origin gPackager )
				)
				( objectStatus "UPI_CPU1_CPU0_P1P1_DP<14>" )
			)
			( signal "@baseboard_fab2_lib.baseboard_fab2(sch_1):upi_cpu1_cpu0_p1p1_dp(15)"
				( attribute "CDS_PHYS_NET_NAME" "UPI_CPU1_CPU0_P1P1_DP<15>"
					( Origin gPackager )
				)
				( attribute "PNN" "UPI_CPU1_CPU0_P1P1_DP<15>"
					( Origin gPackager )
				)
				( objectStatus "UPI_CPU1_CPU0_P1P1_DP<15>" )
			)
			( signal "@baseboard_fab2_lib.baseboard_fab2(sch_1):upi_cpu1_cpu0_p1p1_dp(16)"
				( attribute "CDS_PHYS_NET_NAME" "UPI_CPU1_CPU0_P1P1_DP<16>"
					( Origin gPackager )
				)
				( attribute "PNN" "UPI_CPU1_CPU0_P1P1_DP<16>"
					( Origin gPackager )
				)
				( objectStatus "UPI_CPU1_CPU0_P1P1_DP<16>" )
			)
			( signal "@baseboard_fab2_lib.baseboard_fab2(sch_1):upi_cpu1_cpu0_p1p1_dp(17)"
				( attribute "CDS_PHYS_NET_NAME" "UPI_CPU1_CPU0_P1P1_DP<17>"
					( Origin gPackager )
				)
				( attribute "PNN" "UPI_CPU1_CPU0_P1P1_DP<17>"
					( Origin gPackager )
				)
				( objectStatus "UPI_CPU1_CPU0_P1P1_DP<17>" )
			)
			( signal "@baseboard_fab2_lib.baseboard_fab2(sch_1):upi_cpu1_cpu0_p1p1_dp(18)"
				( attribute "CDS_PHYS_NET_NAME" "UPI_CPU1_CPU0_P1P1_DP<18>"
					( Origin gPackager )
				)
				( attribute "PNN" "UPI_CPU1_CPU0_P1P1_DP<18>"
					( Origin gPackager )
				)
				( objectStatus "UPI_CPU1_CPU0_P1P1_DP<18>" )
			)
			( signal "@baseboard_fab2_lib.baseboard_fab2(sch_1):upi_cpu1_cpu0_p1p1_dp(19)"
				( attribute "CDS_PHYS_NET_NAME" "UPI_CPU1_CPU0_P1P1_DP<19>"
					( Origin gPackager )
				)
				( attribute "PNN" "UPI_CPU1_CPU0_P1P1_DP<19>"
					( Origin gPackager )
				)
				( objectStatus "UPI_CPU1_CPU0_P1P1_DP<19>" )
			)
			( signal "@baseboard_fab2_lib.baseboard_fab2(sch_1):tp_cpu0_upi2_rsvd_ca12"
				( attribute "CDS_PHYS_NET_NAME" "TP_CPU0_UPI2_RSVD_CA12"
					( Origin gPackager )
				)
				( objectStatus "TP_CPU0_UPI2_RSVD_CA12" )
			)
			( signal "@baseboard_fab2_lib.baseboard_fab2(sch_1):tp_cpu0_upi2_rsvd_cb11"
				( attribute "CDS_PHYS_NET_NAME" "TP_CPU0_UPI2_RSVD_CB11"
					( Origin gPackager )
				)
				( objectStatus "TP_CPU0_UPI2_RSVD_CB11" )
			)
			( signal "@baseboard_fab2_lib.baseboard_fab2(sch_1):tp_cpu0_upi2_rsvd_cc10"
				( attribute "CDS_PHYS_NET_NAME" "TP_CPU0_UPI2_RSVD_CC10"
					( Origin gPackager )
				)
				( objectStatus "TP_CPU0_UPI2_RSVD_CC10" )
			)
			( signal "@baseboard_fab2_lib.baseboard_fab2(sch_1):tp_cpu0_upi2_rsvd_cc12"
				( attribute "CDS_PHYS_NET_NAME" "TP_CPU0_UPI2_RSVD_CC12"
					( Origin gPackager )
				)
				( objectStatus "TP_CPU0_UPI2_RSVD_CC12" )
			)
			( signal "@baseboard_fab2_lib.baseboard_fab2(sch_1):tp_cpu0_upi2_rsvd_cd11"
				( attribute "CDS_PHYS_NET_NAME" "TP_CPU0_UPI2_RSVD_CD11"
					( Origin gPackager )
				)
				( objectStatus "TP_CPU0_UPI2_RSVD_CD11" )
			)
			( signal "@baseboard_fab2_lib.baseboard_fab2(sch_1):tp_cpu0_upi2_rsvd_ce12"
				( attribute "CDS_PHYS_NET_NAME" "TP_CPU0_UPI2_RSVD_CE12"
					( Origin gPackager )
				)
				( objectStatus "TP_CPU0_UPI2_RSVD_CE12" )
			)
			( signal "@baseboard_fab2_lib.baseboard_fab2(sch_1):tp_cpu0_upi2_rsvd_cf11"
				( attribute "CDS_PHYS_NET_NAME" "TP_CPU0_UPI2_RSVD_CF11"
					( Origin gPackager )
				)
				( objectStatus "TP_CPU0_UPI2_RSVD_CF11" )
			)
			( signal "@baseboard_fab2_lib.baseboard_fab2(sch_1):tp_cpu0_upi2_rsvd_cf13"
				( attribute "CDS_PHYS_NET_NAME" "TP_CPU0_UPI2_RSVD_CF13"
					( Origin gPackager )
				)
				( objectStatus "TP_CPU0_UPI2_RSVD_CF13" )
			)
			( signal "@baseboard_fab2_lib.baseboard_fab2(sch_1):tp_cpu0_upi2_rsvd_cg12"
				( attribute "CDS_PHYS_NET_NAME" "TP_CPU0_UPI2_RSVD_CG12"
					( Origin gPackager )
				)
				( objectStatus "TP_CPU0_UPI2_RSVD_CG12" )
			)
			( signal "@baseboard_fab2_lib.baseboard_fab2(sch_1):tp_cpu0_upi2_rsvd_ch11"
				( attribute "CDS_PHYS_NET_NAME" "TP_CPU0_UPI2_RSVD_CH11"
					( Origin gPackager )
				)
				( objectStatus "TP_CPU0_UPI2_RSVD_CH11" )
			)
			( signal "@baseboard_fab2_lib.baseboard_fab2(sch_1):tp_cpu0_upi2_rsvd_ch13"
				( attribute "CDS_PHYS_NET_NAME" "TP_CPU0_UPI2_RSVD_CH13"
					( Origin gPackager )
				)
				( objectStatus "TP_CPU0_UPI2_RSVD_CH13" )
			)
			( signal "@baseboard_fab2_lib.baseboard_fab2(sch_1):tp_cpu0_upi2_rsvd_cj14"
				( attribute "CDS_PHYS_NET_NAME" "TP_CPU0_UPI2_RSVD_CJ14"
					( Origin gPackager )
				)
				( objectStatus "TP_CPU0_UPI2_RSVD_CJ14" )
			)
			( signal "@baseboard_fab2_lib.baseboard_fab2(sch_1):tp_cpu0_upi2_rsvd_ck13"
				( attribute "CDS_PHYS_NET_NAME" "TP_CPU0_UPI2_RSVD_CK13"
					( Origin gPackager )
				)
				( objectStatus "TP_CPU0_UPI2_RSVD_CK13" )
			)
			( signal "@baseboard_fab2_lib.baseboard_fab2(sch_1):tp_cpu0_upi2_rsvd_cm13"
				( attribute "CDS_PHYS_NET_NAME" "TP_CPU0_UPI2_RSVD_CM13"
					( Origin gPackager )
				)
				( objectStatus "TP_CPU0_UPI2_RSVD_CM13" )
			)
			( signal "@baseboard_fab2_lib.baseboard_fab2(sch_1):tp_cpu0_upi2_rsvd_cr14"
				( attribute "CDS_PHYS_NET_NAME" "TP_CPU0_UPI2_RSVD_CR14"
					( Origin gPackager )
				)
				( objectStatus "TP_CPU0_UPI2_RSVD_CR14" )
			)
			( signal "@baseboard_fab2_lib.baseboard_fab2(sch_1):tp_cpu0_upi2_rsvd_cu14"
				( attribute "CDS_PHYS_NET_NAME" "TP_CPU0_UPI2_RSVD_CU14"
					( Origin gPackager )
				)
				( objectStatus "TP_CPU0_UPI2_RSVD_CU14" )
			)
			( signal "@baseboard_fab2_lib.baseboard_fab2(sch_1):tp_cpu0_upi2_rsvd_cv13"
				( attribute "CDS_PHYS_NET_NAME" "TP_CPU0_UPI2_RSVD_CV13"
					( Origin gPackager )
				)
				( objectStatus "TP_CPU0_UPI2_RSVD_CV13" )
			)
			( signal "@baseboard_fab2_lib.baseboard_fab2(sch_1):tp_cpu0_upi2_rsvd_cw14"
				( attribute "CDS_PHYS_NET_NAME" "TP_CPU0_UPI2_RSVD_CW14"
					( Origin gPackager )
				)
				( objectStatus "TP_CPU0_UPI2_RSVD_CW14" )
			)
			( signal "@baseboard_fab2_lib.baseboard_fab2(sch_1):tp_cpu0_upi2_rsvd_cw16"
				( attribute "CDS_PHYS_NET_NAME" "TP_CPU0_UPI2_RSVD_CW16"
					( Origin gPackager )
				)
				( objectStatus "TP_CPU0_UPI2_RSVD_CW16" )
			)
			( signal "@baseboard_fab2_lib.baseboard_fab2(sch_1):tp_cpu0_upi2_rsvd_da16"
				( attribute "CDS_PHYS_NET_NAME" "TP_CPU0_UPI2_RSVD_DA16"
					( Origin gPackager )
				)
				( objectStatus "TP_CPU0_UPI2_RSVD_DA16" )
			)
			( signal "@baseboard_fab2_lib.baseboard_fab2(sch_1):tp_cpu0_upi2_rsvd_db15"
				( attribute "CDS_PHYS_NET_NAME" "TP_CPU0_UPI2_RSVD_DB15"
					( Origin gPackager )
				)
				( objectStatus "TP_CPU0_UPI2_RSVD_DB15" )
			)
			( signal "@baseboard_fab2_lib.baseboard_fab2(sch_1):tp_cpu0_upi2_rsvd_dc16"
				( attribute "CDS_PHYS_NET_NAME" "TP_CPU0_UPI2_RSVD_DC16"
					( Origin gPackager )
				)
				( objectStatus "TP_CPU0_UPI2_RSVD_DC16" )
			)
			( signal "@baseboard_fab2_lib.baseboard_fab2(sch_1):tp_cpu0_upi2_rsvd_dd15"
				( attribute "CDS_PHYS_NET_NAME" "TP_CPU0_UPI2_RSVD_DD15"
					( Origin gPackager )
				)
				( objectStatus "TP_CPU0_UPI2_RSVD_DD15" )
			)
			( signal "@baseboard_fab2_lib.baseboard_fab2(sch_1):tp_cpu0_upi2_rsvd_dd17"
				( attribute "CDS_PHYS_NET_NAME" "TP_CPU0_UPI2_RSVD_DD17"
					( Origin gPackager )
				)
				( objectStatus "TP_CPU0_UPI2_RSVD_DD17" )
			)
			( signal "@baseboard_fab2_lib.baseboard_fab2(sch_1):tp_cpu0_upi2_rsvd_de16"
				( attribute "CDS_PHYS_NET_NAME" "TP_CPU0_UPI2_RSVD_DE16"
					( Origin gPackager )
				)
				( objectStatus "TP_CPU0_UPI2_RSVD_DE16" )
			)
			( signal "@baseboard_fab2_lib.baseboard_fab2(sch_1):tp_cpu0_upi2_rsvd_df15"
				( attribute "CDS_PHYS_NET_NAME" "TP_CPU0_UPI2_RSVD_DF15"
					( Origin gPackager )
				)
				( objectStatus "TP_CPU0_UPI2_RSVD_DF15" )
			)
			( signal "@baseboard_fab2_lib.baseboard_fab2(sch_1):tp_cpu0_upi2_rsvd_df17"
				( attribute "CDS_PHYS_NET_NAME" "TP_CPU0_UPI2_RSVD_DF17"
					( Origin gPackager )
				)
				( objectStatus "TP_CPU0_UPI2_RSVD_DF17" )
			)
			( signal "@baseboard_fab2_lib.baseboard_fab2(sch_1):tp_cpu0_upi2_rsvd_dg18"
				( attribute "CDS_PHYS_NET_NAME" "TP_CPU0_UPI2_RSVD_DG18"
					( Origin gPackager )
				)
				( objectStatus "TP_CPU0_UPI2_RSVD_DG18" )
			)
			( signal "@baseboard_fab2_lib.baseboard_fab2(sch_1):tp_cpu0_upi2_rsvd_dg20"
				( attribute "CDS_PHYS_NET_NAME" "TP_CPU0_UPI2_RSVD_DG20"
					( Origin gPackager )
				)
				( objectStatus "TP_CPU0_UPI2_RSVD_DG20" )
			)
			( signal "@baseboard_fab2_lib.baseboard_fab2(sch_1):tp_cpu0_upi2_rsvd_dh17"
				( attribute "CDS_PHYS_NET_NAME" "TP_CPU0_UPI2_RSVD_DH17"
					( Origin gPackager )
				)
				( objectStatus "TP_CPU0_UPI2_RSVD_DH17" )
			)
			( signal "@baseboard_fab2_lib.baseboard_fab2(sch_1):tp_cpu0_upi2_rsvd_dh19"
				( attribute "CDS_PHYS_NET_NAME" "TP_CPU0_UPI2_RSVD_DH19"
					( Origin gPackager )
				)
				( objectStatus "TP_CPU0_UPI2_RSVD_DH19" )
			)
			( signal "@baseboard_fab2_lib.baseboard_fab2(sch_1):tp_cpu0_upi2_rsvd_dj18"
				( attribute "CDS_PHYS_NET_NAME" "TP_CPU0_UPI2_RSVD_DJ18"
					( Origin gPackager )
				)
				( objectStatus "TP_CPU0_UPI2_RSVD_DJ18" )
			)
			( signal "@baseboard_fab2_lib.baseboard_fab2(sch_1):tp_cpu0_upi2_rsvd_dj20"
				( attribute "CDS_PHYS_NET_NAME" "TP_CPU0_UPI2_RSVD_DJ20"
					( Origin gPackager )
				)
				( objectStatus "TP_CPU0_UPI2_RSVD_DJ20" )
			)
			( signal "@baseboard_fab2_lib.baseboard_fab2(sch_1):tp_cpu0_upi2_rsvd_dk17"
				( attribute "CDS_PHYS_NET_NAME" "TP_CPU0_UPI2_RSVD_DK17"
					( Origin gPackager )
				)
				( objectStatus "TP_CPU0_UPI2_RSVD_DK17" )
			)
			( signal "@baseboard_fab2_lib.baseboard_fab2(sch_1):tp_cpu0_upi2_rsvd_dk19"
				( attribute "CDS_PHYS_NET_NAME" "TP_CPU0_UPI2_RSVD_DK19"
					( Origin gPackager )
				)
				( objectStatus "TP_CPU0_UPI2_RSVD_DK19" )
			)
			( signal "@baseboard_fab2_lib.baseboard_fab2(sch_1):tp_cpu0_upi2_rsvd_dl20"
				( attribute "CDS_PHYS_NET_NAME" "TP_CPU0_UPI2_RSVD_DL20"
					( Origin gPackager )
				)
				( objectStatus "TP_CPU0_UPI2_RSVD_DL20" )
			)
			( signal "@baseboard_fab2_lib.baseboard_fab2(sch_1):tp_cpu0_upi2_rsvd_dm21"
				( attribute "CDS_PHYS_NET_NAME" "TP_CPU0_UPI2_RSVD_DM21"
					( Origin gPackager )
				)
				( objectStatus "TP_CPU0_UPI2_RSVD_DM21" )
			)
			( signal "@baseboard_fab2_lib.baseboard_fab2(sch_1):tp_cpu0_upi2_rsvd_dn20"
				( attribute "CDS_PHYS_NET_NAME" "TP_CPU0_UPI2_RSVD_DN20"
					( Origin gPackager )
				)
				( objectStatus "TP_CPU0_UPI2_RSVD_DN20" )
			)
			( signal "@baseboard_fab2_lib.baseboard_fab2(sch_1):tp_cpu0_upi2_rsvd_dp21"
				( attribute "CDS_PHYS_NET_NAME" "TP_CPU0_UPI2_RSVD_DP21"
					( Origin gPackager )
				)
				( objectStatus "TP_CPU0_UPI2_RSVD_DP21" )
			)
			( signal "@baseboard_fab2_lib.baseboard_fab2(sch_1):tp_cpu0_upi2_rsvd_dt21"
				( attribute "CDS_PHYS_NET_NAME" "TP_CPU0_UPI2_RSVD_DT21"
					( Origin gPackager )
				)
				( objectStatus "TP_CPU0_UPI2_RSVD_DT21" )
			)
			( signal "@baseboard_fab2_lib.baseboard_fab2(sch_1):clk_100m_cpu0_rc_refclk1_dn"
				( attribute "CDS_PHYS_NET_NAME" "CLK_100M_CPU0_RC_REFCLK1_DN"
					( Origin gPackager )
				)
				( objectStatus "CLK_100M_CPU0_RC_REFCLK1_DN" )
			)
			( signal "@baseboard_fab2_lib.baseboard_fab2(sch_1):clk_100m_cpu0_rc_refclk1_dp"
				( attribute "CDS_PHYS_NET_NAME" "CLK_100M_CPU0_RC_REFCLK1_DP"
					( Origin gPackager )
				)
				( objectStatus "CLK_100M_CPU0_RC_REFCLK1_DP" )
			)
			( signal "@baseboard_fab2_lib.baseboard_fab2(sch_1):tp_cpu0_rsvd_100"
				( attribute "CDS_PHYS_NET_NAME" "TP_CPU0_RSVD_100"
					( Origin gPackager )
				)
				( objectStatus "TP_CPU0_RSVD_100" )
			)
			( signal "@baseboard_fab2_lib.baseboard_fab2(sch_1):tp_cpu0_rsvd_101"
				( attribute "CDS_PHYS_NET_NAME" "TP_CPU0_RSVD_101"
					( Origin gPackager )
				)
				( objectStatus "TP_CPU0_RSVD_101" )
			)
			( signal "@baseboard_fab2_lib.baseboard_fab2(sch_1):tp_cpu0_rsvd_105"
				( attribute "CDS_PHYS_NET_NAME" "TP_CPU0_RSVD_105"
					( Origin gPackager )
				)
				( objectStatus "TP_CPU0_RSVD_105" )
			)
			( signal "@baseboard_fab2_lib.baseboard_fab2(sch_1):tp_cpu0_rsvd_106"
				( attribute "CDS_PHYS_NET_NAME" "TP_CPU0_RSVD_106"
					( Origin gPackager )
				)
				( objectStatus "TP_CPU0_RSVD_106" )
			)
			( signal "@baseboard_fab2_lib.baseboard_fab2(sch_1):tp_cpu0_rsvd_108"
				( attribute "CDS_PHYS_NET_NAME" "TP_CPU0_RSVD_108"
					( Origin gPackager )
				)
				( objectStatus "TP_CPU0_RSVD_108" )
			)
			( signal "@baseboard_fab2_lib.baseboard_fab2(sch_1):tp_cpu0_rsvd_111"
				( attribute "CDS_PHYS_NET_NAME" "TP_CPU0_RSVD_111"
					( Origin gPackager )
				)
				( objectStatus "TP_CPU0_RSVD_111" )
			)
			( signal "@baseboard_fab2_lib.baseboard_fab2(sch_1):tp_cpu0_rsvd_113"
				( attribute "CDS_PHYS_NET_NAME" "TP_CPU0_RSVD_113"
					( Origin gPackager )
				)
				( objectStatus "TP_CPU0_RSVD_113" )
			)
			( signal "@baseboard_fab2_lib.baseboard_fab2(sch_1):tp_cpu0_rsvd_114"
				( attribute "CDS_PHYS_NET_NAME" "TP_CPU0_RSVD_114"
					( Origin gPackager )
				)
				( objectStatus "TP_CPU0_RSVD_114" )
			)
			( signal "@baseboard_fab2_lib.baseboard_fab2(sch_1):tp_cpu0_rsvd_117"
				( attribute "CDS_PHYS_NET_NAME" "TP_CPU0_RSVD_117"
					( Origin gPackager )
				)
				( objectStatus "TP_CPU0_RSVD_117" )
			)
			( signal "@baseboard_fab2_lib.baseboard_fab2(sch_1):tp_cpu0_rsvd_119"
				( attribute "CDS_PHYS_NET_NAME" "TP_CPU0_RSVD_119"
					( Origin gPackager )
				)
				( objectStatus "TP_CPU0_RSVD_119" )
			)
			( signal "@baseboard_fab2_lib.baseboard_fab2(sch_1):tp_cpu0_rsvd_121"
				( attribute "CDS_PHYS_NET_NAME" "TP_CPU0_RSVD_121"
					( Origin gPackager )
				)
				( objectStatus "TP_CPU0_RSVD_121" )
			)
			( signal "@baseboard_fab2_lib.baseboard_fab2(sch_1):tp_cpu0_rsvd_123"
				( attribute "CDS_PHYS_NET_NAME" "TP_CPU0_RSVD_123"
					( Origin gPackager )
				)
				( objectStatus "TP_CPU0_RSVD_123" )
			)
			( signal "@baseboard_fab2_lib.baseboard_fab2(sch_1):tp_cpu0_rsvd_124"
				( attribute "CDS_PHYS_NET_NAME" "TP_CPU0_RSVD_124"
					( Origin gPackager )
				)
				( objectStatus "TP_CPU0_RSVD_124" )
			)
			( signal "@baseboard_fab2_lib.baseboard_fab2(sch_1):tp_cpu0_rsvd_144"
				( attribute "CDS_PHYS_NET_NAME" "TP_CPU0_RSVD_144"
					( Origin gPackager )
				)
				( objectStatus "TP_CPU0_RSVD_144" )
			)
			( signal "@baseboard_fab2_lib.baseboard_fab2(sch_1):tp_cpu0_rsvd_145"
				( attribute "CDS_PHYS_NET_NAME" "TP_CPU0_RSVD_145"
					( Origin gPackager )
				)
				( objectStatus "TP_CPU0_RSVD_145" )
			)
			( signal "@baseboard_fab2_lib.baseboard_fab2(sch_1):tp_cpu0_rsvd_146"
				( attribute "CDS_PHYS_NET_NAME" "TP_CPU0_RSVD_146"
					( Origin gPackager )
				)
				( objectStatus "TP_CPU0_RSVD_146" )
			)
			( signal "@baseboard_fab2_lib.baseboard_fab2(sch_1):tp_cpu0_rsvd_147"
				( attribute "CDS_PHYS_NET_NAME" "TP_CPU0_RSVD_147"
					( Origin gPackager )
				)
				( objectStatus "TP_CPU0_RSVD_147" )
			)
			( signal "@baseboard_fab2_lib.baseboard_fab2(sch_1):tp_cpu0_rsvd_148"
				( attribute "CDS_PHYS_NET_NAME" "TP_CPU0_RSVD_148"
					( Origin gPackager )
				)
				( objectStatus "TP_CPU0_RSVD_148" )
			)
			( signal "@baseboard_fab2_lib.baseboard_fab2(sch_1):tp_cpu0_rsvd_149"
				( attribute "CDS_PHYS_NET_NAME" "TP_CPU0_RSVD_149"
					( Origin gPackager )
				)
				( objectStatus "TP_CPU0_RSVD_149" )
			)
			( signal "@baseboard_fab2_lib.baseboard_fab2(sch_1):tp_cpu0_rsvd_150"
				( attribute "CDS_PHYS_NET_NAME" "TP_CPU0_RSVD_150"
					( Origin gPackager )
				)
				( objectStatus "TP_CPU0_RSVD_150" )
			)
			( signal "@baseboard_fab2_lib.baseboard_fab2(sch_1):tp_cpu0_rsvd_151"
				( attribute "CDS_PHYS_NET_NAME" "TP_CPU0_RSVD_151"
					( Origin gPackager )
				)
				( objectStatus "TP_CPU0_RSVD_151" )
			)
			( signal "@baseboard_fab2_lib.baseboard_fab2(sch_1):tp_cpu0_rsvd_152"
				( attribute "CDS_PHYS_NET_NAME" "TP_CPU0_RSVD_152"
					( Origin gPackager )
				)
				( objectStatus "TP_CPU0_RSVD_152" )
			)
			( signal "@baseboard_fab2_lib.baseboard_fab2(sch_1):tp_cpu0_rsvd_154"
				( attribute "CDS_PHYS_NET_NAME" "TP_CPU0_RSVD_154"
					( Origin gPackager )
				)
				( objectStatus "TP_CPU0_RSVD_154" )
			)
			( signal "@baseboard_fab2_lib.baseboard_fab2(sch_1):tp_cpu0_rsvd_155"
				( attribute "CDS_PHYS_NET_NAME" "TP_CPU0_RSVD_155"
					( Origin gPackager )
				)
				( objectStatus "TP_CPU0_RSVD_155" )
			)
			( signal "@baseboard_fab2_lib.baseboard_fab2(sch_1):tp_cpu0_rsvd_156"
				( attribute "CDS_PHYS_NET_NAME" "TP_CPU0_RSVD_156"
					( Origin gPackager )
				)
				( objectStatus "TP_CPU0_RSVD_156" )
			)
			( signal "@baseboard_fab2_lib.baseboard_fab2(sch_1):tp_cpu0_rsvd_157"
				( attribute "CDS_PHYS_NET_NAME" "TP_CPU0_RSVD_157"
					( Origin gPackager )
				)
				( objectStatus "TP_CPU0_RSVD_157" )
			)
			( signal "@baseboard_fab2_lib.baseboard_fab2(sch_1):tp_cpu0_rsvd_158"
				( attribute "CDS_PHYS_NET_NAME" "TP_CPU0_RSVD_158"
					( Origin gPackager )
				)
				( objectStatus "TP_CPU0_RSVD_158" )
			)
			( signal "@baseboard_fab2_lib.baseboard_fab2(sch_1):tp_cpu0_rsvd_159"
				( attribute "CDS_PHYS_NET_NAME" "TP_CPU0_RSVD_159"
					( Origin gPackager )
				)
				( objectStatus "TP_CPU0_RSVD_159" )
			)
			( signal "@baseboard_fab2_lib.baseboard_fab2(sch_1):tp_cpu0_rsvd_160"
				( attribute "CDS_PHYS_NET_NAME" "TP_CPU0_RSVD_160"
					( Origin gPackager )
				)
				( objectStatus "TP_CPU0_RSVD_160" )
			)
			( signal "@baseboard_fab2_lib.baseboard_fab2(sch_1):tp_cpu0_rsvd_161"
				( attribute "CDS_PHYS_NET_NAME" "TP_CPU0_RSVD_161"
					( Origin gPackager )
				)
				( objectStatus "TP_CPU0_RSVD_161" )
			)
			( signal "@baseboard_fab2_lib.baseboard_fab2(sch_1):tp_cpu0_rsvd_162"
				( attribute "CDS_PHYS_NET_NAME" "TP_CPU0_RSVD_162"
					( Origin gPackager )
				)
				( objectStatus "TP_CPU0_RSVD_162" )
			)
			( signal "@baseboard_fab2_lib.baseboard_fab2(sch_1):tp_cpu0_rsvd_163"
				( attribute "CDS_PHYS_NET_NAME" "TP_CPU0_RSVD_163"
					( Origin gPackager )
				)
				( objectStatus "TP_CPU0_RSVD_163" )
			)
			( signal "@baseboard_fab2_lib.baseboard_fab2(sch_1):tp_cpu0_rsvd_164"
				( attribute "CDS_PHYS_NET_NAME" "TP_CPU0_RSVD_164"
					( Origin gPackager )
				)
				( objectStatus "TP_CPU0_RSVD_164" )
			)
			( signal "@baseboard_fab2_lib.baseboard_fab2(sch_1):tp_cpu0_rsvd_166"
				( attribute "CDS_PHYS_NET_NAME" "TP_CPU0_RSVD_166"
					( Origin gPackager )
				)
				( objectStatus "TP_CPU0_RSVD_166" )
			)
			( signal "@baseboard_fab2_lib.baseboard_fab2(sch_1):tp_cpu0_rsvd_167"
				( attribute "CDS_PHYS_NET_NAME" "TP_CPU0_RSVD_167"
					( Origin gPackager )
				)
				( objectStatus "TP_CPU0_RSVD_167" )
			)
			( signal "@baseboard_fab2_lib.baseboard_fab2(sch_1):tp_cpu0_rsvd_168"
				( attribute "CDS_PHYS_NET_NAME" "TP_CPU0_RSVD_168"
					( Origin gPackager )
				)
				( objectStatus "TP_CPU0_RSVD_168" )
			)
			( signal "@baseboard_fab2_lib.baseboard_fab2(sch_1):tp_cpu0_rsvd_169"
				( attribute "CDS_PHYS_NET_NAME" "TP_CPU0_RSVD_169"
					( Origin gPackager )
				)
				( objectStatus "TP_CPU0_RSVD_169" )
			)
			( signal "@baseboard_fab2_lib.baseboard_fab2(sch_1):tp_cpu0_rsvd_170"
				( attribute "CDS_PHYS_NET_NAME" "TP_CPU0_RSVD_170"
					( Origin gPackager )
				)
				( objectStatus "TP_CPU0_RSVD_170" )
			)
			( signal "@baseboard_fab2_lib.baseboard_fab2(sch_1):tp_cpu0_rsvd_171"
				( attribute "CDS_PHYS_NET_NAME" "TP_CPU0_RSVD_171"
					( Origin gPackager )
				)
				( objectStatus "TP_CPU0_RSVD_171" )
			)
			( signal "@baseboard_fab2_lib.baseboard_fab2(sch_1):tp_cpu0_rsvd_255"
				( attribute "CDS_PHYS_NET_NAME" "TP_CPU0_RSVD_255"
					( Origin gPackager )
				)
				( objectStatus "TP_CPU0_RSVD_255" )
			)
			( signal "@baseboard_fab2_lib.baseboard_fab2(sch_1):tp_cpu0_rsvd_82"
				( attribute "CDS_PHYS_NET_NAME" "TP_CPU0_RSVD_82"
					( Origin gPackager )
				)
				( objectStatus "TP_CPU0_RSVD_82" )
			)
			( signal "@baseboard_fab2_lib.baseboard_fab2(sch_1):tp_cpu0_rsvd_85"
				( attribute "CDS_PHYS_NET_NAME" "TP_CPU0_RSVD_85"
					( Origin gPackager )
				)
				( objectStatus "TP_CPU0_RSVD_85" )
			)
			( signal "@baseboard_fab2_lib.baseboard_fab2(sch_1):tp_cpu0_rsvd_90"
				( attribute "CDS_PHYS_NET_NAME" "TP_CPU0_RSVD_90"
					( Origin gPackager )
				)
				( objectStatus "TP_CPU0_RSVD_90" )
			)
			( signal "@baseboard_fab2_lib.baseboard_fab2(sch_1):tp_cpu0_rsvd_91"
				( attribute "CDS_PHYS_NET_NAME" "TP_CPU0_RSVD_91"
					( Origin gPackager )
				)
				( objectStatus "TP_CPU0_RSVD_91" )
			)
			( signal "@baseboard_fab2_lib.baseboard_fab2(sch_1):tp_cpu0_rsvd_94"
				( attribute "CDS_PHYS_NET_NAME" "TP_CPU0_RSVD_94"
					( Origin gPackager )
				)
				( objectStatus "TP_CPU0_RSVD_94" )
			)
			( signal "@baseboard_fab2_lib.baseboard_fab2(sch_1):tp_cpu0_rsvd_95"
				( attribute "CDS_PHYS_NET_NAME" "TP_CPU0_RSVD_95"
					( Origin gPackager )
				)
				( objectStatus "TP_CPU0_RSVD_95" )
			)
			( signal "@baseboard_fab2_lib.baseboard_fab2(sch_1):tp_cpu0_rsvd_97"
				( attribute "CDS_PHYS_NET_NAME" "TP_CPU0_RSVD_97"
					( Origin gPackager )
				)
				( objectStatus "TP_CPU0_RSVD_97" )
			)
			( signal "@baseboard_fab2_lib.baseboard_fab2(sch_1):tp_cpu0_rsvd_99"
				( attribute "CDS_PHYS_NET_NAME" "TP_CPU0_RSVD_99"
					( Origin gPackager )
				)
				( objectStatus "TP_CPU0_RSVD_99" )
			)
			( signal "@baseboard_fab2_lib.baseboard_fab2(sch_1):tp_cpu0_test_10"
				( attribute "CDS_PHYS_NET_NAME" "TP_CPU0_TEST_10"
					( Origin gPackager )
				)
				( objectStatus "TP_CPU0_TEST_10" )
			)
			( signal "@baseboard_fab2_lib.baseboard_fab2(sch_1):tp_cpu0_test_6"
				( attribute "CDS_PHYS_NET_NAME" "TP_CPU0_TEST_6"
					( Origin gPackager )
				)
				( objectStatus "TP_CPU0_TEST_6" )
			)
			( signal "@baseboard_fab2_lib.baseboard_fab2(sch_1):tp_cpu0_test_7"
				( attribute "CDS_PHYS_NET_NAME" "TP_CPU0_TEST_7"
					( Origin gPackager )
				)
				( objectStatus "TP_CPU0_TEST_7" )
			)
			( signal "@baseboard_fab2_lib.baseboard_fab2(sch_1):tp_cpu0_test_8"
				( attribute "CDS_PHYS_NET_NAME" "TP_CPU0_TEST_8"
					( Origin gPackager )
				)
				( objectStatus "TP_CPU0_TEST_8" )
			)
			( signal "@baseboard_fab2_lib.baseboard_fab2(sch_1):tp_cpu0_test_9"
				( attribute "CDS_PHYS_NET_NAME" "TP_CPU0_TEST_9"
					( Origin gPackager )
				)
				( objectStatus "TP_CPU0_TEST_9" )
			)
			( signal "@baseboard_fab2_lib.baseboard_fab2(sch_1):pvccin_cpu0"
				( alias ( signalRef "@baseboard_fab2_lib.baseboard_fab2(sch_1):page37_pvccin_cpu0") )
				( alias ( signalRef "@baseboard_fab2_lib.baseboard_fab2(sch_1):page42_pvccin_cpu0") )
				( alias ( signalRef "@baseboard_fab2_lib.baseboard_fab2(sch_1):page202_pvccin_cpu0") )
				( alias ( signalRef "@baseboard_fab2_lib.baseboard_fab2(sch_1):page203_pvccin_cpu0") )
				( alias ( signalRef "@baseboard_fab2_lib.baseboard_fab2(sch_1):page204_pvccin_cpu0") )
				( attribute "CDS_PHYS_NET_NAME" "PVCCIN_CPU0"
					( Origin gPackager )
				)
				( attribute "VOLTAGE" "2.0V"
					( Units "uVoltage" "V" 1.000000)
					( Status sAliasFlattened )
					( Origin gFrontEnd )
				)
				( attribute "PHYS_NET_NAME" "PVCCIN_CPU0"
					( Origin gPackager )
				)
				( objectStatus "PVCCIN_CPU0" )
			)
			( signal "@baseboard_fab2_lib.baseboard_fab2(sch_1):page37_pvccin_cpu0"
				( attribute "VOLTAGE" "2.0V"
					( Units "uVoltage" "V" 1.000000)
					( Origin gFrontEnd )
				)
				( objectFlag fObjectAlias )
				( objectStatus "page37_pvccin_cpu0" )
			)
			( signal "@baseboard_fab2_lib.baseboard_fab2(sch_1):page42_pvccin_cpu0"
				( attribute "VOLTAGE" "2.0V"
					( Units "uVoltage" "V" 1.000000)
					( Origin gFrontEnd )
				)
				( objectFlag fObjectAlias )
				( objectStatus "page42_pvccin_cpu0" )
			)
			( signal "@baseboard_fab2_lib.baseboard_fab2(sch_1):page202_pvccin_cpu0"
				( attribute "VOLTAGE" "2.0V"
					( Units "uVoltage" "V" 1.000000)
					( Origin gFrontEnd )
				)
				( objectFlag fObjectAlias )
				( objectStatus "page202_pvccin_cpu0" )
			)
			( signal "@baseboard_fab2_lib.baseboard_fab2(sch_1):page203_pvccin_cpu0"
				( attribute "VOLTAGE" "2.0V"
					( Units "uVoltage" "V" 1.000000)
					( Origin gFrontEnd )
				)
				( objectFlag fObjectAlias )
				( objectStatus "page203_pvccin_cpu0" )
			)
			( signal "@baseboard_fab2_lib.baseboard_fab2(sch_1):page204_pvccin_cpu0"
				( attribute "VOLTAGE" "2.0V"
					( Units "uVoltage" "V" 1.000000)
					( Origin gFrontEnd )
				)
				( objectFlag fObjectAlias )
				( objectStatus "page204_pvccin_cpu0" )
			)
			( signal "@baseboard_fab2_lib.baseboard_fab2(sch_1):vsense_pmax_cpu0"
				( attribute "CDS_PHYS_NET_NAME" "VSENSE_PMAX_CPU0"
					( Origin gPackager )
				)
				( objectStatus "VSENSE_PMAX_CPU0" )
			)
			( signal "@baseboard_fab2_lib.baseboard_fab2(sch_1):vsense_pvccin_cpu0_skt_vrtn"
				( attribute "CDS_PHYS_NET_NAME" "VSENSE_PVCCIN_CPU0_SKT_VRTN"
					( Origin gPackager )
				)
				( objectStatus "VSENSE_PVCCIN_CPU0_SKT_VRTN" )
			)
			( signal "@baseboard_fab2_lib.baseboard_fab2(sch_1):vsense_pvccin_cpu0_skt_vsen"
				( attribute "CDS_PHYS_NET_NAME" "VSENSE_PVCCIN_CPU0_SKT_VSEN"
					( Origin gPackager )
				)
				( objectStatus "VSENSE_PVCCIN_CPU0_SKT_VSEN" )
			)
			( signal "@baseboard_fab2_lib.baseboard_fab2(sch_1):vsense_vccinr2pmax_cpu0"
				( attribute "CDS_PHYS_NET_NAME" "VSENSE_VCCINR2PMAX_CPU0"
					( Origin gPackager )
				)
				( objectStatus "VSENSE_VCCINR2PMAX_CPU0" )
			)
			( signal "@baseboard_fab2_lib.baseboard_fab2(sch_1):pvcciomcp_cpu0"
				( alias ( signalRef "@baseboard_fab2_lib.baseboard_fab2(sch_1):page38_pvcciomcp_cpu0") )
				( alias ( signalRef "@baseboard_fab2_lib.baseboard_fab2(sch_1):page194_pvcciomcp_cpu0") )
				( attribute "VOLTAGE" "+0.95"
					( Units "uVoltage" "V" 1.000000)
					( Status sAliasFlattened )
					( Origin gFrontEnd )
				)
				( attribute "CDS_PHYS_NET_NAME" "PVCCIOMCP_CPU0"
					( Origin gPackager )
				)
				( objectStatus "PVCCIOMCP_CPU0" )
			)
			( signal "@baseboard_fab2_lib.baseboard_fab2(sch_1):page38_pvcciomcp_cpu0"
				( objectFlag fObjectAlias )
				( objectStatus "page38_pvcciomcp_cpu0" )
			)
			( signal "@baseboard_fab2_lib.baseboard_fab2(sch_1):page194_pvcciomcp_cpu0"
				( attribute "VOLTAGE" "+0.95"
					( Units "uVoltage" "V" 1.000000)
					( Origin gFrontEnd )
				)
				( objectFlag fObjectAlias )
				( objectStatus "page194_pvcciomcp_cpu0" )
			)
			( signal "@baseboard_fab2_lib.baseboard_fab2(sch_1):pvddq_abc"
				( alias ( signalRef "@baseboard_fab2_lib.baseboard_fab2(sch_1):page38_pvddq_abc") )
				( alias ( signalRef "@baseboard_fab2_lib.baseboard_fab2(sch_1):page43_pvddq_abc") )
				( alias ( signalRef "@baseboard_fab2_lib.baseboard_fab2(sch_1):page44_pvddq_abc") )
				( alias ( signalRef "@baseboard_fab2_lib.baseboard_fab2(sch_1):page45_pvddq_abc") )
				( alias ( signalRef "@baseboard_fab2_lib.baseboard_fab2(sch_1):page46_pvddq_abc") )
				( alias ( signalRef "@baseboard_fab2_lib.baseboard_fab2(sch_1):page47_pvddq_abc") )
				( alias ( signalRef "@baseboard_fab2_lib.baseboard_fab2(sch_1):page48_pvddq_abc") )
				( alias ( signalRef "@baseboard_fab2_lib.baseboard_fab2(sch_1):page96_pvddq_abc") )
				( alias ( signalRef "@baseboard_fab2_lib.baseboard_fab2(sch_1):page98_pvddq_abc") )
				( alias ( signalRef "@baseboard_fab2_lib.baseboard_fab2(sch_1):page216_pvddq_abc") )
				( alias ( signalRef "@baseboard_fab2_lib.baseboard_fab2(sch_1):page217_pvddq_abc") )
				( alias ( signalRef "@baseboard_fab2_lib.baseboard_fab2(sch_1):page221_pvddq_abc") )
				( alias ( signalRef "@baseboard_fab2_lib.baseboard_fab2(sch_1):page242_pvddq_abc") )
				( attribute "VOLTAGE" "1.2V"
					( Units "uVoltage" "V" 1.000000)
					( Status sAliasFlattened )
					( Origin gFrontEnd )
				)
				( attribute "CDS_PHYS_NET_NAME" "PVDDQ_ABC"
					( Origin gPackager )
				)
				( objectStatus "PVDDQ_ABC" )
			)
			( signal "@baseboard_fab2_lib.baseboard_fab2(sch_1):page38_pvddq_abc"
				( attribute "VOLTAGE" "1.2V"
					( Units "uVoltage" "V" 1.000000)
					( Origin gFrontEnd )
				)
				( objectFlag fObjectAlias )
				( objectStatus "page38_pvddq_abc" )
			)
			( signal "@baseboard_fab2_lib.baseboard_fab2(sch_1):page43_pvddq_abc"
				( attribute "VOLTAGE" "1.2V"
					( Units "uVoltage" "V" 1.000000)
					( Origin gFrontEnd )
				)
				( objectFlag fObjectAlias )
				( objectStatus "page43_pvddq_abc" )
			)
			( signal "@baseboard_fab2_lib.baseboard_fab2(sch_1):page44_pvddq_abc"
				( attribute "VOLTAGE" "1.2V"
					( Units "uVoltage" "V" 1.000000)
					( Origin gFrontEnd )
				)
				( objectFlag fObjectAlias )
				( objectStatus "page44_pvddq_abc" )
			)
			( signal "@baseboard_fab2_lib.baseboard_fab2(sch_1):page45_pvddq_abc"
				( attribute "VOLTAGE" "1.2V"
					( Units "uVoltage" "V" 1.000000)
					( Origin gFrontEnd )
				)
				( objectFlag fObjectAlias )
				( objectStatus "page45_pvddq_abc" )
			)
			( signal "@baseboard_fab2_lib.baseboard_fab2(sch_1):page46_pvddq_abc"
				( attribute "VOLTAGE" "1.2V"
					( Units "uVoltage" "V" 1.000000)
					( Origin gFrontEnd )
				)
				( objectFlag fObjectAlias )
				( objectStatus "page46_pvddq_abc" )
			)
			( signal "@baseboard_fab2_lib.baseboard_fab2(sch_1):page47_pvddq_abc"
				( attribute "VOLTAGE" "1.2V"
					( Units "uVoltage" "V" 1.000000)
					( Origin gFrontEnd )
				)
				( objectFlag fObjectAlias )
				( objectStatus "page47_pvddq_abc" )
			)
			( signal "@baseboard_fab2_lib.baseboard_fab2(sch_1):page48_pvddq_abc"
				( attribute "VOLTAGE" "1.2V"
					( Units "uVoltage" "V" 1.000000)
					( Origin gFrontEnd )
				)
				( objectFlag fObjectAlias )
				( objectStatus "page48_pvddq_abc" )
			)
			( signal "@baseboard_fab2_lib.baseboard_fab2(sch_1):page96_pvddq_abc"
				( attribute "VOLTAGE" "1.2V"
					( Units "uVoltage" "V" 1.000000)
					( Origin gFrontEnd )
				)
				( objectFlag fObjectAlias )
				( objectStatus "page96_pvddq_abc" )
			)
			( signal "@baseboard_fab2_lib.baseboard_fab2(sch_1):page98_pvddq_abc"
				( attribute "VOLTAGE" "1.2V"
					( Units "uVoltage" "V" 1.000000)
					( Origin gFrontEnd )
				)
				( objectFlag fObjectAlias )
				( objectStatus "page98_pvddq_abc" )
			)
			( signal "@baseboard_fab2_lib.baseboard_fab2(sch_1):page216_pvddq_abc"
				( attribute "VOLTAGE" "1.2V"
					( Units "uVoltage" "V" 1.000000)
					( Origin gFrontEnd )
				)
				( objectFlag fObjectAlias )
				( objectStatus "page216_pvddq_abc" )
			)
			( signal "@baseboard_fab2_lib.baseboard_fab2(sch_1):page217_pvddq_abc"
				( attribute "VOLTAGE" "1.2V"
					( Units "uVoltage" "V" 1.000000)
					( Origin gFrontEnd )
				)
				( objectFlag fObjectAlias )
				( objectStatus "page217_pvddq_abc" )
			)
			( signal "@baseboard_fab2_lib.baseboard_fab2(sch_1):page221_pvddq_abc"
				( attribute "VOLTAGE" "1.2V"
					( Units "uVoltage" "V" 1.000000)
					( Origin gFrontEnd )
				)
				( objectFlag fObjectAlias )
				( objectStatus "page221_pvddq_abc" )
			)
			( signal "@baseboard_fab2_lib.baseboard_fab2(sch_1):page242_pvddq_abc"
				( attribute "VOLTAGE" "1.2V"
					( Units "uVoltage" "V" 1.000000)
					( Origin gFrontEnd )
				)
				( objectFlag fObjectAlias )
				( objectStatus "page242_pvddq_abc" )
			)
			( signal "@baseboard_fab2_lib.baseboard_fab2(sch_1):pvddq_def"
				( alias ( signalRef "@baseboard_fab2_lib.baseboard_fab2(sch_1):page38_pvddq_def") )
				( alias ( signalRef "@baseboard_fab2_lib.baseboard_fab2(sch_1):page49_pvddq_def") )
				( alias ( signalRef "@baseboard_fab2_lib.baseboard_fab2(sch_1):page50_pvddq_def") )
				( alias ( signalRef "@baseboard_fab2_lib.baseboard_fab2(sch_1):page51_pvddq_def") )
				( alias ( signalRef "@baseboard_fab2_lib.baseboard_fab2(sch_1):page52_pvddq_def") )
				( alias ( signalRef "@baseboard_fab2_lib.baseboard_fab2(sch_1):page53_pvddq_def") )
				( alias ( signalRef "@baseboard_fab2_lib.baseboard_fab2(sch_1):page54_pvddq_def") )
				( alias ( signalRef "@baseboard_fab2_lib.baseboard_fab2(sch_1):page96_pvddq_def") )
				( alias ( signalRef "@baseboard_fab2_lib.baseboard_fab2(sch_1):page98_pvddq_def") )
				( alias ( signalRef "@baseboard_fab2_lib.baseboard_fab2(sch_1):page219_pvddq_def") )
				( alias ( signalRef "@baseboard_fab2_lib.baseboard_fab2(sch_1):page220_pvddq_def") )
				( alias ( signalRef "@baseboard_fab2_lib.baseboard_fab2(sch_1):page222_pvddq_def") )
				( alias ( signalRef "@baseboard_fab2_lib.baseboard_fab2(sch_1):page242_pvddq_def") )
				( attribute "VOLTAGE" "1.2V"
					( Units "uVoltage" "V" 1.000000)
					( Status sAliasFlattened )
					( Origin gFrontEnd )
				)
				( attribute "CDS_PHYS_NET_NAME" "PVDDQ_DEF"
					( Origin gPackager )
				)
				( objectStatus "PVDDQ_DEF" )
			)
			( signal "@baseboard_fab2_lib.baseboard_fab2(sch_1):page38_pvddq_def"
				( attribute "VOLTAGE" "1.2V"
					( Units "uVoltage" "V" 1.000000)
					( Origin gFrontEnd )
				)
				( objectFlag fObjectAlias )
				( objectStatus "page38_pvddq_def" )
			)
			( signal "@baseboard_fab2_lib.baseboard_fab2(sch_1):page49_pvddq_def"
				( attribute "VOLTAGE" "1.2V"
					( Units "uVoltage" "V" 1.000000)
					( Origin gFrontEnd )
				)
				( objectFlag fObjectAlias )
				( objectStatus "page49_pvddq_def" )
			)
			( signal "@baseboard_fab2_lib.baseboard_fab2(sch_1):page50_pvddq_def"
				( attribute "VOLTAGE" "1.2V"
					( Units "uVoltage" "V" 1.000000)
					( Origin gFrontEnd )
				)
				( objectFlag fObjectAlias )
				( objectStatus "page50_pvddq_def" )
			)
			( signal "@baseboard_fab2_lib.baseboard_fab2(sch_1):page51_pvddq_def"
				( attribute "VOLTAGE" "1.2V"
					( Units "uVoltage" "V" 1.000000)
					( Origin gFrontEnd )
				)
				( objectFlag fObjectAlias )
				( objectStatus "page51_pvddq_def" )
			)
			( signal "@baseboard_fab2_lib.baseboard_fab2(sch_1):page52_pvddq_def"
				( attribute "VOLTAGE" "1.2V"
					( Units "uVoltage" "V" 1.000000)
					( Origin gFrontEnd )
				)
				( objectFlag fObjectAlias )
				( objectStatus "page52_pvddq_def" )
			)
			( signal "@baseboard_fab2_lib.baseboard_fab2(sch_1):page53_pvddq_def"
				( attribute "VOLTAGE" "1.2V"
					( Units "uVoltage" "V" 1.000000)
					( Origin gFrontEnd )
				)
				( objectFlag fObjectAlias )
				( objectStatus "page53_pvddq_def" )
			)
			( signal "@baseboard_fab2_lib.baseboard_fab2(sch_1):page54_pvddq_def"
				( attribute "VOLTAGE" "1.2V"
					( Units "uVoltage" "V" 1.000000)
					( Origin gFrontEnd )
				)
				( objectFlag fObjectAlias )
				( objectStatus "page54_pvddq_def" )
			)
			( signal "@baseboard_fab2_lib.baseboard_fab2(sch_1):page96_pvddq_def"
				( attribute "VOLTAGE" "1.2V"
					( Units "uVoltage" "V" 1.000000)
					( Origin gFrontEnd )
				)
				( objectFlag fObjectAlias )
				( objectStatus "page96_pvddq_def" )
			)
			( signal "@baseboard_fab2_lib.baseboard_fab2(sch_1):page98_pvddq_def"
				( attribute "VOLTAGE" "1.2V"
					( Units "uVoltage" "V" 1.000000)
					( Origin gFrontEnd )
				)
				( objectFlag fObjectAlias )
				( objectStatus "page98_pvddq_def" )
			)
			( signal "@baseboard_fab2_lib.baseboard_fab2(sch_1):page219_pvddq_def"
				( attribute "VOLTAGE" "1.2V"
					( Units "uVoltage" "V" 1.000000)
					( Origin gFrontEnd )
				)
				( objectFlag fObjectAlias )
				( objectStatus "page219_pvddq_def" )
			)
			( signal "@baseboard_fab2_lib.baseboard_fab2(sch_1):page220_pvddq_def"
				( attribute "VOLTAGE" "1.2V"
					( Units "uVoltage" "V" 1.000000)
					( Origin gFrontEnd )
				)
				( objectFlag fObjectAlias )
				( objectStatus "page220_pvddq_def" )
			)
			( signal "@baseboard_fab2_lib.baseboard_fab2(sch_1):page222_pvddq_def"
				( attribute "VOLTAGE" "1.2V"
					( Units "uVoltage" "V" 1.000000)
					( Origin gFrontEnd )
				)
				( objectFlag fObjectAlias )
				( objectStatus "page222_pvddq_def" )
			)
			( signal "@baseboard_fab2_lib.baseboard_fab2(sch_1):page242_pvddq_def"
				( attribute "VOLTAGE" "1.2V"
					( Units "uVoltage" "V" 1.000000)
					( Origin gFrontEnd )
				)
				( objectFlag fObjectAlias )
				( objectStatus "page242_pvddq_def" )
			)
			( signal "@baseboard_fab2_lib.baseboard_fab2(sch_1):pvpp_abc"
				( alias ( signalRef "@baseboard_fab2_lib.baseboard_fab2(sch_1):page38_pvpp_abc") )
				( alias ( signalRef "@baseboard_fab2_lib.baseboard_fab2(sch_1):page43_pvpp_abc") )
				( alias ( signalRef "@baseboard_fab2_lib.baseboard_fab2(sch_1):page44_pvpp_abc") )
				( alias ( signalRef "@baseboard_fab2_lib.baseboard_fab2(sch_1):page45_pvpp_abc") )
				( alias ( signalRef "@baseboard_fab2_lib.baseboard_fab2(sch_1):page46_pvpp_abc") )
				( alias ( signalRef "@baseboard_fab2_lib.baseboard_fab2(sch_1):page47_pvpp_abc") )
				( alias ( signalRef "@baseboard_fab2_lib.baseboard_fab2(sch_1):page48_pvpp_abc") )
				( alias ( signalRef "@baseboard_fab2_lib.baseboard_fab2(sch_1):page89_pvpp_abc") )
				( alias ( signalRef "@baseboard_fab2_lib.baseboard_fab2(sch_1):page91_pvpp_abc") )
				( alias ( signalRef "@baseboard_fab2_lib.baseboard_fab2(sch_1):page94_pvpp_abc") )
				( alias ( signalRef "@baseboard_fab2_lib.baseboard_fab2(sch_1):page99_pvpp_abc") )
				( alias ( signalRef "@baseboard_fab2_lib.baseboard_fab2(sch_1):page192_pvpp_abc") )
				( alias ( signalRef "@baseboard_fab2_lib.baseboard_fab2(sch_1):page231_pvpp_abc") )
				( attribute "VOLTAGE" "2.5V"
					( Units "uVoltage" "V" 1.000000)
					( Status sAliasFlattened )
					( Origin gFrontEnd )
				)
				( attribute "CDS_PHYS_NET_NAME" "PVPP_ABC"
					( Origin gPackager )
				)
				( objectStatus "PVPP_ABC" )
			)
			( signal "@baseboard_fab2_lib.baseboard_fab2(sch_1):page38_pvpp_abc"
				( attribute "VOLTAGE" "2.5V"
					( Units "uVoltage" "V" 1.000000)
					( Origin gFrontEnd )
				)
				( objectFlag fObjectAlias )
				( objectStatus "page38_pvpp_abc" )
			)
			( signal "@baseboard_fab2_lib.baseboard_fab2(sch_1):page43_pvpp_abc"
				( attribute "VOLTAGE" "2.5V"
					( Units "uVoltage" "V" 1.000000)
					( Origin gFrontEnd )
				)
				( objectFlag fObjectAlias )
				( objectStatus "page43_pvpp_abc" )
			)
			( signal "@baseboard_fab2_lib.baseboard_fab2(sch_1):page44_pvpp_abc"
				( attribute "VOLTAGE" "2.5V"
					( Units "uVoltage" "V" 1.000000)
					( Origin gFrontEnd )
				)
				( objectFlag fObjectAlias )
				( objectStatus "page44_pvpp_abc" )
			)
			( signal "@baseboard_fab2_lib.baseboard_fab2(sch_1):page45_pvpp_abc"
				( attribute "VOLTAGE" "2.5V"
					( Units "uVoltage" "V" 1.000000)
					( Origin gFrontEnd )
				)
				( objectFlag fObjectAlias )
				( objectStatus "page45_pvpp_abc" )
			)
			( signal "@baseboard_fab2_lib.baseboard_fab2(sch_1):page46_pvpp_abc"
				( attribute "VOLTAGE" "2.5V"
					( Units "uVoltage" "V" 1.000000)
					( Origin gFrontEnd )
				)
				( objectFlag fObjectAlias )
				( objectStatus "page46_pvpp_abc" )
			)
			( signal "@baseboard_fab2_lib.baseboard_fab2(sch_1):page47_pvpp_abc"
				( attribute "VOLTAGE" "2.5V"
					( Units "uVoltage" "V" 1.000000)
					( Origin gFrontEnd )
				)
				( objectFlag fObjectAlias )
				( objectStatus "page47_pvpp_abc" )
			)
			( signal "@baseboard_fab2_lib.baseboard_fab2(sch_1):page48_pvpp_abc"
				( attribute "VOLTAGE" "2.5V"
					( Units "uVoltage" "V" 1.000000)
					( Origin gFrontEnd )
				)
				( objectFlag fObjectAlias )
				( objectStatus "page48_pvpp_abc" )
			)
			( signal "@baseboard_fab2_lib.baseboard_fab2(sch_1):page89_pvpp_abc"
				( attribute "VOLTAGE" "2.5V"
					( Units "uVoltage" "V" 1.000000)
					( Origin gFrontEnd )
				)
				( objectFlag fObjectAlias )
				( objectStatus "page89_pvpp_abc" )
			)
			( signal "@baseboard_fab2_lib.baseboard_fab2(sch_1):page91_pvpp_abc"
				( attribute "VOLTAGE" "2.5V"
					( Units "uVoltage" "V" 1.000000)
					( Origin gFrontEnd )
				)
				( objectFlag fObjectAlias )
				( objectStatus "page91_pvpp_abc" )
			)
			( signal "@baseboard_fab2_lib.baseboard_fab2(sch_1):page94_pvpp_abc"
				( attribute "VOLTAGE" "2.5V"
					( Units "uVoltage" "V" 1.000000)
					( Origin gFrontEnd )
				)
				( objectFlag fObjectAlias )
				( objectStatus "page94_pvpp_abc" )
			)
			( signal "@baseboard_fab2_lib.baseboard_fab2(sch_1):page99_pvpp_abc"
				( attribute "VOLTAGE" "2.5V"
					( Units "uVoltage" "V" 1.000000)
					( Origin gFrontEnd )
				)
				( objectFlag fObjectAlias )
				( objectStatus "page99_pvpp_abc" )
			)
			( signal "@baseboard_fab2_lib.baseboard_fab2(sch_1):page192_pvpp_abc"
				( attribute "VOLTAGE" "2.5V"
					( Units "uVoltage" "V" 1.000000)
					( Origin gFrontEnd )
				)
				( objectFlag fObjectAlias )
				( objectStatus "page192_pvpp_abc" )
			)
			( signal "@baseboard_fab2_lib.baseboard_fab2(sch_1):page231_pvpp_abc"
				( attribute "VOLTAGE" "2.5V"
					( Units "uVoltage" "V" 1.000000)
					( Origin gFrontEnd )
				)
				( objectFlag fObjectAlias )
				( objectStatus "page231_pvpp_abc" )
			)
			( signal "@baseboard_fab2_lib.baseboard_fab2(sch_1):pvsa_cpu0"
				( alias ( signalRef "@baseboard_fab2_lib.baseboard_fab2(sch_1):page38_pvsa_cpu0") )
				( alias ( signalRef "@baseboard_fab2_lib.baseboard_fab2(sch_1):page42_pvsa_cpu0") )
				( alias ( signalRef "@baseboard_fab2_lib.baseboard_fab2(sch_1):page205_pvsa_cpu0") )
				( attribute "VOLTAGE" "1.1V"
					( Units "uVoltage" "V" 1.000000)
					( Status sAliasFlattened )
					( Origin gFrontEnd )
				)
				( attribute "CDS_PHYS_NET_NAME" "PVSA_CPU0"
					( Origin gPackager )
				)
				( objectStatus "PVSA_CPU0" )
			)
			( signal "@baseboard_fab2_lib.baseboard_fab2(sch_1):page38_pvsa_cpu0"
				( attribute "VOLTAGE" "1.1V"
					( Units "uVoltage" "V" 1.000000)
					( Origin gFrontEnd )
				)
				( objectFlag fObjectAlias )
				( objectStatus "page38_pvsa_cpu0" )
			)
			( signal "@baseboard_fab2_lib.baseboard_fab2(sch_1):page42_pvsa_cpu0"
				( attribute "VOLTAGE" "1.1V"
					( Units "uVoltage" "V" 1.000000)
					( Origin gFrontEnd )
				)
				( objectFlag fObjectAlias )
				( objectStatus "page42_pvsa_cpu0" )
			)
			( signal "@baseboard_fab2_lib.baseboard_fab2(sch_1):page205_pvsa_cpu0"
				( attribute "VOLTAGE" "1.1V"
					( Units "uVoltage" "V" 1.000000)
					( Origin gFrontEnd )
				)
				( objectFlag fObjectAlias )
				( objectStatus "page205_pvsa_cpu0" )
			)
			( signal "@baseboard_fab2_lib.baseboard_fab2(sch_1):pd_cpu0_mcp01_dmon"
				( attribute "CDS_PHYS_NET_NAME" "PD_CPU0_MCP01_DMON"
					( Origin gPackager )
				)
				( objectStatus "PD_CPU0_MCP01_DMON" )
			)
			( signal "@baseboard_fab2_lib.baseboard_fab2(sch_1):tp_cpu0_kti2_amonv"
				( attribute "CDS_PHYS_NET_NAME" "TP_CPU0_KTI2_AMONV"
					( Origin gPackager )
				)
				( objectStatus "TP_CPU0_KTI2_AMONV" )
			)
			( signal "@baseboard_fab2_lib.baseboard_fab2(sch_1):tp_cpu0_kti2_dfx_dn"
				( attribute "CDS_PHYS_NET_NAME" "TP_CPU0_KTI2_DFX_DN"
					( Origin gPackager )
				)
				( objectStatus "TP_CPU0_KTI2_DFX_DN" )
			)
			( signal "@baseboard_fab2_lib.baseboard_fab2(sch_1):tp_cpu0_rsvd_0"
				( attribute "CDS_PHYS_NET_NAME" "TP_CPU0_RSVD_0"
					( Origin gPackager )
				)
				( objectStatus "TP_CPU0_RSVD_0" )
			)
			( signal "@baseboard_fab2_lib.baseboard_fab2(sch_1):tp_cpu0_rsvd_1"
				( attribute "CDS_PHYS_NET_NAME" "TP_CPU0_RSVD_1"
					( Origin gPackager )
				)
				( objectStatus "TP_CPU0_RSVD_1" )
			)
			( signal "@baseboard_fab2_lib.baseboard_fab2(sch_1):tp_cpu0_rsvd_10"
				( attribute "CDS_PHYS_NET_NAME" "TP_CPU0_RSVD_10"
					( Origin gPackager )
				)
				( objectStatus "TP_CPU0_RSVD_10" )
			)
			( signal "@baseboard_fab2_lib.baseboard_fab2(sch_1):tp_cpu0_rsvd_11"
				( attribute "CDS_PHYS_NET_NAME" "TP_CPU0_RSVD_11"
					( Origin gPackager )
				)
				( objectStatus "TP_CPU0_RSVD_11" )
			)
			( signal "@baseboard_fab2_lib.baseboard_fab2(sch_1):tp_cpu0_rsvd_12"
				( attribute "CDS_PHYS_NET_NAME" "TP_CPU0_RSVD_12"
					( Origin gPackager )
				)
				( objectStatus "TP_CPU0_RSVD_12" )
			)
			( signal "@baseboard_fab2_lib.baseboard_fab2(sch_1):tp_cpu0_rsvd_13"
				( attribute "CDS_PHYS_NET_NAME" "TP_CPU0_RSVD_13"
					( Origin gPackager )
				)
				( objectStatus "TP_CPU0_RSVD_13" )
			)
			( signal "@baseboard_fab2_lib.baseboard_fab2(sch_1):tp_cpu0_rsvd_14"
				( attribute "CDS_PHYS_NET_NAME" "TP_CPU0_RSVD_14"
					( Origin gPackager )
				)
				( objectStatus "TP_CPU0_RSVD_14" )
			)
			( signal "@baseboard_fab2_lib.baseboard_fab2(sch_1):tp_cpu0_rsvd_15"
				( attribute "CDS_PHYS_NET_NAME" "TP_CPU0_RSVD_15"
					( Origin gPackager )
				)
				( objectStatus "TP_CPU0_RSVD_15" )
			)
			( signal "@baseboard_fab2_lib.baseboard_fab2(sch_1):tp_cpu0_rsvd_16"
				( attribute "CDS_PHYS_NET_NAME" "TP_CPU0_RSVD_16"
					( Origin gPackager )
				)
				( objectStatus "TP_CPU0_RSVD_16" )
			)
			( signal "@baseboard_fab2_lib.baseboard_fab2(sch_1):tp_cpu0_rsvd_17"
				( attribute "CDS_PHYS_NET_NAME" "TP_CPU0_RSVD_17"
					( Origin gPackager )
				)
				( objectStatus "TP_CPU0_RSVD_17" )
			)
			( signal "@baseboard_fab2_lib.baseboard_fab2(sch_1):tp_cpu0_rsvd_18"
				( attribute "CDS_PHYS_NET_NAME" "TP_CPU0_RSVD_18"
					( Origin gPackager )
				)
				( objectStatus "TP_CPU0_RSVD_18" )
			)
			( signal "@baseboard_fab2_lib.baseboard_fab2(sch_1):tp_cpu0_rsvd_19"
				( attribute "CDS_PHYS_NET_NAME" "TP_CPU0_RSVD_19"
					( Origin gPackager )
				)
				( objectStatus "TP_CPU0_RSVD_19" )
			)
			( signal "@baseboard_fab2_lib.baseboard_fab2(sch_1):tp_cpu0_rsvd_2"
				( attribute "CDS_PHYS_NET_NAME" "TP_CPU0_RSVD_2"
					( Origin gPackager )
				)
				( objectStatus "TP_CPU0_RSVD_2" )
			)
			( signal "@baseboard_fab2_lib.baseboard_fab2(sch_1):tp_cpu0_rsvd_20"
				( attribute "CDS_PHYS_NET_NAME" "TP_CPU0_RSVD_20"
					( Origin gPackager )
				)
				( objectStatus "TP_CPU0_RSVD_20" )
			)
			( signal "@baseboard_fab2_lib.baseboard_fab2(sch_1):tp_cpu0_rsvd_21"
				( attribute "CDS_PHYS_NET_NAME" "TP_CPU0_RSVD_21"
					( Origin gPackager )
				)
				( objectStatus "TP_CPU0_RSVD_21" )
			)
			( signal "@baseboard_fab2_lib.baseboard_fab2(sch_1):tp_cpu0_rsvd_22"
				( attribute "CDS_PHYS_NET_NAME" "TP_CPU0_RSVD_22"
					( Origin gPackager )
				)
				( objectStatus "TP_CPU0_RSVD_22" )
			)
			( signal "@baseboard_fab2_lib.baseboard_fab2(sch_1):tp_cpu0_rsvd_23"
				( attribute "CDS_PHYS_NET_NAME" "TP_CPU0_RSVD_23"
					( Origin gPackager )
				)
				( objectStatus "TP_CPU0_RSVD_23" )
			)
			( signal "@baseboard_fab2_lib.baseboard_fab2(sch_1):tp_cpu0_rsvd_24"
				( attribute "CDS_PHYS_NET_NAME" "TP_CPU0_RSVD_24"
					( Origin gPackager )
				)
				( objectStatus "TP_CPU0_RSVD_24" )
			)
			( signal "@baseboard_fab2_lib.baseboard_fab2(sch_1):tp_cpu0_rsvd_25"
				( attribute "CDS_PHYS_NET_NAME" "TP_CPU0_RSVD_25"
					( Origin gPackager )
				)
				( objectStatus "TP_CPU0_RSVD_25" )
			)
			( signal "@baseboard_fab2_lib.baseboard_fab2(sch_1):tp_cpu0_rsvd_26"
				( attribute "CDS_PHYS_NET_NAME" "TP_CPU0_RSVD_26"
					( Origin gPackager )
				)
				( objectStatus "TP_CPU0_RSVD_26" )
			)
			( signal "@baseboard_fab2_lib.baseboard_fab2(sch_1):tp_cpu0_rsvd_27"
				( attribute "CDS_PHYS_NET_NAME" "TP_CPU0_RSVD_27"
					( Origin gPackager )
				)
				( objectStatus "TP_CPU0_RSVD_27" )
			)
			( signal "@baseboard_fab2_lib.baseboard_fab2(sch_1):tp_cpu0_rsvd_28"
				( attribute "CDS_PHYS_NET_NAME" "TP_CPU0_RSVD_28"
					( Origin gPackager )
				)
				( objectStatus "TP_CPU0_RSVD_28" )
			)
			( signal "@baseboard_fab2_lib.baseboard_fab2(sch_1):tp_cpu0_rsvd_29"
				( attribute "CDS_PHYS_NET_NAME" "TP_CPU0_RSVD_29"
					( Origin gPackager )
				)
				( objectStatus "TP_CPU0_RSVD_29" )
			)
			( signal "@baseboard_fab2_lib.baseboard_fab2(sch_1):tp_cpu0_rsvd_3"
				( attribute "CDS_PHYS_NET_NAME" "TP_CPU0_RSVD_3"
					( Origin gPackager )
				)
				( objectStatus "TP_CPU0_RSVD_3" )
			)
			( signal "@baseboard_fab2_lib.baseboard_fab2(sch_1):tp_cpu0_rsvd_30"
				( attribute "CDS_PHYS_NET_NAME" "TP_CPU0_RSVD_30"
					( Origin gPackager )
				)
				( objectStatus "TP_CPU0_RSVD_30" )
			)
			( signal "@baseboard_fab2_lib.baseboard_fab2(sch_1):tp_cpu0_rsvd_31"
				( attribute "CDS_PHYS_NET_NAME" "TP_CPU0_RSVD_31"
					( Origin gPackager )
				)
				( objectStatus "TP_CPU0_RSVD_31" )
			)
			( signal "@baseboard_fab2_lib.baseboard_fab2(sch_1):tp_cpu0_rsvd_32"
				( attribute "CDS_PHYS_NET_NAME" "TP_CPU0_RSVD_32"
					( Origin gPackager )
				)
				( objectStatus "TP_CPU0_RSVD_32" )
			)
			( signal "@baseboard_fab2_lib.baseboard_fab2(sch_1):tp_cpu0_rsvd_33"
				( attribute "CDS_PHYS_NET_NAME" "TP_CPU0_RSVD_33"
					( Origin gPackager )
				)
				( objectStatus "TP_CPU0_RSVD_33" )
			)
			( signal "@baseboard_fab2_lib.baseboard_fab2(sch_1):tp_cpu0_rsvd_34"
				( attribute "CDS_PHYS_NET_NAME" "TP_CPU0_RSVD_34"
					( Origin gPackager )
				)
				( objectStatus "TP_CPU0_RSVD_34" )
			)
			( signal "@baseboard_fab2_lib.baseboard_fab2(sch_1):tp_cpu0_rsvd_35"
				( attribute "CDS_PHYS_NET_NAME" "TP_CPU0_RSVD_35"
					( Origin gPackager )
				)
				( objectStatus "TP_CPU0_RSVD_35" )
			)
			( signal "@baseboard_fab2_lib.baseboard_fab2(sch_1):tp_cpu0_rsvd_36"
				( attribute "CDS_PHYS_NET_NAME" "TP_CPU0_RSVD_36"
					( Origin gPackager )
				)
				( objectStatus "TP_CPU0_RSVD_36" )
			)
			( signal "@baseboard_fab2_lib.baseboard_fab2(sch_1):tp_cpu0_rsvd_37"
				( attribute "CDS_PHYS_NET_NAME" "TP_CPU0_RSVD_37"
					( Origin gPackager )
				)
				( objectStatus "TP_CPU0_RSVD_37" )
			)
			( signal "@baseboard_fab2_lib.baseboard_fab2(sch_1):tp_cpu0_rsvd_38"
				( attribute "CDS_PHYS_NET_NAME" "TP_CPU0_RSVD_38"
					( Origin gPackager )
				)
				( objectStatus "TP_CPU0_RSVD_38" )
			)
			( signal "@baseboard_fab2_lib.baseboard_fab2(sch_1):tp_cpu0_rsvd_39"
				( attribute "CDS_PHYS_NET_NAME" "TP_CPU0_RSVD_39"
					( Origin gPackager )
				)
				( objectStatus "TP_CPU0_RSVD_39" )
			)
			( signal "@baseboard_fab2_lib.baseboard_fab2(sch_1):tp_cpu0_rsvd_4"
				( attribute "CDS_PHYS_NET_NAME" "TP_CPU0_RSVD_4"
					( Origin gPackager )
				)
				( objectStatus "TP_CPU0_RSVD_4" )
			)
			( signal "@baseboard_fab2_lib.baseboard_fab2(sch_1):tp_cpu0_rsvd_40"
				( attribute "CDS_PHYS_NET_NAME" "TP_CPU0_RSVD_40"
					( Origin gPackager )
				)
				( objectStatus "TP_CPU0_RSVD_40" )
			)
			( signal "@baseboard_fab2_lib.baseboard_fab2(sch_1):tp_cpu0_rsvd_41"
				( attribute "CDS_PHYS_NET_NAME" "TP_CPU0_RSVD_41"
					( Origin gPackager )
				)
				( objectStatus "TP_CPU0_RSVD_41" )
			)
			( signal "@baseboard_fab2_lib.baseboard_fab2(sch_1):tp_cpu0_rsvd_42"
				( attribute "CDS_PHYS_NET_NAME" "TP_CPU0_RSVD_42"
					( Origin gPackager )
				)
				( objectStatus "TP_CPU0_RSVD_42" )
			)
			( signal "@baseboard_fab2_lib.baseboard_fab2(sch_1):tp_cpu0_rsvd_43"
				( attribute "CDS_PHYS_NET_NAME" "TP_CPU0_RSVD_43"
					( Origin gPackager )
				)
				( objectStatus "TP_CPU0_RSVD_43" )
			)
			( signal "@baseboard_fab2_lib.baseboard_fab2(sch_1):tp_cpu0_rsvd_44"
				( attribute "CDS_PHYS_NET_NAME" "TP_CPU0_RSVD_44"
					( Origin gPackager )
				)
				( objectStatus "TP_CPU0_RSVD_44" )
			)
			( signal "@baseboard_fab2_lib.baseboard_fab2(sch_1):tp_cpu0_rsvd_45"
				( attribute "CDS_PHYS_NET_NAME" "TP_CPU0_RSVD_45"
					( Origin gPackager )
				)
				( objectStatus "TP_CPU0_RSVD_45" )
			)
			( signal "@baseboard_fab2_lib.baseboard_fab2(sch_1):tp_cpu0_rsvd_46"
				( attribute "CDS_PHYS_NET_NAME" "TP_CPU0_RSVD_46"
					( Origin gPackager )
				)
				( objectStatus "TP_CPU0_RSVD_46" )
			)
			( signal "@baseboard_fab2_lib.baseboard_fab2(sch_1):tp_cpu0_rsvd_47"
				( attribute "CDS_PHYS_NET_NAME" "TP_CPU0_RSVD_47"
					( Origin gPackager )
				)
				( objectStatus "TP_CPU0_RSVD_47" )
			)
			( signal "@baseboard_fab2_lib.baseboard_fab2(sch_1):tp_cpu0_rsvd_48"
				( attribute "CDS_PHYS_NET_NAME" "TP_CPU0_RSVD_48"
					( Origin gPackager )
				)
				( objectStatus "TP_CPU0_RSVD_48" )
			)
			( signal "@baseboard_fab2_lib.baseboard_fab2(sch_1):tp_cpu0_rsvd_49"
				( attribute "CDS_PHYS_NET_NAME" "TP_CPU0_RSVD_49"
					( Origin gPackager )
				)
				( objectStatus "TP_CPU0_RSVD_49" )
			)
			( signal "@baseboard_fab2_lib.baseboard_fab2(sch_1):tp_cpu0_rsvd_5"
				( attribute "CDS_PHYS_NET_NAME" "TP_CPU0_RSVD_5"
					( Origin gPackager )
				)
				( objectStatus "TP_CPU0_RSVD_5" )
			)
			( signal "@baseboard_fab2_lib.baseboard_fab2(sch_1):tp_cpu0_rsvd_50"
				( attribute "CDS_PHYS_NET_NAME" "TP_CPU0_RSVD_50"
					( Origin gPackager )
				)
				( objectStatus "TP_CPU0_RSVD_50" )
			)
			( signal "@baseboard_fab2_lib.baseboard_fab2(sch_1):tp_cpu0_rsvd_51"
				( attribute "CDS_PHYS_NET_NAME" "TP_CPU0_RSVD_51"
					( Origin gPackager )
				)
				( objectStatus "TP_CPU0_RSVD_51" )
			)
			( signal "@baseboard_fab2_lib.baseboard_fab2(sch_1):tp_cpu0_rsvd_53"
				( attribute "CDS_PHYS_NET_NAME" "TP_CPU0_RSVD_53"
					( Origin gPackager )
				)
				( objectStatus "TP_CPU0_RSVD_53" )
			)
			( signal "@baseboard_fab2_lib.baseboard_fab2(sch_1):tp_cpu0_rsvd_54"
				( attribute "CDS_PHYS_NET_NAME" "TP_CPU0_RSVD_54"
					( Origin gPackager )
				)
				( objectStatus "TP_CPU0_RSVD_54" )
			)
			( signal "@baseboard_fab2_lib.baseboard_fab2(sch_1):tp_cpu0_rsvd_55"
				( attribute "CDS_PHYS_NET_NAME" "TP_CPU0_RSVD_55"
					( Origin gPackager )
				)
				( objectStatus "TP_CPU0_RSVD_55" )
			)
			( signal "@baseboard_fab2_lib.baseboard_fab2(sch_1):tp_cpu0_rsvd_56"
				( attribute "CDS_PHYS_NET_NAME" "TP_CPU0_RSVD_56"
					( Origin gPackager )
				)
				( objectStatus "TP_CPU0_RSVD_56" )
			)
			( signal "@baseboard_fab2_lib.baseboard_fab2(sch_1):tp_cpu0_rsvd_57"
				( attribute "CDS_PHYS_NET_NAME" "TP_CPU0_RSVD_57"
					( Origin gPackager )
				)
				( objectStatus "TP_CPU0_RSVD_57" )
			)
			( signal "@baseboard_fab2_lib.baseboard_fab2(sch_1):tp_cpu0_rsvd_59"
				( attribute "CDS_PHYS_NET_NAME" "TP_CPU0_RSVD_59"
					( Origin gPackager )
				)
				( objectStatus "TP_CPU0_RSVD_59" )
			)
			( signal "@baseboard_fab2_lib.baseboard_fab2(sch_1):tp_cpu0_rsvd_6"
				( attribute "CDS_PHYS_NET_NAME" "TP_CPU0_RSVD_6"
					( Origin gPackager )
				)
				( objectStatus "TP_CPU0_RSVD_6" )
			)
			( signal "@baseboard_fab2_lib.baseboard_fab2(sch_1):tp_cpu0_rsvd_60"
				( attribute "CDS_PHYS_NET_NAME" "TP_CPU0_RSVD_60"
					( Origin gPackager )
				)
				( objectStatus "TP_CPU0_RSVD_60" )
			)
			( signal "@baseboard_fab2_lib.baseboard_fab2(sch_1):tp_cpu0_rsvd_61"
				( attribute "CDS_PHYS_NET_NAME" "TP_CPU0_RSVD_61"
					( Origin gPackager )
				)
				( objectStatus "TP_CPU0_RSVD_61" )
			)
			( signal "@baseboard_fab2_lib.baseboard_fab2(sch_1):tp_cpu0_rsvd_64"
				( attribute "CDS_PHYS_NET_NAME" "TP_CPU0_RSVD_64"
					( Origin gPackager )
				)
				( objectStatus "TP_CPU0_RSVD_64" )
			)
			( signal "@baseboard_fab2_lib.baseboard_fab2(sch_1):tp_cpu0_rsvd_66"
				( attribute "CDS_PHYS_NET_NAME" "TP_CPU0_RSVD_66"
					( Origin gPackager )
				)
				( objectStatus "TP_CPU0_RSVD_66" )
			)
			( signal "@baseboard_fab2_lib.baseboard_fab2(sch_1):tp_cpu0_rsvd_67"
				( attribute "CDS_PHYS_NET_NAME" "TP_CPU0_RSVD_67"
					( Origin gPackager )
				)
				( objectStatus "TP_CPU0_RSVD_67" )
			)
			( signal "@baseboard_fab2_lib.baseboard_fab2(sch_1):tp_cpu0_rsvd_69"
				( attribute "CDS_PHYS_NET_NAME" "TP_CPU0_RSVD_69"
					( Origin gPackager )
				)
				( objectStatus "TP_CPU0_RSVD_69" )
			)
			( signal "@baseboard_fab2_lib.baseboard_fab2(sch_1):tp_cpu0_rsvd_7"
				( attribute "CDS_PHYS_NET_NAME" "TP_CPU0_RSVD_7"
					( Origin gPackager )
				)
				( objectStatus "TP_CPU0_RSVD_7" )
			)
			( signal "@baseboard_fab2_lib.baseboard_fab2(sch_1):tp_cpu0_rsvd_70"
				( attribute "CDS_PHYS_NET_NAME" "TP_CPU0_RSVD_70"
					( Origin gPackager )
				)
				( objectStatus "TP_CPU0_RSVD_70" )
			)
			( signal "@baseboard_fab2_lib.baseboard_fab2(sch_1):tp_cpu0_rsvd_72"
				( attribute "CDS_PHYS_NET_NAME" "TP_CPU0_RSVD_72"
					( Origin gPackager )
				)
				( objectStatus "TP_CPU0_RSVD_72" )
			)
			( signal "@baseboard_fab2_lib.baseboard_fab2(sch_1):tp_cpu0_rsvd_73"
				( attribute "CDS_PHYS_NET_NAME" "TP_CPU0_RSVD_73"
					( Origin gPackager )
				)
				( objectStatus "TP_CPU0_RSVD_73" )
			)
			( signal "@baseboard_fab2_lib.baseboard_fab2(sch_1):tp_cpu0_rsvd_8"
				( attribute "CDS_PHYS_NET_NAME" "TP_CPU0_RSVD_8"
					( Origin gPackager )
				)
				( objectStatus "TP_CPU0_RSVD_8" )
			)
			( signal "@baseboard_fab2_lib.baseboard_fab2(sch_1):tp_cpu0_rsvd_9"
				( attribute "CDS_PHYS_NET_NAME" "TP_CPU0_RSVD_9"
					( Origin gPackager )
				)
				( objectStatus "TP_CPU0_RSVD_9" )
			)
			( signal "@baseboard_fab2_lib.baseboard_fab2(sch_1):vsense_pvccio_cpu0_skt_vrtn"
				( attribute "CDS_PHYS_NET_NAME" "VSENSE_PVCCIO_CPU0_SKT_VRTN"
					( Origin gPackager )
				)
				( objectStatus "VSENSE_PVCCIO_CPU0_SKT_VRTN" )
			)
			( signal "@baseboard_fab2_lib.baseboard_fab2(sch_1):vsense_pvccio_cpu0_skt_vsen"
				( attribute "CDS_PHYS_NET_NAME" "VSENSE_PVCCIO_CPU0_SKT_VSEN"
					( Origin gPackager )
				)
				( objectStatus "VSENSE_PVCCIO_CPU0_SKT_VSEN" )
			)
			( signal "@baseboard_fab2_lib.baseboard_fab2(sch_1):vsense_pvcciomcp_cpu0_skt_vrtn"
				( attribute "CDS_PHYS_NET_NAME" "VSENSE_PVCCIOMCP_CPU0_SKT_VRTN"
					( Origin gPackager )
				)
				( objectStatus "VSENSE_PVCCIOMCP_CPU0_SKT_VRTN" )
			)
			( signal "@baseboard_fab2_lib.baseboard_fab2(sch_1):vsense_pvcciomcp_cpu0_skt_vsen"
				( attribute "CDS_PHYS_NET_NAME" "VSENSE_PVCCIOMCP_CPU0_SKT_VSEN"
					( Origin gPackager )
				)
				( objectStatus "VSENSE_PVCCIOMCP_CPU0_SKT_VSEN" )
			)
			( signal "@baseboard_fab2_lib.baseboard_fab2(sch_1):vsense_pvccmcp_cpu0_skt_vrtn"
				( attribute "CDS_PHYS_NET_NAME" "VSENSE_PVCCMCP_CPU0_SKT_VRTN"
					( Origin gPackager )
				)
				( objectStatus "VSENSE_PVCCMCP_CPU0_SKT_VRTN" )
			)
			( signal "@baseboard_fab2_lib.baseboard_fab2(sch_1):vsense_pvccmcp_cpu0_skt_vsen"
				( attribute "CDS_PHYS_NET_NAME" "VSENSE_PVCCMCP_CPU0_SKT_VSEN"
					( Origin gPackager )
				)
				( objectStatus "VSENSE_PVCCMCP_CPU0_SKT_VSEN" )
			)
			( signal "@baseboard_fab2_lib.baseboard_fab2(sch_1):vsense_pvsa_cpu0_skt_vrtn"
				( attribute "CDS_PHYS_NET_NAME" "VSENSE_PVSA_CPU0_SKT_VRTN"
					( Origin gPackager )
				)
				( objectStatus "VSENSE_PVSA_CPU0_SKT_VRTN" )
			)
			( signal "@baseboard_fab2_lib.baseboard_fab2(sch_1):vsense_pvsa_cpu0_skt_vsen"
				( attribute "CDS_PHYS_NET_NAME" "VSENSE_PVSA_CPU0_SKT_VSEN"
					( Origin gPackager )
				)
				( objectStatus "VSENSE_PVSA_CPU0_SKT_VSEN" )
			)
			( signal "@baseboard_fab2_lib.baseboard_fab2(sch_1):fm_adr_complete_abc_n"
				( attribute "CDS_PHYS_NET_NAME" "FM_ADR_COMPLETE_ABC_N"
					( Origin gPackager )
				)
				( objectStatus "FM_ADR_COMPLETE_ABC_N" )
			)
			( signal "@baseboard_fab2_lib.baseboard_fab2(sch_1):fm_dimm_event_cod_n"
				( attribute "CDS_PHYS_NET_NAME" "FM_DIMM_EVENT_COD_N"
					( Origin gPackager )
				)
				( objectStatus "FM_DIMM_EVENT_COD_N" )
			)
			( signal "@baseboard_fab2_lib.baseboard_fab2(sch_1):m_a_vref"
				( attribute "CDS_PHYS_NET_NAME" "M_A_VREF"
					( Origin gPackager )
				)
				( objectStatus "M_A_VREF" )
			)
			( signal "@baseboard_fab2_lib.baseboard_fab2(sch_1):p12v_nvdimm_abc"
				( alias ( signalRef "@baseboard_fab2_lib.baseboard_fab2(sch_1):page43_p12v_nvdimm_abc") )
				( alias ( signalRef "@baseboard_fab2_lib.baseboard_fab2(sch_1):page44_p12v_nvdimm_abc") )
				( alias ( signalRef "@baseboard_fab2_lib.baseboard_fab2(sch_1):page45_p12v_nvdimm_abc") )
				( alias ( signalRef "@baseboard_fab2_lib.baseboard_fab2(sch_1):page46_p12v_nvdimm_abc") )
				( alias ( signalRef "@baseboard_fab2_lib.baseboard_fab2(sch_1):page47_p12v_nvdimm_abc") )
				( alias ( signalRef "@baseboard_fab2_lib.baseboard_fab2(sch_1):page48_p12v_nvdimm_abc") )
				( alias ( signalRef "@baseboard_fab2_lib.baseboard_fab2(sch_1):page197_p12v_nvdimm_abc") )
				( attribute "VOLTAGE" "12.0"
					( Units "uVoltage" "V" 1.000000)
					( Status sAliasFlattened )
					( Origin gFrontEnd )
				)
				( attribute "CDS_PHYS_NET_NAME" "P12V_NVDIMM_ABC"
					( Origin gPackager )
				)
				( objectStatus "P12V_NVDIMM_ABC" )
			)
			( signal "@baseboard_fab2_lib.baseboard_fab2(sch_1):page43_p12v_nvdimm_abc"
				( attribute "VOLTAGE" "12.0"
					( Units "uVoltage" "V" 1.000000)
					( Origin gFrontEnd )
				)
				( objectFlag fObjectAlias )
				( objectStatus "page43_p12v_nvdimm_abc" )
			)
			( signal "@baseboard_fab2_lib.baseboard_fab2(sch_1):page44_p12v_nvdimm_abc"
				( attribute "VOLTAGE" "12.0"
					( Units "uVoltage" "V" 1.000000)
					( Origin gFrontEnd )
				)
				( objectFlag fObjectAlias )
				( objectStatus "page44_p12v_nvdimm_abc" )
			)
			( signal "@baseboard_fab2_lib.baseboard_fab2(sch_1):page45_p12v_nvdimm_abc"
				( attribute "VOLTAGE" "12.0"
					( Units "uVoltage" "V" 1.000000)
					( Origin gFrontEnd )
				)
				( objectFlag fObjectAlias )
				( objectStatus "page45_p12v_nvdimm_abc" )
			)
			( signal "@baseboard_fab2_lib.baseboard_fab2(sch_1):page46_p12v_nvdimm_abc"
				( attribute "VOLTAGE" "12.0"
					( Units "uVoltage" "V" 1.000000)
					( Origin gFrontEnd )
				)
				( objectFlag fObjectAlias )
				( objectStatus "page46_p12v_nvdimm_abc" )
			)
			( signal "@baseboard_fab2_lib.baseboard_fab2(sch_1):page47_p12v_nvdimm_abc"
				( attribute "VOLTAGE" "12.0"
					( Units "uVoltage" "V" 1.000000)
					( Origin gFrontEnd )
				)
				( objectFlag fObjectAlias )
				( objectStatus "page47_p12v_nvdimm_abc" )
			)
			( signal "@baseboard_fab2_lib.baseboard_fab2(sch_1):page48_p12v_nvdimm_abc"
				( attribute "VOLTAGE" "12.0"
					( Units "uVoltage" "V" 1.000000)
					( Origin gFrontEnd )
				)
				( objectFlag fObjectAlias )
				( objectStatus "page48_p12v_nvdimm_abc" )
			)
			( signal "@baseboard_fab2_lib.baseboard_fab2(sch_1):page197_p12v_nvdimm_abc"
				( attribute "VOLTAGE" "12.0"
					( Units "uVoltage" "V" 1.000000)
					( Origin gFrontEnd )
				)
				( objectFlag fObjectAlias )
				( objectStatus "page197_p12v_nvdimm_abc" )
			)
			( signal "@baseboard_fab2_lib.baseboard_fab2(sch_1):pvtt_abc"
				( alias ( signalRef "@baseboard_fab2_lib.baseboard_fab2(sch_1):page43_pvtt_abc") )
				( alias ( signalRef "@baseboard_fab2_lib.baseboard_fab2(sch_1):page44_pvtt_abc") )
				( alias ( signalRef "@baseboard_fab2_lib.baseboard_fab2(sch_1):page45_pvtt_abc") )
				( alias ( signalRef "@baseboard_fab2_lib.baseboard_fab2(sch_1):page46_pvtt_abc") )
				( alias ( signalRef "@baseboard_fab2_lib.baseboard_fab2(sch_1):page47_pvtt_abc") )
				( alias ( signalRef "@baseboard_fab2_lib.baseboard_fab2(sch_1):page48_pvtt_abc") )
				( alias ( signalRef "@baseboard_fab2_lib.baseboard_fab2(sch_1):page221_pvtt_abc") )
				( attribute "VOLTAGE" "0.6V"
					( Units "uVoltage" "V" 1.000000)
					( Status sAliasFlattened )
					( Origin gFrontEnd )
				)
				( attribute "CDS_PHYS_NET_NAME" "PVTT_ABC"
					( Origin gPackager )
				)
				( objectStatus "PVTT_ABC" )
			)
			( signal "@baseboard_fab2_lib.baseboard_fab2(sch_1):page43_pvtt_abc"
				( attribute "VOLTAGE" "0.6V"
					( Units "uVoltage" "V" 1.000000)
					( Origin gFrontEnd )
				)
				( objectFlag fObjectAlias )
				( objectStatus "page43_pvtt_abc" )
			)
			( signal "@baseboard_fab2_lib.baseboard_fab2(sch_1):page44_pvtt_abc"
				( attribute "VOLTAGE" "0.6V"
					( Units "uVoltage" "V" 1.000000)
					( Origin gFrontEnd )
				)
				( objectFlag fObjectAlias )
				( objectStatus "page44_pvtt_abc" )
			)
			( signal "@baseboard_fab2_lib.baseboard_fab2(sch_1):page45_pvtt_abc"
				( attribute "VOLTAGE" "0.6V"
					( Units "uVoltage" "V" 1.000000)
					( Origin gFrontEnd )
				)
				( objectFlag fObjectAlias )
				( objectStatus "page45_pvtt_abc" )
			)
			( signal "@baseboard_fab2_lib.baseboard_fab2(sch_1):page46_pvtt_abc"
				( attribute "VOLTAGE" "0.6V"
					( Units "uVoltage" "V" 1.000000)
					( Origin gFrontEnd )
				)
				( objectFlag fObjectAlias )
				( objectStatus "page46_pvtt_abc" )
			)
			( signal "@baseboard_fab2_lib.baseboard_fab2(sch_1):page47_pvtt_abc"
				( attribute "VOLTAGE" "0.6V"
					( Units "uVoltage" "V" 1.000000)
					( Origin gFrontEnd )
				)
				( objectFlag fObjectAlias )
				( objectStatus "page47_pvtt_abc" )
			)
			( signal "@baseboard_fab2_lib.baseboard_fab2(sch_1):page48_pvtt_abc"
				( attribute "VOLTAGE" "0.6V"
					( Units "uVoltage" "V" 1.000000)
					( Origin gFrontEnd )
				)
				( objectFlag fObjectAlias )
				( objectStatus "page48_pvtt_abc" )
			)
			( signal "@baseboard_fab2_lib.baseboard_fab2(sch_1):page221_pvtt_abc"
				( attribute "VOLTAGE" "0.6V"
					( Units "uVoltage" "V" 1.000000)
					( Origin gFrontEnd )
				)
				( objectFlag fObjectAlias )
				( objectStatus "page221_pvtt_abc" )
			)
			( signal "@baseboard_fab2_lib.baseboard_fab2(sch_1):smb_ddr_abc_vpp_scl"
				( attribute "CDS_PHYS_NET_NAME" "SMB_DDR_ABC_VPP_SCL"
					( Origin gPackager )
				)
				( objectStatus "SMB_DDR_ABC_VPP_SCL" )
			)
			( signal "@baseboard_fab2_lib.baseboard_fab2(sch_1):smb_ddr_abc_vpp_sda"
				( attribute "CDS_PHYS_NET_NAME" "SMB_DDR_ABC_VPP_SDA"
					( Origin gPackager )
				)
				( objectStatus "SMB_DDR_ABC_VPP_SDA" )
			)
			( signal "@baseboard_fab2_lib.baseboard_fab2(sch_1):tp_ch_a_dimm_a0_rfu_0"
				( attribute "CDS_PHYS_NET_NAME" "TP_CH_A_DIMM_A0_RFU_0"
					( Origin gPackager )
				)
				( objectStatus "TP_CH_A_DIMM_A0_RFU_0" )
			)
			( signal "@baseboard_fab2_lib.baseboard_fab2(sch_1):tp_ch_a_dimm_a0_rfu_1"
				( attribute "CDS_PHYS_NET_NAME" "TP_CH_A_DIMM_A0_RFU_1"
					( Origin gPackager )
				)
				( objectStatus "TP_CH_A_DIMM_A0_RFU_1" )
			)
			( signal "@baseboard_fab2_lib.baseboard_fab2(sch_1):tp_ch_a_dimm_a0_rfu_2"
				( attribute "CDS_PHYS_NET_NAME" "TP_CH_A_DIMM_A0_RFU_2"
					( Origin gPackager )
				)
				( objectStatus "TP_CH_A_DIMM_A0_RFU_2" )
			)
			( signal "@baseboard_fab2_lib.baseboard_fab2(sch_1):tp_ch_a_dimm_a1_rfu_0"
				( attribute "CDS_PHYS_NET_NAME" "TP_CH_A_DIMM_A1_RFU_0"
					( Origin gPackager )
				)
				( objectStatus "TP_CH_A_DIMM_A1_RFU_0" )
			)
			( signal "@baseboard_fab2_lib.baseboard_fab2(sch_1):tp_ch_a_dimm_a1_rfu_1"
				( attribute "CDS_PHYS_NET_NAME" "TP_CH_A_DIMM_A1_RFU_1"
					( Origin gPackager )
				)
				( objectStatus "TP_CH_A_DIMM_A1_RFU_1" )
			)
			( signal "@baseboard_fab2_lib.baseboard_fab2(sch_1):tp_ch_a_dimm_a1_rfu_2"
				( attribute "CDS_PHYS_NET_NAME" "TP_CH_A_DIMM_A1_RFU_2"
					( Origin gPackager )
				)
				( objectStatus "TP_CH_A_DIMM_A1_RFU_2" )
			)
			( signal "@baseboard_fab2_lib.baseboard_fab2(sch_1):m_b_vref"
				( attribute "CDS_PHYS_NET_NAME" "M_B_VREF"
					( Origin gPackager )
				)
				( objectStatus "M_B_VREF" )
			)
			( signal "@baseboard_fab2_lib.baseboard_fab2(sch_1):tp_ch_b_dimm_b0_rfu_0"
				( attribute "CDS_PHYS_NET_NAME" "TP_CH_B_DIMM_B0_RFU_0"
					( Origin gPackager )
				)
				( objectStatus "TP_CH_B_DIMM_B0_RFU_0" )
			)
			( signal "@baseboard_fab2_lib.baseboard_fab2(sch_1):tp_ch_b_dimm_b0_rfu_1"
				( attribute "CDS_PHYS_NET_NAME" "TP_CH_B_DIMM_B0_RFU_1"
					( Origin gPackager )
				)
				( objectStatus "TP_CH_B_DIMM_B0_RFU_1" )
			)
			( signal "@baseboard_fab2_lib.baseboard_fab2(sch_1):tp_ch_b_dimm_b0_rfu_2"
				( attribute "CDS_PHYS_NET_NAME" "TP_CH_B_DIMM_B0_RFU_2"
					( Origin gPackager )
				)
				( objectStatus "TP_CH_B_DIMM_B0_RFU_2" )
			)
			( signal "@baseboard_fab2_lib.baseboard_fab2(sch_1):tp_ch_b_dimm_b1_rfu_0"
				( attribute "CDS_PHYS_NET_NAME" "TP_CH_B_DIMM_B1_RFU_0"
					( Origin gPackager )
				)
				( objectStatus "TP_CH_B_DIMM_B1_RFU_0" )
			)
			( signal "@baseboard_fab2_lib.baseboard_fab2(sch_1):tp_ch_b_dimm_b1_rfu_1"
				( attribute "CDS_PHYS_NET_NAME" "TP_CH_B_DIMM_B1_RFU_1"
					( Origin gPackager )
				)
				( objectStatus "TP_CH_B_DIMM_B1_RFU_1" )
			)
			( signal "@baseboard_fab2_lib.baseboard_fab2(sch_1):tp_ch_b_dimm_b1_rfu_2"
				( attribute "CDS_PHYS_NET_NAME" "TP_CH_B_DIMM_B1_RFU_2"
					( Origin gPackager )
				)
				( objectStatus "TP_CH_B_DIMM_B1_RFU_2" )
			)
			( signal "@baseboard_fab2_lib.baseboard_fab2(sch_1):m_c_vref"
				( attribute "CDS_PHYS_NET_NAME" "M_C_VREF"
					( Origin gPackager )
				)
				( objectStatus "M_C_VREF" )
			)
			( signal "@baseboard_fab2_lib.baseboard_fab2(sch_1):tp_ch_c_dimm_c0_rfu_0"
				( attribute "CDS_PHYS_NET_NAME" "TP_CH_C_DIMM_C0_RFU_0"
					( Origin gPackager )
				)
				( objectStatus "TP_CH_C_DIMM_C0_RFU_0" )
			)
			( signal "@baseboard_fab2_lib.baseboard_fab2(sch_1):tp_ch_c_dimm_c0_rfu_1"
				( attribute "CDS_PHYS_NET_NAME" "TP_CH_C_DIMM_C0_RFU_1"
					( Origin gPackager )
				)
				( objectStatus "TP_CH_C_DIMM_C0_RFU_1" )
			)
			( signal "@baseboard_fab2_lib.baseboard_fab2(sch_1):tp_ch_c_dimm_c0_rfu_2"
				( attribute "CDS_PHYS_NET_NAME" "TP_CH_C_DIMM_C0_RFU_2"
					( Origin gPackager )
				)
				( objectStatus "TP_CH_C_DIMM_C0_RFU_2" )
			)
			( signal "@baseboard_fab2_lib.baseboard_fab2(sch_1):tp_ch_c_dimm_c1_rfu_0"
				( attribute "CDS_PHYS_NET_NAME" "TP_CH_C_DIMM_C1_RFU_0"
					( Origin gPackager )
				)
				( objectStatus "TP_CH_C_DIMM_C1_RFU_0" )
			)
			( signal "@baseboard_fab2_lib.baseboard_fab2(sch_1):tp_ch_c_dimm_c1_rfu_1"
				( attribute "CDS_PHYS_NET_NAME" "TP_CH_C_DIMM_C1_RFU_1"
					( Origin gPackager )
				)
				( objectStatus "TP_CH_C_DIMM_C1_RFU_1" )
			)
			( signal "@baseboard_fab2_lib.baseboard_fab2(sch_1):tp_ch_c_dimm_c1_rfu_2"
				( attribute "CDS_PHYS_NET_NAME" "TP_CH_C_DIMM_C1_RFU_2"
					( Origin gPackager )
				)
				( objectStatus "TP_CH_C_DIMM_C1_RFU_2" )
			)
			( signal "@baseboard_fab2_lib.baseboard_fab2(sch_1):fm_adr_complete_def_n"
				( attribute "CDS_PHYS_NET_NAME" "FM_ADR_COMPLETE_DEF_N"
					( Origin gPackager )
				)
				( objectStatus "FM_ADR_COMPLETE_DEF_N" )
			)
			( signal "@baseboard_fab2_lib.baseboard_fab2(sch_1):m_d_vref"
				( attribute "CDS_PHYS_NET_NAME" "M_D_VREF"
					( Origin gPackager )
				)
				( objectStatus "M_D_VREF" )
			)
			( signal "@baseboard_fab2_lib.baseboard_fab2(sch_1):p12v_nvdimm_def"
				( alias ( signalRef "@baseboard_fab2_lib.baseboard_fab2(sch_1):page49_p12v_nvdimm_def") )
				( alias ( signalRef "@baseboard_fab2_lib.baseboard_fab2(sch_1):page50_p12v_nvdimm_def") )
				( alias ( signalRef "@baseboard_fab2_lib.baseboard_fab2(sch_1):page51_p12v_nvdimm_def") )
				( alias ( signalRef "@baseboard_fab2_lib.baseboard_fab2(sch_1):page52_p12v_nvdimm_def") )
				( alias ( signalRef "@baseboard_fab2_lib.baseboard_fab2(sch_1):page53_p12v_nvdimm_def") )
				( alias ( signalRef "@baseboard_fab2_lib.baseboard_fab2(sch_1):page54_p12v_nvdimm_def") )
				( alias ( signalRef "@baseboard_fab2_lib.baseboard_fab2(sch_1):page197_p12v_nvdimm_def") )
				( attribute "VOLTAGE" "12.0"
					( Units "uVoltage" "V" 1.000000)
					( Status sAliasFlattened )
					( Origin gFrontEnd )
				)
				( attribute "CDS_PHYS_NET_NAME" "P12V_NVDIMM_DEF"
					( Origin gPackager )
				)
				( objectStatus "P12V_NVDIMM_DEF" )
			)
			( signal "@baseboard_fab2_lib.baseboard_fab2(sch_1):page49_p12v_nvdimm_def"
				( attribute "VOLTAGE" "12.0"
					( Units "uVoltage" "V" 1.000000)
					( Origin gFrontEnd )
				)
				( objectFlag fObjectAlias )
				( objectStatus "page49_p12v_nvdimm_def" )
			)
			( signal "@baseboard_fab2_lib.baseboard_fab2(sch_1):page50_p12v_nvdimm_def"
				( attribute "VOLTAGE" "12.0"
					( Units "uVoltage" "V" 1.000000)
					( Origin gFrontEnd )
				)
				( objectFlag fObjectAlias )
				( objectStatus "page50_p12v_nvdimm_def" )
			)
			( signal "@baseboard_fab2_lib.baseboard_fab2(sch_1):page51_p12v_nvdimm_def"
				( attribute "VOLTAGE" "12.0"
					( Units "uVoltage" "V" 1.000000)
					( Origin gFrontEnd )
				)
				( objectFlag fObjectAlias )
				( objectStatus "page51_p12v_nvdimm_def" )
			)
			( signal "@baseboard_fab2_lib.baseboard_fab2(sch_1):page52_p12v_nvdimm_def"
				( attribute "VOLTAGE" "12.0"
					( Units "uVoltage" "V" 1.000000)
					( Origin gFrontEnd )
				)
				( objectFlag fObjectAlias )
				( objectStatus "page52_p12v_nvdimm_def" )
			)
			( signal "@baseboard_fab2_lib.baseboard_fab2(sch_1):page53_p12v_nvdimm_def"
				( attribute "VOLTAGE" "12.0"
					( Units "uVoltage" "V" 1.000000)
					( Origin gFrontEnd )
				)
				( objectFlag fObjectAlias )
				( objectStatus "page53_p12v_nvdimm_def" )
			)
			( signal "@baseboard_fab2_lib.baseboard_fab2(sch_1):page54_p12v_nvdimm_def"
				( attribute "VOLTAGE" "12.0"
					( Units "uVoltage" "V" 1.000000)
					( Origin gFrontEnd )
				)
				( objectFlag fObjectAlias )
				( objectStatus "page54_p12v_nvdimm_def" )
			)
			( signal "@baseboard_fab2_lib.baseboard_fab2(sch_1):page197_p12v_nvdimm_def"
				( attribute "VOLTAGE" "12.0"
					( Units "uVoltage" "V" 1.000000)
					( Origin gFrontEnd )
				)
				( objectFlag fObjectAlias )
				( objectStatus "page197_p12v_nvdimm_def" )
			)
			( signal "@baseboard_fab2_lib.baseboard_fab2(sch_1):pvpp_def"
				( alias ( signalRef "@baseboard_fab2_lib.baseboard_fab2(sch_1):page49_pvpp_def") )
				( alias ( signalRef "@baseboard_fab2_lib.baseboard_fab2(sch_1):page50_pvpp_def") )
				( alias ( signalRef "@baseboard_fab2_lib.baseboard_fab2(sch_1):page51_pvpp_def") )
				( alias ( signalRef "@baseboard_fab2_lib.baseboard_fab2(sch_1):page52_pvpp_def") )
				( alias ( signalRef "@baseboard_fab2_lib.baseboard_fab2(sch_1):page53_pvpp_def") )
				( alias ( signalRef "@baseboard_fab2_lib.baseboard_fab2(sch_1):page54_pvpp_def") )
				( alias ( signalRef "@baseboard_fab2_lib.baseboard_fab2(sch_1):page99_pvpp_def") )
				( alias ( signalRef "@baseboard_fab2_lib.baseboard_fab2(sch_1):page232_pvpp_def") )
				( attribute "VOLTAGE" "2.5V"
					( Units "uVoltage" "V" 1.000000)
					( Status sAliasFlattened )
					( Origin gFrontEnd )
				)
				( attribute "CDS_PHYS_NET_NAME" "PVPP_DEF"
					( Origin gPackager )
				)
				( objectStatus "PVPP_DEF" )
			)
			( signal "@baseboard_fab2_lib.baseboard_fab2(sch_1):page49_pvpp_def"
				( attribute "VOLTAGE" "2.5V"
					( Units "uVoltage" "V" 1.000000)
					( Origin gFrontEnd )
				)
				( objectFlag fObjectAlias )
				( objectStatus "page49_pvpp_def" )
			)
			( signal "@baseboard_fab2_lib.baseboard_fab2(sch_1):page50_pvpp_def"
				( attribute "VOLTAGE" "2.5V"
					( Units "uVoltage" "V" 1.000000)
					( Origin gFrontEnd )
				)
				( objectFlag fObjectAlias )
				( objectStatus "page50_pvpp_def" )
			)
			( signal "@baseboard_fab2_lib.baseboard_fab2(sch_1):page51_pvpp_def"
				( attribute "VOLTAGE" "2.5V"
					( Units "uVoltage" "V" 1.000000)
					( Origin gFrontEnd )
				)
				( objectFlag fObjectAlias )
				( objectStatus "page51_pvpp_def" )
			)
			( signal "@baseboard_fab2_lib.baseboard_fab2(sch_1):page52_pvpp_def"
				( attribute "VOLTAGE" "2.5V"
					( Units "uVoltage" "V" 1.000000)
					( Origin gFrontEnd )
				)
				( objectFlag fObjectAlias )
				( objectStatus "page52_pvpp_def" )
			)
			( signal "@baseboard_fab2_lib.baseboard_fab2(sch_1):page53_pvpp_def"
				( attribute "VOLTAGE" "2.5V"
					( Units "uVoltage" "V" 1.000000)
					( Origin gFrontEnd )
				)
				( objectFlag fObjectAlias )
				( objectStatus "page53_pvpp_def" )
			)
			( signal "@baseboard_fab2_lib.baseboard_fab2(sch_1):page54_pvpp_def"
				( attribute "VOLTAGE" "2.5V"
					( Units "uVoltage" "V" 1.000000)
					( Origin gFrontEnd )
				)
				( objectFlag fObjectAlias )
				( objectStatus "page54_pvpp_def" )
			)
			( signal "@baseboard_fab2_lib.baseboard_fab2(sch_1):page99_pvpp_def"
				( attribute "VOLTAGE" "2.5V"
					( Units "uVoltage" "V" 1.000000)
					( Origin gFrontEnd )
				)
				( objectFlag fObjectAlias )
				( objectStatus "page99_pvpp_def" )
			)
			( signal "@baseboard_fab2_lib.baseboard_fab2(sch_1):page232_pvpp_def"
				( attribute "VOLTAGE" "2.5V"
					( Units "uVoltage" "V" 1.000000)
					( Origin gFrontEnd )
				)
				( objectFlag fObjectAlias )
				( objectStatus "page232_pvpp_def" )
			)
			( signal "@baseboard_fab2_lib.baseboard_fab2(sch_1):pvtt_def"
				( alias ( signalRef "@baseboard_fab2_lib.baseboard_fab2(sch_1):page49_pvtt_def") )
				( alias ( signalRef "@baseboard_fab2_lib.baseboard_fab2(sch_1):page50_pvtt_def") )
				( alias ( signalRef "@baseboard_fab2_lib.baseboard_fab2(sch_1):page51_pvtt_def") )
				( alias ( signalRef "@baseboard_fab2_lib.baseboard_fab2(sch_1):page52_pvtt_def") )
				( alias ( signalRef "@baseboard_fab2_lib.baseboard_fab2(sch_1):page53_pvtt_def") )
				( alias ( signalRef "@baseboard_fab2_lib.baseboard_fab2(sch_1):page54_pvtt_def") )
				( alias ( signalRef "@baseboard_fab2_lib.baseboard_fab2(sch_1):page222_pvtt_def") )
				( attribute "VOLTAGE" "0.6V"
					( Units "uVoltage" "V" 1.000000)
					( Status sAliasFlattened )
					( Origin gFrontEnd )
				)
				( attribute "CDS_PHYS_NET_NAME" "PVTT_DEF"
					( Origin gPackager )
				)
				( objectStatus "PVTT_DEF" )
			)
			( signal "@baseboard_fab2_lib.baseboard_fab2(sch_1):page49_pvtt_def"
				( attribute "VOLTAGE" "0.6V"
					( Units "uVoltage" "V" 1.000000)
					( Origin gFrontEnd )
				)
				( objectFlag fObjectAlias )
				( objectStatus "page49_pvtt_def" )
			)
			( signal "@baseboard_fab2_lib.baseboard_fab2(sch_1):page50_pvtt_def"
				( attribute "VOLTAGE" "0.6V"
					( Units "uVoltage" "V" 1.000000)
					( Origin gFrontEnd )
				)
				( objectFlag fObjectAlias )
				( objectStatus "page50_pvtt_def" )
			)
			( signal "@baseboard_fab2_lib.baseboard_fab2(sch_1):page51_pvtt_def"
				( attribute "VOLTAGE" "0.6V"
					( Units "uVoltage" "V" 1.000000)
					( Origin gFrontEnd )
				)
				( objectFlag fObjectAlias )
				( objectStatus "page51_pvtt_def" )
			)
			( signal "@baseboard_fab2_lib.baseboard_fab2(sch_1):page52_pvtt_def"
				( attribute "VOLTAGE" "0.6V"
					( Units "uVoltage" "V" 1.000000)
					( Origin gFrontEnd )
				)
				( objectFlag fObjectAlias )
				( objectStatus "page52_pvtt_def" )
			)
			( signal "@baseboard_fab2_lib.baseboard_fab2(sch_1):page53_pvtt_def"
				( attribute "VOLTAGE" "0.6V"
					( Units "uVoltage" "V" 1.000000)
					( Origin gFrontEnd )
				)
				( objectFlag fObjectAlias )
				( objectStatus "page53_pvtt_def" )
			)
			( signal "@baseboard_fab2_lib.baseboard_fab2(sch_1):page54_pvtt_def"
				( attribute "VOLTAGE" "0.6V"
					( Units "uVoltage" "V" 1.000000)
					( Origin gFrontEnd )
				)
				( objectFlag fObjectAlias )
				( objectStatus "page54_pvtt_def" )
			)
			( signal "@baseboard_fab2_lib.baseboard_fab2(sch_1):page222_pvtt_def"
				( attribute "VOLTAGE" "0.6V"
					( Units "uVoltage" "V" 1.000000)
					( Origin gFrontEnd )
				)
				( objectFlag fObjectAlias )
				( objectStatus "page222_pvtt_def" )
			)
			( signal "@baseboard_fab2_lib.baseboard_fab2(sch_1):smb_ddr_def_vpp_scl"
				( attribute "CDS_PHYS_NET_NAME" "SMB_DDR_DEF_VPP_SCL"
					( Origin gPackager )
				)
				( objectStatus "SMB_DDR_DEF_VPP_SCL" )
			)
			( signal "@baseboard_fab2_lib.baseboard_fab2(sch_1):smb_ddr_def_vpp_sda"
				( attribute "CDS_PHYS_NET_NAME" "SMB_DDR_DEF_VPP_SDA"
					( Origin gPackager )
				)
				( objectStatus "SMB_DDR_DEF_VPP_SDA" )
			)
			( signal "@baseboard_fab2_lib.baseboard_fab2(sch_1):tp_ch_d_dimm_d0_rfu_0"
				( attribute "CDS_PHYS_NET_NAME" "TP_CH_D_DIMM_D0_RFU_0"
					( Origin gPackager )
				)
				( objectStatus "TP_CH_D_DIMM_D0_RFU_0" )
			)
			( signal "@baseboard_fab2_lib.baseboard_fab2(sch_1):tp_ch_d_dimm_d0_rfu_1"
				( attribute "CDS_PHYS_NET_NAME" "TP_CH_D_DIMM_D0_RFU_1"
					( Origin gPackager )
				)
				( objectStatus "TP_CH_D_DIMM_D0_RFU_1" )
			)
			( signal "@baseboard_fab2_lib.baseboard_fab2(sch_1):tp_ch_d_dimm_d0_rfu_2"
				( attribute "CDS_PHYS_NET_NAME" "TP_CH_D_DIMM_D0_RFU_2"
					( Origin gPackager )
				)
				( objectStatus "TP_CH_D_DIMM_D0_RFU_2" )
			)
			( signal "@baseboard_fab2_lib.baseboard_fab2(sch_1):tp_ch_d_dimm_d1_rfu_0"
				( attribute "CDS_PHYS_NET_NAME" "TP_CH_D_DIMM_D1_RFU_0"
					( Origin gPackager )
				)
				( objectStatus "TP_CH_D_DIMM_D1_RFU_0" )
			)
			( signal "@baseboard_fab2_lib.baseboard_fab2(sch_1):tp_ch_d_dimm_d1_rfu_1"
				( attribute "CDS_PHYS_NET_NAME" "TP_CH_D_DIMM_D1_RFU_1"
					( Origin gPackager )
				)
				( objectStatus "TP_CH_D_DIMM_D1_RFU_1" )
			)
			( signal "@baseboard_fab2_lib.baseboard_fab2(sch_1):tp_ch_d_dimm_d1_rfu_2"
				( attribute "CDS_PHYS_NET_NAME" "TP_CH_D_DIMM_D1_RFU_2"
					( Origin gPackager )
				)
				( objectStatus "TP_CH_D_DIMM_D1_RFU_2" )
			)
			( signal "@baseboard_fab2_lib.baseboard_fab2(sch_1):m_e_vref"
				( attribute "CDS_PHYS_NET_NAME" "M_E_VREF"
					( Origin gPackager )
				)
				( objectStatus "M_E_VREF" )
			)
			( signal "@baseboard_fab2_lib.baseboard_fab2(sch_1):tp_ch_e_dimm_e0_rfu_0"
				( attribute "CDS_PHYS_NET_NAME" "TP_CH_E_DIMM_E0_RFU_0"
					( Origin gPackager )
				)
				( objectStatus "TP_CH_E_DIMM_E0_RFU_0" )
			)
			( signal "@baseboard_fab2_lib.baseboard_fab2(sch_1):tp_ch_e_dimm_e0_rfu_1"
				( attribute "CDS_PHYS_NET_NAME" "TP_CH_E_DIMM_E0_RFU_1"
					( Origin gPackager )
				)
				( objectStatus "TP_CH_E_DIMM_E0_RFU_1" )
			)
			( signal "@baseboard_fab2_lib.baseboard_fab2(sch_1):tp_ch_e_dimm_e0_rfu_2"
				( attribute "CDS_PHYS_NET_NAME" "TP_CH_E_DIMM_E0_RFU_2"
					( Origin gPackager )
				)
				( objectStatus "TP_CH_E_DIMM_E0_RFU_2" )
			)
			( signal "@baseboard_fab2_lib.baseboard_fab2(sch_1):tp_ch_e_dimm_e1_rfu_0"
				( attribute "CDS_PHYS_NET_NAME" "TP_CH_E_DIMM_E1_RFU_0"
					( Origin gPackager )
				)
				( objectStatus "TP_CH_E_DIMM_E1_RFU_0" )
			)
			( signal "@baseboard_fab2_lib.baseboard_fab2(sch_1):tp_ch_e_dimm_e1_rfu_1"
				( attribute "CDS_PHYS_NET_NAME" "TP_CH_E_DIMM_E1_RFU_1"
					( Origin gPackager )
				)
				( objectStatus "TP_CH_E_DIMM_E1_RFU_1" )
			)
			( signal "@baseboard_fab2_lib.baseboard_fab2(sch_1):tp_ch_e_dimm_e1_rfu_2"
				( attribute "CDS_PHYS_NET_NAME" "TP_CH_E_DIMM_E1_RFU_2"
					( Origin gPackager )
				)
				( objectStatus "TP_CH_E_DIMM_E1_RFU_2" )
			)
			( signal "@baseboard_fab2_lib.baseboard_fab2(sch_1):m_f_vref"
				( attribute "CDS_PHYS_NET_NAME" "M_F_VREF"
					( Origin gPackager )
				)
				( objectStatus "M_F_VREF" )
			)
			( signal "@baseboard_fab2_lib.baseboard_fab2(sch_1):tp_ch_f_dimm_f0_rfu_0"
				( attribute "CDS_PHYS_NET_NAME" "TP_CH_F_DIMM_F0_RFU_0"
					( Origin gPackager )
				)
				( objectStatus "TP_CH_F_DIMM_F0_RFU_0" )
			)
			( signal "@baseboard_fab2_lib.baseboard_fab2(sch_1):tp_ch_f_dimm_f0_rfu_1"
				( attribute "CDS_PHYS_NET_NAME" "TP_CH_F_DIMM_F0_RFU_1"
					( Origin gPackager )
				)
				( objectStatus "TP_CH_F_DIMM_F0_RFU_1" )
			)
			( signal "@baseboard_fab2_lib.baseboard_fab2(sch_1):tp_ch_f_dimm_f0_rfu_2"
				( attribute "CDS_PHYS_NET_NAME" "TP_CH_F_DIMM_F0_RFU_2"
					( Origin gPackager )
				)
				( objectStatus "TP_CH_F_DIMM_F0_RFU_2" )
			)
			( signal "@baseboard_fab2_lib.baseboard_fab2(sch_1):tp_ch_f_dimm_f1_rfu_0"
				( attribute "CDS_PHYS_NET_NAME" "TP_CH_F_DIMM_F1_RFU_0"
					( Origin gPackager )
				)
				( objectStatus "TP_CH_F_DIMM_F1_RFU_0" )
			)
			( signal "@baseboard_fab2_lib.baseboard_fab2(sch_1):tp_ch_f_dimm_f1_rfu_1"
				( attribute "CDS_PHYS_NET_NAME" "TP_CH_F_DIMM_F1_RFU_1"
					( Origin gPackager )
				)
				( objectStatus "TP_CH_F_DIMM_F1_RFU_1" )
			)
			( signal "@baseboard_fab2_lib.baseboard_fab2(sch_1):tp_ch_f_dimm_f1_rfu_2"
				( attribute "CDS_PHYS_NET_NAME" "TP_CH_F_DIMM_F1_RFU_2"
					( Origin gPackager )
				)
				( objectStatus "TP_CH_F_DIMM_F1_RFU_2" )
			)
			( signal "@baseboard_fab2_lib.baseboard_fab2(sch_1):a_cpu1_ghj_rcomp0"
				( attribute "CDS_PHYS_NET_NAME" "A_CPU1_GHJ_RCOMP0"
					( Origin gPackager )
				)
				( objectStatus "A_CPU1_GHJ_RCOMP0" )
			)
			( signal "@baseboard_fab2_lib.baseboard_fab2(sch_1):a_cpu1_ghj_rcomp1"
				( attribute "CDS_PHYS_NET_NAME" "A_CPU1_GHJ_RCOMP1"
					( Origin gPackager )
				)
				( objectStatus "A_CPU1_GHJ_RCOMP1" )
			)
			( signal "@baseboard_fab2_lib.baseboard_fab2(sch_1):a_cpu1_ghj_rcomp2"
				( attribute "CDS_PHYS_NET_NAME" "A_CPU1_GHJ_RCOMP2"
					( Origin gPackager )
				)
				( objectStatus "A_CPU1_GHJ_RCOMP2" )
			)
			( signal "@baseboard_fab2_lib.baseboard_fab2(sch_1):a_cpu1_klm_rcomp0"
				( attribute "CDS_PHYS_NET_NAME" "A_CPU1_KLM_RCOMP0"
					( Origin gPackager )
				)
				( objectStatus "A_CPU1_KLM_RCOMP0" )
			)
			( signal "@baseboard_fab2_lib.baseboard_fab2(sch_1):a_cpu1_klm_rcomp1"
				( attribute "CDS_PHYS_NET_NAME" "A_CPU1_KLM_RCOMP1"
					( Origin gPackager )
				)
				( objectStatus "A_CPU1_KLM_RCOMP1" )
			)
			( signal "@baseboard_fab2_lib.baseboard_fab2(sch_1):a_cpu1_klm_rcomp2"
				( attribute "CDS_PHYS_NET_NAME" "A_CPU1_KLM_RCOMP2"
					( Origin gPackager )
				)
				( objectStatus "A_CPU1_KLM_RCOMP2" )
			)
			( signal "@baseboard_fab2_lib.baseboard_fab2(sch_1):a_cpu1_mcp01_rbias"
				( attribute "CDS_PHYS_NET_NAME" "A_CPU1_MCP01_RBIAS"
					( Origin gPackager )
				)
				( objectStatus "A_CPU1_MCP01_RBIAS" )
			)
			( signal "@baseboard_fab2_lib.baseboard_fab2(sch_1):a_cpu1_pe012_rbias"
				( attribute "CDS_PHYS_NET_NAME" "A_CPU1_PE012_RBIAS"
					( Origin gPackager )
				)
				( objectStatus "A_CPU1_PE012_RBIAS" )
			)
			( signal "@baseboard_fab2_lib.baseboard_fab2(sch_1):a_cpu1_pe3_rbias"
				( attribute "CDS_PHYS_NET_NAME" "A_CPU1_PE3_RBIAS"
					( Origin gPackager )
				)
				( objectStatus "A_CPU1_PE3_RBIAS" )
			)
			( signal "@baseboard_fab2_lib.baseboard_fab2(sch_1):a_cpu1_upi01_rbias"
				( attribute "CDS_PHYS_NET_NAME" "A_CPU1_UPI01_RBIAS"
					( Origin gPackager )
				)
				( objectStatus "A_CPU1_UPI01_RBIAS" )
			)
			( signal "@baseboard_fab2_lib.baseboard_fab2(sch_1):a_cpu1_upi2_rbias"
				( attribute "CDS_PHYS_NET_NAME" "A_CPU1_UPI2_RBIAS"
					( Origin gPackager )
				)
				( objectStatus "A_CPU1_UPI2_RBIAS" )
			)
			( signal "@baseboard_fab2_lib.baseboard_fab2(sch_1):clk_100m_cpu1_bclk0_dn"
				( attribute "CDS_PHYS_NET_NAME" "CLK_100M_CPU1_BCLK0_DN"
					( Origin gPackager )
				)
				( objectStatus "CLK_100M_CPU1_BCLK0_DN" )
			)
			( signal "@baseboard_fab2_lib.baseboard_fab2(sch_1):clk_100m_cpu1_bclk0_dp"
				( attribute "CDS_PHYS_NET_NAME" "CLK_100M_CPU1_BCLK0_DP"
					( Origin gPackager )
				)
				( objectStatus "CLK_100M_CPU1_BCLK0_DP" )
			)
			( signal "@baseboard_fab2_lib.baseboard_fab2(sch_1):clk_100m_cpu1_bclk1_dn"
				( attribute "CDS_PHYS_NET_NAME" "CLK_100M_CPU1_BCLK1_DN"
					( Origin gPackager )
				)
				( objectStatus "CLK_100M_CPU1_BCLK1_DN" )
			)
			( signal "@baseboard_fab2_lib.baseboard_fab2(sch_1):clk_100m_cpu1_bclk1_dp"
				( attribute "CDS_PHYS_NET_NAME" "CLK_100M_CPU1_BCLK1_DP"
					( Origin gPackager )
				)
				( objectStatus "CLK_100M_CPU1_BCLK1_DP" )
			)
			( signal "@baseboard_fab2_lib.baseboard_fab2(sch_1):clk_100m_cpu1_bclk2_dn"
				( attribute "CDS_PHYS_NET_NAME" "CLK_100M_CPU1_BCLK2_DN"
					( Origin gPackager )
				)
				( objectStatus "CLK_100M_CPU1_BCLK2_DN" )
			)
			( signal "@baseboard_fab2_lib.baseboard_fab2(sch_1):clk_100m_cpu1_bclk2_dp"
				( attribute "CDS_PHYS_NET_NAME" "CLK_100M_CPU1_BCLK2_DP"
					( Origin gPackager )
				)
				( objectStatus "CLK_100M_CPU1_BCLK2_DP" )
			)
			( signal "@baseboard_fab2_lib.baseboard_fab2(sch_1):fm_cpu1_pkgid0"
				( attribute "CDS_PHYS_NET_NAME" "FM_CPU1_PKGID0"
					( Origin gPackager )
				)
				( objectStatus "FM_CPU1_PKGID0" )
			)
			( signal "@baseboard_fab2_lib.baseboard_fab2(sch_1):fm_cpu1_pkgid1"
				( attribute "CDS_PHYS_NET_NAME" "FM_CPU1_PKGID1"
					( Origin gPackager )
				)
				( objectStatus "FM_CPU1_PKGID1" )
			)
			( signal "@baseboard_fab2_lib.baseboard_fab2(sch_1):fm_cpu1_pkgid2"
				( attribute "CDS_PHYS_NET_NAME" "FM_CPU1_PKGID2"
					( Origin gPackager )
				)
				( objectStatus "FM_CPU1_PKGID2" )
			)
			( signal "@baseboard_fab2_lib.baseboard_fab2(sch_1):fm_cpu1_proc_id0"
				( attribute "CDS_PHYS_NET_NAME" "FM_CPU1_PROC_ID0"
					( Origin gPackager )
				)
				( objectStatus "FM_CPU1_PROC_ID0" )
			)
			( signal "@baseboard_fab2_lib.baseboard_fab2(sch_1):fm_cpu1_proc_id1"
				( attribute "CDS_PHYS_NET_NAME" "FM_CPU1_PROC_ID1"
					( Origin gPackager )
				)
				( objectStatus "FM_CPU1_PROC_ID1" )
			)
			( signal "@baseboard_fab2_lib.baseboard_fab2(sch_1):fm_cpu1_sktocc_lvt3_n"
				( attribute "CDS_PHYS_NET_NAME" "FM_CPU1_SKTOCC_LVT3_N"
					( Origin gPackager )
				)
				( attribute "PHYS_NET_NAME" "FM_CPU1_SKTOCC_LVT3_N"
					( Origin gPackager )
				)
				( objectStatus "FM_CPU1_SKTOCC_LVT3_N" )
			)
			( signal "@baseboard_fab2_lib.baseboard_fab2(sch_1):fm_cpu1_sm_wp"
				( attribute "CDS_PHYS_NET_NAME" "FM_CPU1_SM_WP"
					( Origin gPackager )
				)
				( objectStatus "FM_CPU1_SM_WP" )
			)
			( signal "@baseboard_fab2_lib.baseboard_fab2(sch_1):h_cpu1_bmcinit"
				( attribute "CDS_PHYS_NET_NAME" "H_CPU1_BMCINIT"
					( Origin gPackager )
				)
				( objectStatus "H_CPU1_BMCINIT" )
			)
			( signal "@baseboard_fab2_lib.baseboard_fab2(sch_1):h_cpu1_caterr_g_n"
				( attribute "CDS_PHYS_NET_NAME" "H_CPU1_CATERR_G_N"
					( Origin gPackager )
				)
				( objectStatus "H_CPU1_CATERR_G_N" )
			)
			( signal "@baseboard_fab2_lib.baseboard_fab2(sch_1):h_cpu1_err0_g_n"
				( attribute "CDS_PHYS_NET_NAME" "H_CPU1_ERR0_G_N"
					( Origin gPackager )
				)
				( objectStatus "H_CPU1_ERR0_G_N" )
			)
			( signal "@baseboard_fab2_lib.baseboard_fab2(sch_1):h_cpu1_err1_g_n"
				( attribute "CDS_PHYS_NET_NAME" "H_CPU1_ERR1_G_N"
					( Origin gPackager )
				)
				( objectStatus "H_CPU1_ERR1_G_N" )
			)
			( signal "@baseboard_fab2_lib.baseboard_fab2(sch_1):h_cpu1_err2_g_n"
				( attribute "CDS_PHYS_NET_NAME" "H_CPU1_ERR2_G_N"
					( Origin gPackager )
				)
				( objectStatus "H_CPU1_ERR2_G_N" )
			)
			( signal "@baseboard_fab2_lib.baseboard_fab2(sch_1):h_cpu1_fast_wake_n"
				( attribute "CDS_PHYS_NET_NAME" "H_CPU1_FAST_WAKE_N"
					( Origin gPackager )
				)
				( objectStatus "H_CPU1_FAST_WAKE_N" )
			)
			( signal "@baseboard_fab2_lib.baseboard_fab2(sch_1):h_cpu1_memghj_memhot_g_n"
				( attribute "CDS_PHYS_NET_NAME" "H_CPU1_MEMGHJ_MEMHOT_G_N"
					( Origin gPackager )
				)
				( objectStatus "H_CPU1_MEMGHJ_MEMHOT_G_N" )
			)
			( signal "@baseboard_fab2_lib.baseboard_fab2(sch_1):h_cpu1_memklm_memhot_g_n"
				( attribute "CDS_PHYS_NET_NAME" "H_CPU1_MEMKLM_MEMHOT_G_N"
					( Origin gPackager )
				)
				( objectStatus "H_CPU1_MEMKLM_MEMHOT_G_N" )
			)
			( signal "@baseboard_fab2_lib.baseboard_fab2(sch_1):h_cpu1_msmi_g_n"
				( attribute "CDS_PHYS_NET_NAME" "H_CPU1_MSMI_G_N"
					( Origin gPackager )
				)
				( objectStatus "H_CPU1_MSMI_G_N" )
			)
			( signal "@baseboard_fab2_lib.baseboard_fab2(sch_1):h_cpu1_prochot_g_n"
				( attribute "CDS_PHYS_NET_NAME" "H_CPU1_PROCHOT_G_N"
					( Origin gPackager )
				)
				( objectStatus "H_CPU1_PROCHOT_G_N" )
			)
			( signal "@baseboard_fab2_lib.baseboard_fab2(sch_1):h_cpu1_thermtrip_g_n"
				( attribute "CDS_PHYS_NET_NAME" "H_CPU1_THERMTRIP_G_N"
					( Origin gPackager )
				)
				( objectStatus "H_CPU1_THERMTRIP_G_N" )
			)
			( signal "@baseboard_fab2_lib.baseboard_fab2(sch_1):h_pm_sync_gtl_r2"
				( attribute "CDS_PHYS_NET_NAME" "H_PM_SYNC_GTL_R2"
					( Origin gPackager )
				)
				( objectStatus "H_PM_SYNC_GTL_R2" )
			)
			( signal "@baseboard_fab2_lib.baseboard_fab2(sch_1):h_pmsync_clk_24m_cpu1"
				( attribute "CDS_PHYS_NET_NAME" "H_PMSYNC_CLK_24M_CPU1"
					( Origin gPackager )
				)
				( objectStatus "H_PMSYNC_CLK_24M_CPU1" )
			)
			( signal "@baseboard_fab2_lib.baseboard_fab2(sch_1):m_g_cpu_vref"
				( attribute "CDS_PHYS_NET_NAME" "M_G_CPU_VREF"
					( Origin gPackager )
				)
				( objectStatus "M_G_CPU_VREF" )
			)
			( signal "@baseboard_fab2_lib.baseboard_fab2(sch_1):m_ghj_rst_n"
				( attribute "CDS_PHYS_NET_NAME" "M_GHJ_RST_N"
					( Origin gPackager )
				)
				( objectStatus "M_GHJ_RST_N" )
			)
			( signal "@baseboard_fab2_lib.baseboard_fab2(sch_1):m_h_cpu_vref"
				( attribute "CDS_PHYS_NET_NAME" "M_H_CPU_VREF"
					( Origin gPackager )
				)
				( objectStatus "M_H_CPU_VREF" )
			)
			( signal "@baseboard_fab2_lib.baseboard_fab2(sch_1):m_j_cpu_vref"
				( attribute "CDS_PHYS_NET_NAME" "M_J_CPU_VREF"
					( Origin gPackager )
				)
				( objectStatus "M_J_CPU_VREF" )
			)
			( signal "@baseboard_fab2_lib.baseboard_fab2(sch_1):m_k_cpu_vref"
				( attribute "CDS_PHYS_NET_NAME" "M_K_CPU_VREF"
					( Origin gPackager )
				)
				( objectStatus "M_K_CPU_VREF" )
			)
			( signal "@baseboard_fab2_lib.baseboard_fab2(sch_1):m_klm_rst_n"
				( attribute "CDS_PHYS_NET_NAME" "M_KLM_RST_N"
					( Origin gPackager )
				)
				( objectStatus "M_KLM_RST_N" )
			)
			( signal "@baseboard_fab2_lib.baseboard_fab2(sch_1):m_l_cpu_vref"
				( attribute "CDS_PHYS_NET_NAME" "M_L_CPU_VREF"
					( Origin gPackager )
				)
				( objectStatus "M_L_CPU_VREF" )
			)
			( signal "@baseboard_fab2_lib.baseboard_fab2(sch_1):m_m_cpu_vref"
				( attribute "CDS_PHYS_NET_NAME" "M_M_CPU_VREF"
					( Origin gPackager )
				)
				( objectStatus "M_M_CPU_VREF" )
			)
			( signal "@baseboard_fab2_lib.baseboard_fab2(sch_1):pd_cpu1_bist_enable"
				( attribute "CDS_PHYS_NET_NAME" "PD_CPU1_BIST_ENABLE"
					( Origin gPackager )
				)
				( objectStatus "PD_CPU1_BIST_ENABLE" )
			)
			( signal "@baseboard_fab2_lib.baseboard_fab2(sch_1):pd_cpu1_ksfc_dis"
				( attribute "CDS_PHYS_NET_NAME" "PD_CPU1_KSFC_DIS"
					( Origin gPackager )
				)
				( objectStatus "PD_CPU1_KSFC_DIS" )
			)
			( signal "@baseboard_fab2_lib.baseboard_fab2(sch_1):pd_cpu1_test12"
				( attribute "CDS_PHYS_NET_NAME" "PD_CPU1_TEST12"
					( Origin gPackager )
				)
				( objectStatus "PD_CPU1_TEST12" )
			)
			( signal "@baseboard_fab2_lib.baseboard_fab2(sch_1):pd_cpu1_test13"
				( attribute "CDS_PHYS_NET_NAME" "PD_CPU1_TEST13"
					( Origin gPackager )
				)
				( objectStatus "PD_CPU1_TEST13" )
			)
			( signal "@baseboard_fab2_lib.baseboard_fab2(sch_1):pd_cpu1_test14"
				( attribute "CDS_PHYS_NET_NAME" "PD_CPU1_TEST14"
					( Origin gPackager )
				)
				( objectStatus "PD_CPU1_TEST14" )
			)
			( signal "@baseboard_fab2_lib.baseboard_fab2(sch_1):pd_cpu1_txt_plten"
				( attribute "CDS_PHYS_NET_NAME" "PD_CPU1_TXT_PLTEN"
					( Origin gPackager )
				)
				( objectStatus "PD_CPU1_TXT_PLTEN" )
			)
			( signal "@baseboard_fab2_lib.baseboard_fab2(sch_1):pd_pirom_cpu1_addr1"
				( attribute "CDS_PHYS_NET_NAME" "PD_PIROM_CPU1_ADDR1"
					( Origin gPackager )
				)
				( objectStatus "PD_PIROM_CPU1_ADDR1" )
			)
			( signal "@baseboard_fab2_lib.baseboard_fab2(sch_1):pd_pirom_cpu1_addr2"
				( attribute "CDS_PHYS_NET_NAME" "PD_PIROM_CPU1_ADDR2"
					( Origin gPackager )
				)
				( objectStatus "PD_PIROM_CPU1_ADDR2" )
			)
			( signal "@baseboard_fab2_lib.baseboard_fab2(sch_1):pu_cpu1_ear_n"
				( attribute "CDS_PHYS_NET_NAME" "PU_CPU1_EAR_N"
					( Origin gPackager )
				)
				( objectStatus "PU_CPU1_EAR_N" )
			)
			( signal "@baseboard_fab2_lib.baseboard_fab2(sch_1):pu_cpu1_frmagent"
				( attribute "CDS_PHYS_NET_NAME" "PU_CPU1_FRMAGENT"
					( Origin gPackager )
				)
				( objectStatus "PU_CPU1_FRMAGENT" )
			)
			( signal "@baseboard_fab2_lib.baseboard_fab2(sch_1):pu_cpu1_legacy_skt"
				( attribute "CDS_PHYS_NET_NAME" "PU_CPU1_LEGACY_SKT"
					( Origin gPackager )
				)
				( objectStatus "PU_CPU1_LEGACY_SKT" )
			)
			( signal "@baseboard_fab2_lib.baseboard_fab2(sch_1):pu_cpu1_safe_mode_boot"
				( attribute "CDS_PHYS_NET_NAME" "PU_CPU1_SAFE_MODE_BOOT"
					( Origin gPackager )
				)
				( objectStatus "PU_CPU1_SAFE_MODE_BOOT" )
			)
			( signal "@baseboard_fab2_lib.baseboard_fab2(sch_1):pu_cpu1_socket_id_0"
				( attribute "CDS_PHYS_NET_NAME" "PU_CPU1_SOCKET_ID_0"
					( Origin gPackager )
				)
				( objectStatus "PU_CPU1_SOCKET_ID_0" )
			)
			( signal "@baseboard_fab2_lib.baseboard_fab2(sch_1):pu_cpu1_socket_id_1"
				( attribute "CDS_PHYS_NET_NAME" "PU_CPU1_SOCKET_ID_1"
					( Origin gPackager )
				)
				( objectStatus "PU_CPU1_SOCKET_ID_1" )
			)
			( signal "@baseboard_fab2_lib.baseboard_fab2(sch_1):pu_cpu1_tsc_sync"
				( attribute "CDS_PHYS_NET_NAME" "PU_CPU1_TSC_SYNC"
					( Origin gPackager )
				)
				( objectStatus "PU_CPU1_TSC_SYNC" )
			)
			( signal "@baseboard_fab2_lib.baseboard_fab2(sch_1):pu_cpu1_txt_agent"
				( attribute "CDS_PHYS_NET_NAME" "PU_CPU1_TXT_AGENT"
					( Origin gPackager )
				)
				( objectStatus "PU_CPU1_TXT_AGENT" )
			)
			( signal "@baseboard_fab2_lib.baseboard_fab2(sch_1):pu_pirom_cpu1_addr0"
				( attribute "CDS_PHYS_NET_NAME" "PU_PIROM_CPU1_ADDR0"
					( Origin gPackager )
				)
				( objectStatus "PU_PIROM_CPU1_ADDR0" )
			)
			( signal "@baseboard_fab2_lib.baseboard_fab2(sch_1):pvccio_cpu1"
				( alias ( signalRef "@baseboard_fab2_lib.baseboard_fab2(sch_1):page55_pvccio_cpu1") )
				( alias ( signalRef "@baseboard_fab2_lib.baseboard_fab2(sch_1):page71_pvccio_cpu1") )
				( alias ( signalRef "@baseboard_fab2_lib.baseboard_fab2(sch_1):page72_pvccio_cpu1") )
				( alias ( signalRef "@baseboard_fab2_lib.baseboard_fab2(sch_1):page73_pvccio_cpu1") )
				( alias ( signalRef "@baseboard_fab2_lib.baseboard_fab2(sch_1):page76_pvccio_cpu1") )
				( alias ( signalRef "@baseboard_fab2_lib.baseboard_fab2(sch_1):page90_pvccio_cpu1") )
				( alias ( signalRef "@baseboard_fab2_lib.baseboard_fab2(sch_1):page92_pvccio_cpu1") )
				( alias ( signalRef "@baseboard_fab2_lib.baseboard_fab2(sch_1):page93_pvccio_cpu1") )
				( alias ( signalRef "@baseboard_fab2_lib.baseboard_fab2(sch_1):page96_pvccio_cpu1") )
				( alias ( signalRef "@baseboard_fab2_lib.baseboard_fab2(sch_1):page97_pvccio_cpu1") )
				( alias ( signalRef "@baseboard_fab2_lib.baseboard_fab2(sch_1):page99_pvccio_cpu1") )
				( alias ( signalRef "@baseboard_fab2_lib.baseboard_fab2(sch_1):page112_pvccio_cpu1") )
				( alias ( signalRef "@baseboard_fab2_lib.baseboard_fab2(sch_1):page152_pvccio_cpu1") )
				( alias ( signalRef "@baseboard_fab2_lib.baseboard_fab2(sch_1):page163_pvccio_cpu1") )
				( alias ( signalRef "@baseboard_fab2_lib.baseboard_fab2(sch_1):page193_pvccio_cpu1") )
				( alias ( signalRef "@baseboard_fab2_lib.baseboard_fab2(sch_1):page206_pvccio_cpu1") )
				( alias ( signalRef "@baseboard_fab2_lib.baseboard_fab2(sch_1):page213_pvccio_cpu1") )
				( alias ( signalRef "@baseboard_fab2_lib.baseboard_fab2(sch_1):page214_pvccio_cpu1") )
				( alias ( signalRef "@baseboard_fab2_lib.baseboard_fab2(sch_1):page223_pvccio_cpu1") )
				( alias ( signalRef "@baseboard_fab2_lib.baseboard_fab2(sch_1):page226_pvccio_cpu1") )
				( attribute "VOLTAGE" "1.1V"
					( Units "uVoltage" "V" 1.000000)
					( Status sAliasFlattened )
					( Origin gFrontEnd )
				)
				( attribute "CDS_PHYS_NET_NAME" "PVCCIO_CPU1"
					( Origin gPackager )
				)
				( objectStatus "PVCCIO_CPU1" )
			)
			( signal "@baseboard_fab2_lib.baseboard_fab2(sch_1):page55_pvccio_cpu1"
				( attribute "VOLTAGE" "1.1V"
					( Units "uVoltage" "V" 1.000000)
					( Origin gFrontEnd )
				)
				( objectFlag fObjectAlias )
				( objectStatus "page55_pvccio_cpu1" )
			)
			( signal "@baseboard_fab2_lib.baseboard_fab2(sch_1):page71_pvccio_cpu1"
				( attribute "VOLTAGE" "1.1V"
					( Units "uVoltage" "V" 1.000000)
					( Origin gFrontEnd )
				)
				( objectFlag fObjectAlias )
				( objectStatus "page71_pvccio_cpu1" )
			)
			( signal "@baseboard_fab2_lib.baseboard_fab2(sch_1):page72_pvccio_cpu1"
				( attribute "VOLTAGE" "1.1V"
					( Units "uVoltage" "V" 1.000000)
					( Origin gFrontEnd )
				)
				( objectFlag fObjectAlias )
				( objectStatus "page72_pvccio_cpu1" )
			)
			( signal "@baseboard_fab2_lib.baseboard_fab2(sch_1):page73_pvccio_cpu1"
				( attribute "VOLTAGE" "1.1V"
					( Units "uVoltage" "V" 1.000000)
					( Origin gFrontEnd )
				)
				( objectFlag fObjectAlias )
				( objectStatus "page73_pvccio_cpu1" )
			)
			( signal "@baseboard_fab2_lib.baseboard_fab2(sch_1):page76_pvccio_cpu1"
				( attribute "VOLTAGE" "1.1V"
					( Units "uVoltage" "V" 1.000000)
					( Origin gFrontEnd )
				)
				( objectFlag fObjectAlias )
				( objectStatus "page76_pvccio_cpu1" )
			)
			( signal "@baseboard_fab2_lib.baseboard_fab2(sch_1):page90_pvccio_cpu1"
				( attribute "VOLTAGE" "1.1V"
					( Units "uVoltage" "V" 1.000000)
					( Origin gFrontEnd )
				)
				( objectFlag fObjectAlias )
				( objectStatus "page90_pvccio_cpu1" )
			)
			( signal "@baseboard_fab2_lib.baseboard_fab2(sch_1):page92_pvccio_cpu1"
				( attribute "VOLTAGE" "1.1V"
					( Units "uVoltage" "V" 1.000000)
					( Origin gFrontEnd )
				)
				( objectFlag fObjectAlias )
				( objectStatus "page92_pvccio_cpu1" )
			)
			( signal "@baseboard_fab2_lib.baseboard_fab2(sch_1):page93_pvccio_cpu1"
				( attribute "VOLTAGE" "1.1V"
					( Units "uVoltage" "V" 1.000000)
					( Origin gFrontEnd )
				)
				( objectFlag fObjectAlias )
				( objectStatus "page93_pvccio_cpu1" )
			)
			( signal "@baseboard_fab2_lib.baseboard_fab2(sch_1):page96_pvccio_cpu1"
				( attribute "VOLTAGE" "1.1V"
					( Units "uVoltage" "V" 1.000000)
					( Origin gFrontEnd )
				)
				( objectFlag fObjectAlias )
				( objectStatus "page96_pvccio_cpu1" )
			)
			( signal "@baseboard_fab2_lib.baseboard_fab2(sch_1):page97_pvccio_cpu1"
				( attribute "VOLTAGE" "1.1V"
					( Units "uVoltage" "V" 1.000000)
					( Origin gFrontEnd )
				)
				( objectFlag fObjectAlias )
				( objectStatus "page97_pvccio_cpu1" )
			)
			( signal "@baseboard_fab2_lib.baseboard_fab2(sch_1):page99_pvccio_cpu1"
				( attribute "VOLTAGE" "1.1V"
					( Units "uVoltage" "V" 1.000000)
					( Origin gFrontEnd )
				)
				( objectFlag fObjectAlias )
				( objectStatus "page99_pvccio_cpu1" )
			)
			( signal "@baseboard_fab2_lib.baseboard_fab2(sch_1):page112_pvccio_cpu1"
				( attribute "VOLTAGE" "1.1V"
					( Units "uVoltage" "V" 1.000000)
					( Origin gFrontEnd )
				)
				( objectFlag fObjectAlias )
				( objectStatus "page112_pvccio_cpu1" )
			)
			( signal "@baseboard_fab2_lib.baseboard_fab2(sch_1):page152_pvccio_cpu1"
				( attribute "VOLTAGE" "1.1V"
					( Units "uVoltage" "V" 1.000000)
					( Origin gFrontEnd )
				)
				( objectFlag fObjectAlias )
				( objectStatus "page152_pvccio_cpu1" )
			)
			( signal "@baseboard_fab2_lib.baseboard_fab2(sch_1):page163_pvccio_cpu1"
				( attribute "VOLTAGE" "1.1V"
					( Units "uVoltage" "V" 1.000000)
					( Origin gFrontEnd )
				)
				( objectFlag fObjectAlias )
				( objectStatus "page163_pvccio_cpu1" )
			)
			( signal "@baseboard_fab2_lib.baseboard_fab2(sch_1):page193_pvccio_cpu1"
				( attribute "VOLTAGE" "1.1V"
					( Units "uVoltage" "V" 1.000000)
					( Origin gFrontEnd )
				)
				( objectFlag fObjectAlias )
				( objectStatus "page193_pvccio_cpu1" )
			)
			( signal "@baseboard_fab2_lib.baseboard_fab2(sch_1):page206_pvccio_cpu1"
				( attribute "VOLTAGE" "1.1V"
					( Units "uVoltage" "V" 1.000000)
					( Origin gFrontEnd )
				)
				( objectFlag fObjectAlias )
				( objectStatus "page206_pvccio_cpu1" )
			)
			( signal "@baseboard_fab2_lib.baseboard_fab2(sch_1):page213_pvccio_cpu1"
				( attribute "VOLTAGE" "1.1V"
					( Units "uVoltage" "V" 1.000000)
					( Origin gFrontEnd )
				)
				( objectFlag fObjectAlias )
				( objectStatus "page213_pvccio_cpu1" )
			)
			( signal "@baseboard_fab2_lib.baseboard_fab2(sch_1):page214_pvccio_cpu1"
				( attribute "VOLTAGE" "1.1V"
					( Units "uVoltage" "V" 1.000000)
					( Origin gFrontEnd )
				)
				( objectFlag fObjectAlias )
				( objectStatus "page214_pvccio_cpu1" )
			)
			( signal "@baseboard_fab2_lib.baseboard_fab2(sch_1):page223_pvccio_cpu1"
				( attribute "VOLTAGE" "1.1V"
					( Units "uVoltage" "V" 1.000000)
					( Origin gFrontEnd )
				)
				( objectFlag fObjectAlias )
				( objectStatus "page223_pvccio_cpu1" )
			)
			( signal "@baseboard_fab2_lib.baseboard_fab2(sch_1):page226_pvccio_cpu1"
				( attribute "VOLTAGE" "1.1V"
					( Units "uVoltage" "V" 1.000000)
					( Origin gFrontEnd )
				)
				( objectFlag fObjectAlias )
				( objectStatus "page226_pvccio_cpu1" )
			)
			( signal "@baseboard_fab2_lib.baseboard_fab2(sch_1):pwrgd_cpu1_drampwrok_ghj_g"
				( attribute "CDS_PHYS_NET_NAME" "PWRGD_CPU1_DRAMPWROK_GHJ_G"
					( Origin gPackager )
				)
				( objectStatus "PWRGD_CPU1_DRAMPWROK_GHJ_G" )
			)
			( signal "@baseboard_fab2_lib.baseboard_fab2(sch_1):pwrgd_cpu1_drampwrok_klm_g"
				( attribute "CDS_PHYS_NET_NAME" "PWRGD_CPU1_DRAMPWROK_KLM_G"
					( Origin gPackager )
				)
				( objectStatus "PWRGD_CPU1_DRAMPWROK_KLM_G" )
			)
			( signal "@baseboard_fab2_lib.baseboard_fab2(sch_1):pwrgd_cpu1_g"
				( attribute "CDS_PHYS_NET_NAME" "PWRGD_CPU1_G"
					( Origin gPackager )
				)
				( objectStatus "PWRGD_CPU1_G" )
			)
			( signal "@baseboard_fab2_lib.baseboard_fab2(sch_1):rst_cpu1_g_n"
				( attribute "CDS_PHYS_NET_NAME" "RST_CPU1_G_N"
					( Origin gPackager )
				)
				( objectStatus "RST_CPU1_G_N" )
			)
			( signal "@baseboard_fab2_lib.baseboard_fab2(sch_1):smb_cpu1_pe_hp_gtl_scl"
				( attribute "CDS_PHYS_NET_NAME" "SMB_CPU1_PE_HP_GTL_SCL"
					( Origin gPackager )
				)
				( objectStatus "SMB_CPU1_PE_HP_GTL_SCL" )
			)
			( signal "@baseboard_fab2_lib.baseboard_fab2(sch_1):smb_cpu1_pe_hp_gtl_sda"
				( attribute "CDS_PHYS_NET_NAME" "SMB_CPU1_PE_HP_GTL_SDA"
					( Origin gPackager )
				)
				( objectStatus "SMB_CPU1_PE_HP_GTL_SDA" )
			)
			( signal "@baseboard_fab2_lib.baseboard_fab2(sch_1):smb_ddr_ghj_scl_g_r"
				( attribute "CDS_PHYS_NET_NAME" "SMB_DDR_GHJ_SCL_G_R"
					( Origin gPackager )
				)
				( objectStatus "SMB_DDR_GHJ_SCL_G_R" )
			)
			( signal "@baseboard_fab2_lib.baseboard_fab2(sch_1):smb_ddr_ghj_sda_g_r"
				( attribute "CDS_PHYS_NET_NAME" "SMB_DDR_GHJ_SDA_G_R"
					( Origin gPackager )
				)
				( objectStatus "SMB_DDR_GHJ_SDA_G_R" )
			)
			( signal "@baseboard_fab2_lib.baseboard_fab2(sch_1):smb_ddr_klm_scl_g_r"
				( attribute "CDS_PHYS_NET_NAME" "SMB_DDR_KLM_SCL_G_R"
					( Origin gPackager )
				)
				( objectStatus "SMB_DDR_KLM_SCL_G_R" )
			)
			( signal "@baseboard_fab2_lib.baseboard_fab2(sch_1):smb_ddr_klm_sda_g_r"
				( attribute "CDS_PHYS_NET_NAME" "SMB_DDR_KLM_SDA_G_R"
					( Origin gPackager )
				)
				( objectStatus "SMB_DDR_KLM_SDA_G_R" )
			)
			( signal "@baseboard_fab2_lib.baseboard_fab2(sch_1):smb_pirom_cpu1_scl"
				( attribute "CDS_PHYS_NET_NAME" "SMB_PIROM_CPU1_SCL"
					( Origin gPackager )
				)
				( objectStatus "SMB_PIROM_CPU1_SCL" )
			)
			( signal "@baseboard_fab2_lib.baseboard_fab2(sch_1):smb_pirom_cpu1_sda"
				( attribute "CDS_PHYS_NET_NAME" "SMB_PIROM_CPU1_SDA"
					( Origin gPackager )
				)
				( objectStatus "SMB_PIROM_CPU1_SDA" )
			)
			( signal "@baseboard_fab2_lib.baseboard_fab2(sch_1):svid_alert0_cpu1_n"
				( attribute "CDS_PHYS_NET_NAME" "SVID_ALERT0_CPU1_N"
					( Origin gPackager )
				)
				( objectStatus "SVID_ALERT0_CPU1_N" )
			)
			( signal "@baseboard_fab2_lib.baseboard_fab2(sch_1):svid_alert0_cpu1_r_n"
				( attribute "CDS_PHYS_NET_NAME" "SVID_ALERT0_CPU1_R_N"
					( Origin gPackager )
				)
				( objectStatus "SVID_ALERT0_CPU1_R_N" )
			)
			( signal "@baseboard_fab2_lib.baseboard_fab2(sch_1):svid_alert1_cpu1_n"
				( attribute "CDS_PHYS_NET_NAME" "SVID_ALERT1_CPU1_N"
					( Origin gPackager )
				)
				( objectStatus "SVID_ALERT1_CPU1_N" )
			)
			( signal "@baseboard_fab2_lib.baseboard_fab2(sch_1):svid_alert1_cpu1_r_n"
				( attribute "CDS_PHYS_NET_NAME" "SVID_ALERT1_CPU1_R_N"
					( Origin gPackager )
				)
				( objectStatus "SVID_ALERT1_CPU1_R_N" )
			)
			( signal "@baseboard_fab2_lib.baseboard_fab2(sch_1):svid_clk0_cpu1"
				( attribute "CDS_PHYS_NET_NAME" "SVID_CLK0_CPU1"
					( Origin gPackager )
				)
				( objectStatus "SVID_CLK0_CPU1" )
			)
			( signal "@baseboard_fab2_lib.baseboard_fab2(sch_1):svid_clk0_cpu1_r"
				( attribute "CDS_PHYS_NET_NAME" "SVID_CLK0_CPU1_R"
					( Origin gPackager )
				)
				( objectStatus "SVID_CLK0_CPU1_R" )
			)
			( signal "@baseboard_fab2_lib.baseboard_fab2(sch_1):svid_clk1_cpu1"
				( attribute "CDS_PHYS_NET_NAME" "SVID_CLK1_CPU1"
					( Origin gPackager )
				)
				( objectStatus "SVID_CLK1_CPU1" )
			)
			( signal "@baseboard_fab2_lib.baseboard_fab2(sch_1):svid_clk1_cpu1_r"
				( attribute "CDS_PHYS_NET_NAME" "SVID_CLK1_CPU1_R"
					( Origin gPackager )
				)
				( objectStatus "SVID_CLK1_CPU1_R" )
			)
			( signal "@baseboard_fab2_lib.baseboard_fab2(sch_1):svid_dio0_cpu1"
				( attribute "CDS_PHYS_NET_NAME" "SVID_DIO0_CPU1"
					( Origin gPackager )
				)
				( objectStatus "SVID_DIO0_CPU1" )
			)
			( signal "@baseboard_fab2_lib.baseboard_fab2(sch_1):svid_dio0_cpu1_r"
				( attribute "CDS_PHYS_NET_NAME" "SVID_DIO0_CPU1_R"
					( Origin gPackager )
				)
				( objectStatus "SVID_DIO0_CPU1_R" )
			)
			( signal "@baseboard_fab2_lib.baseboard_fab2(sch_1):svid_dio1_cpu1"
				( attribute "CDS_PHYS_NET_NAME" "SVID_DIO1_CPU1"
					( Origin gPackager )
				)
				( objectStatus "SVID_DIO1_CPU1" )
			)
			( signal "@baseboard_fab2_lib.baseboard_fab2(sch_1):svid_dio1_cpu1_r"
				( attribute "CDS_PHYS_NET_NAME" "SVID_DIO1_CPU1_R"
					( Origin gPackager )
				)
				( objectStatus "SVID_DIO1_CPU1_R" )
			)
			( signal "@baseboard_fab2_lib.baseboard_fab2(sch_1):tp_cpu1_nmi"
				( attribute "CDS_PHYS_NET_NAME" "TP_CPU1_NMI"
					( Origin gPackager )
				)
				( objectStatus "TP_CPU1_NMI" )
			)
			( signal "@baseboard_fab2_lib.baseboard_fab2(sch_1):tp_cpu1_proc_dis_g_n"
				( attribute "CDS_PHYS_NET_NAME" "TP_CPU1_PROC_DIS_G_N"
					( Origin gPackager )
				)
				( objectStatus "TP_CPU1_PROC_DIS_G_N" )
			)
			( signal "@baseboard_fab2_lib.baseboard_fab2(sch_1):tp_cpu1_socket_id_2"
				( attribute "CDS_PHYS_NET_NAME" "TP_CPU1_SOCKET_ID_2"
					( Origin gPackager )
				)
				( objectStatus "TP_CPU1_SOCKET_ID_2" )
			)
			( signal "@baseboard_fab2_lib.baseboard_fab2(sch_1):tp_xdp_cpu1_obsdata_b0_mbp2_n"
				( attribute "CDS_PHYS_NET_NAME" "TP_XDP_CPU1_OBSDATA_B0_MBP2_N"
					( Origin gPackager )
				)
				( objectStatus "TP_XDP_CPU1_OBSDATA_B0_MBP2_N" )
			)
			( signal "@baseboard_fab2_lib.baseboard_fab2(sch_1):tp_xdp_cpu1_obsdata_b1_mbp3_n"
				( attribute "CDS_PHYS_NET_NAME" "TP_XDP_CPU1_OBSDATA_B1_MBP3_N"
					( Origin gPackager )
				)
				( objectStatus "TP_XDP_CPU1_OBSDATA_B1_MBP3_N" )
			)
			( signal "@baseboard_fab2_lib.baseboard_fab2(sch_1):tp_xdp_cpu1_obsdata_b2_mbp4_n"
				( attribute "CDS_PHYS_NET_NAME" "TP_XDP_CPU1_OBSDATA_B2_MBP4_N"
					( Origin gPackager )
				)
				( objectStatus "TP_XDP_CPU1_OBSDATA_B2_MBP4_N" )
			)
			( signal "@baseboard_fab2_lib.baseboard_fab2(sch_1):tp_xdp_cpu1_obsdata_b3_mbp5_n"
				( attribute "CDS_PHYS_NET_NAME" "TP_XDP_CPU1_OBSDATA_B3_MBP5_N"
					( Origin gPackager )
				)
				( objectStatus "TP_XDP_CPU1_OBSDATA_B3_MBP5_N" )
			)
			( signal "@baseboard_fab2_lib.baseboard_fab2(sch_1):xdp_cpu1_tdi"
				( attribute "CDS_PHYS_NET_NAME" "XDP_CPU1_TDI"
					( Origin gPackager )
				)
				( objectStatus "XDP_CPU1_TDI" )
			)
			( signal "@baseboard_fab2_lib.baseboard_fab2(sch_1):xdp_cpu1_tdo"
				( attribute "CDS_PHYS_NET_NAME" "XDP_CPU1_TDO"
					( Origin gPackager )
				)
				( objectStatus "XDP_CPU1_TDO" )
			)
			( signal "@baseboard_fab2_lib.baseboard_fab2(sch_1):clk_100m_cpu1_rc_refclk0_dn"
				( attribute "CDS_PHYS_NET_NAME" "CLK_100M_CPU1_RC_REFCLK0_DN"
					( Origin gPackager )
				)
				( objectStatus "CLK_100M_CPU1_RC_REFCLK0_DN" )
			)
			( signal "@baseboard_fab2_lib.baseboard_fab2(sch_1):clk_100m_cpu1_rc_refclk0_dp"
				( attribute "CDS_PHYS_NET_NAME" "CLK_100M_CPU1_RC_REFCLK0_DP"
					( Origin gPackager )
				)
				( objectStatus "CLK_100M_CPU1_RC_REFCLK0_DP" )
			)
			( signal "@baseboard_fab2_lib.baseboard_fab2(sch_1):clk_322m_osc_cpu1_rc_dn"
				( attribute "CDS_PHYS_NET_NAME" "CLK_322M_OSC_CPU1_RC_DN"
					( Origin gPackager )
				)
				( objectStatus "CLK_322M_OSC_CPU1_RC_DN" )
			)
			( signal "@baseboard_fab2_lib.baseboard_fab2(sch_1):clk_322m_osc_cpu1_rc_dp"
				( attribute "CDS_PHYS_NET_NAME" "CLK_322M_OSC_CPU1_RC_DP"
					( Origin gPackager )
				)
				( objectStatus "CLK_322M_OSC_CPU1_RC_DP" )
			)
			( signal "@baseboard_fab2_lib.baseboard_fab2(sch_1):fm_cpu1_rc_error_n"
				( alias ( signalRef "@baseboard_fab2_lib.baseboard_fab2(sch_1):page145_fm_cpu1_rc_error_n") )
				( attribute "CDS_PHYS_NET_NAME" "FM_CPU1_RC_ERROR_N"
					( Origin gPackager )
				)
				( attribute "PHYS_NET_NAME" "FM_CPU1_RC_ERROR_N"
					( Origin gPackager )
				)
				( objectStatus "FM_CPU1_RC_ERROR_N" )
			)
			( signal "@baseboard_fab2_lib.baseboard_fab2(sch_1):page145_fm_cpu1_rc_error_n"
				( attribute "CDS_PHYS_NET_NAME" "FM_CPU1_RC_ERROR_N"
					( Origin gPackager )
				)
				( attribute "PHYS_NET_NAME" "FM_CPU1_RC_ERROR_N"
					( Origin gFrontEnd )
				)
				( objectFlag fObjectAlias )
				( objectStatus "page145_fm_cpu1_rc_error_n" )
			)
			( signal "@baseboard_fab2_lib.baseboard_fab2(sch_1):h_cpu1_fivr_fault_g"
				( attribute "CDS_PHYS_NET_NAME" "H_CPU1_FIVR_FAULT_G"
					( Origin gPackager )
				)
				( objectStatus "H_CPU1_FIVR_FAULT_G" )
			)
			( signal "@baseboard_fab2_lib.baseboard_fab2(sch_1):p1v8_mcp_cpu1"
				( alias ( signalRef "@baseboard_fab2_lib.baseboard_fab2(sch_1):page56_p1v8_mcp_cpu1") )
				( alias ( signalRef "@baseboard_fab2_lib.baseboard_fab2(sch_1):page72_p1v8_mcp_cpu1") )
				( alias ( signalRef "@baseboard_fab2_lib.baseboard_fab2(sch_1):page113_p1v8_mcp_cpu1") )
				( alias ( signalRef "@baseboard_fab2_lib.baseboard_fab2(sch_1):page193_p1v8_mcp_cpu1") )
				( attribute "VOLTAGE" "1.8"
					( Units "uVoltage" "V" 1.000000)
					( Status sAliasFlattened )
					( Origin gFrontEnd )
				)
				( attribute "CDS_PHYS_NET_NAME" "P1V8_MCP_CPU1"
					( Origin gPackager )
				)
				( objectStatus "P1V8_MCP_CPU1" )
			)
			( signal "@baseboard_fab2_lib.baseboard_fab2(sch_1):page56_p1v8_mcp_cpu1"
				( attribute "VOLTAGE" "1.8"
					( Units "uVoltage" "V" 1.000000)
					( Origin gFrontEnd )
				)
				( objectFlag fObjectAlias )
				( objectStatus "page56_p1v8_mcp_cpu1" )
			)
			( signal "@baseboard_fab2_lib.baseboard_fab2(sch_1):page72_p1v8_mcp_cpu1"
				( attribute "VOLTAGE" "1.8"
					( Units "uVoltage" "V" 1.000000)
					( Origin gFrontEnd )
				)
				( objectFlag fObjectAlias )
				( objectStatus "page72_p1v8_mcp_cpu1" )
			)
			( signal "@baseboard_fab2_lib.baseboard_fab2(sch_1):page113_p1v8_mcp_cpu1"
				( attribute "VOLTAGE" "1.8"
					( Units "uVoltage" "V" 1.000000)
					( Origin gFrontEnd )
				)
				( objectFlag fObjectAlias )
				( objectStatus "page113_p1v8_mcp_cpu1" )
			)
			( signal "@baseboard_fab2_lib.baseboard_fab2(sch_1):page193_p1v8_mcp_cpu1"
				( attribute "VOLTAGE" "1.8"
					( Units "uVoltage" "V" 1.000000)
					( Origin gFrontEnd )
				)
				( objectFlag fObjectAlias )
				( objectStatus "page193_p1v8_mcp_cpu1" )
			)
			( signal "@baseboard_fab2_lib.baseboard_fab2(sch_1):pd_cpu1_dmimode_override"
				( attribute "CDS_PHYS_NET_NAME" "PD_CPU1_DMIMODE_OVERRIDE"
					( Origin gPackager )
				)
				( objectStatus "PD_CPU1_DMIMODE_OVERRIDE" )
			)
			( signal "@baseboard_fab2_lib.baseboard_fab2(sch_1):pd_cpu1_rsvd_test_1"
				( attribute "CDS_PHYS_NET_NAME" "PD_CPU1_RSVD_TEST_1"
					( Origin gPackager )
				)
				( objectStatus "PD_CPU1_RSVD_TEST_1" )
			)
			( signal "@baseboard_fab2_lib.baseboard_fab2(sch_1):pd_cpu1_rsvd_test_2"
				( attribute "CDS_PHYS_NET_NAME" "PD_CPU1_RSVD_TEST_2"
					( Origin gPackager )
				)
				( objectStatus "PD_CPU1_RSVD_TEST_2" )
			)
			( signal "@baseboard_fab2_lib.baseboard_fab2(sch_1):pvccmcp_cpu1"
				( alias ( signalRef "@baseboard_fab2_lib.baseboard_fab2(sch_1):page56_pvccmcp_cpu1") )
				( alias ( signalRef "@baseboard_fab2_lib.baseboard_fab2(sch_1):page63_pvccmcp_cpu1") )
				( alias ( signalRef "@baseboard_fab2_lib.baseboard_fab2(sch_1):page70_pvccmcp_cpu1") )
				( alias ( signalRef "@baseboard_fab2_lib.baseboard_fab2(sch_1):page72_pvccmcp_cpu1") )
				( alias ( signalRef "@baseboard_fab2_lib.baseboard_fab2(sch_1):page73_pvccmcp_cpu1") )
				( alias ( signalRef "@baseboard_fab2_lib.baseboard_fab2(sch_1):page76_pvccmcp_cpu1") )
				( alias ( signalRef "@baseboard_fab2_lib.baseboard_fab2(sch_1):page193_pvccmcp_cpu1") )
				( attribute "VOLTAGE" "+0.95"
					( Units "uVoltage" "V" 1.000000)
					( Status sAliasFlattened )
					( Origin gFrontEnd )
				)
				( attribute "CDS_PHYS_NET_NAME" "PVCCMCP_CPU1"
					( Origin gPackager )
				)
				( objectStatus "PVCCMCP_CPU1" )
			)
			( signal "@baseboard_fab2_lib.baseboard_fab2(sch_1):page56_pvccmcp_cpu1"
				( objectFlag fObjectAlias )
				( objectStatus "page56_pvccmcp_cpu1" )
			)
			( signal "@baseboard_fab2_lib.baseboard_fab2(sch_1):page63_pvccmcp_cpu1"
				( objectFlag fObjectAlias )
				( objectStatus "page63_pvccmcp_cpu1" )
			)
			( signal "@baseboard_fab2_lib.baseboard_fab2(sch_1):page70_pvccmcp_cpu1"
				( objectFlag fObjectAlias )
				( objectStatus "page70_pvccmcp_cpu1" )
			)
			( signal "@baseboard_fab2_lib.baseboard_fab2(sch_1):page72_pvccmcp_cpu1"
				( objectFlag fObjectAlias )
				( objectStatus "page72_pvccmcp_cpu1" )
			)
			( signal "@baseboard_fab2_lib.baseboard_fab2(sch_1):page73_pvccmcp_cpu1"
				( objectFlag fObjectAlias )
				( objectStatus "page73_pvccmcp_cpu1" )
			)
			( signal "@baseboard_fab2_lib.baseboard_fab2(sch_1):page76_pvccmcp_cpu1"
				( objectFlag fObjectAlias )
				( objectStatus "page76_pvccmcp_cpu1" )
			)
			( signal "@baseboard_fab2_lib.baseboard_fab2(sch_1):page193_pvccmcp_cpu1"
				( attribute "VOLTAGE" "+0.95"
					( Units "uVoltage" "V" 1.000000)
					( Origin gFrontEnd )
				)
				( objectFlag fObjectAlias )
				( objectStatus "page193_pvccmcp_cpu1" )
			)
			( signal "@baseboard_fab2_lib.baseboard_fab2(sch_1):tp_cpu1_rsvd_194"
				( attribute "CDS_PHYS_NET_NAME" "TP_CPU1_RSVD_194"
					( Origin gPackager )
				)
				( objectStatus "TP_CPU1_RSVD_194" )
			)
			( signal "@baseboard_fab2_lib.baseboard_fab2(sch_1):tp_cpu1_rsvd_198"
				( attribute "CDS_PHYS_NET_NAME" "TP_CPU1_RSVD_198"
					( Origin gPackager )
				)
				( objectStatus "TP_CPU1_RSVD_198" )
			)
			( signal "@baseboard_fab2_lib.baseboard_fab2(sch_1):tp_cpu1_rsvd_199"
				( attribute "CDS_PHYS_NET_NAME" "TP_CPU1_RSVD_199"
					( Origin gPackager )
				)
				( objectStatus "TP_CPU1_RSVD_199" )
			)
			( signal "@baseboard_fab2_lib.baseboard_fab2(sch_1):tp_cpu1_rsvd_204"
				( attribute "CDS_PHYS_NET_NAME" "TP_CPU1_RSVD_204"
					( Origin gPackager )
				)
				( objectStatus "TP_CPU1_RSVD_204" )
			)
			( signal "@baseboard_fab2_lib.baseboard_fab2(sch_1):tp_cpu1_rsvd_205"
				( attribute "CDS_PHYS_NET_NAME" "TP_CPU1_RSVD_205"
					( Origin gPackager )
				)
				( objectStatus "TP_CPU1_RSVD_205" )
			)
			( signal "@baseboard_fab2_lib.baseboard_fab2(sch_1):tp_cpu1_rsvd_208"
				( attribute "CDS_PHYS_NET_NAME" "TP_CPU1_RSVD_208"
					( Origin gPackager )
				)
				( objectStatus "TP_CPU1_RSVD_208" )
			)
			( signal "@baseboard_fab2_lib.baseboard_fab2(sch_1):tp_cpu1_rsvd_210"
				( attribute "CDS_PHYS_NET_NAME" "TP_CPU1_RSVD_210"
					( Origin gPackager )
				)
				( objectStatus "TP_CPU1_RSVD_210" )
			)
			( signal "@baseboard_fab2_lib.baseboard_fab2(sch_1):tp_cpu1_rsvd_211"
				( attribute "CDS_PHYS_NET_NAME" "TP_CPU1_RSVD_211"
					( Origin gPackager )
				)
				( objectStatus "TP_CPU1_RSVD_211" )
			)
			( signal "@baseboard_fab2_lib.baseboard_fab2(sch_1):tp_cpu1_rsvd_212"
				( attribute "CDS_PHYS_NET_NAME" "TP_CPU1_RSVD_212"
					( Origin gPackager )
				)
				( objectStatus "TP_CPU1_RSVD_212" )
			)
			( signal "@baseboard_fab2_lib.baseboard_fab2(sch_1):tp_cpu1_rsvd_214"
				( attribute "CDS_PHYS_NET_NAME" "TP_CPU1_RSVD_214"
					( Origin gPackager )
				)
				( objectStatus "TP_CPU1_RSVD_214" )
			)
			( signal "@baseboard_fab2_lib.baseboard_fab2(sch_1):tp_cpu1_rsvd_216"
				( attribute "CDS_PHYS_NET_NAME" "TP_CPU1_RSVD_216"
					( Origin gPackager )
				)
				( objectStatus "TP_CPU1_RSVD_216" )
			)
			( signal "@baseboard_fab2_lib.baseboard_fab2(sch_1):tp_cpu1_rsvd_217"
				( attribute "CDS_PHYS_NET_NAME" "TP_CPU1_RSVD_217"
					( Origin gPackager )
				)
				( objectStatus "TP_CPU1_RSVD_217" )
			)
			( signal "@baseboard_fab2_lib.baseboard_fab2(sch_1):tp_cpu1_rsvd_218"
				( attribute "CDS_PHYS_NET_NAME" "TP_CPU1_RSVD_218"
					( Origin gPackager )
				)
				( objectStatus "TP_CPU1_RSVD_218" )
			)
			( signal "@baseboard_fab2_lib.baseboard_fab2(sch_1):tp_cpu1_rsvd_219"
				( attribute "CDS_PHYS_NET_NAME" "TP_CPU1_RSVD_219"
					( Origin gPackager )
				)
				( objectStatus "TP_CPU1_RSVD_219" )
			)
			( signal "@baseboard_fab2_lib.baseboard_fab2(sch_1):tp_cpu1_rsvd_222"
				( attribute "CDS_PHYS_NET_NAME" "TP_CPU1_RSVD_222"
					( Origin gPackager )
				)
				( objectStatus "TP_CPU1_RSVD_222" )
			)
			( signal "@baseboard_fab2_lib.baseboard_fab2(sch_1):tp_cpu1_rsvd_223"
				( attribute "CDS_PHYS_NET_NAME" "TP_CPU1_RSVD_223"
					( Origin gPackager )
				)
				( objectStatus "TP_CPU1_RSVD_223" )
			)
			( signal "@baseboard_fab2_lib.baseboard_fab2(sch_1):tp_cpu1_rsvd_224"
				( attribute "CDS_PHYS_NET_NAME" "TP_CPU1_RSVD_224"
					( Origin gPackager )
				)
				( objectStatus "TP_CPU1_RSVD_224" )
			)
			( signal "@baseboard_fab2_lib.baseboard_fab2(sch_1):tp_cpu1_rsvd_225"
				( attribute "CDS_PHYS_NET_NAME" "TP_CPU1_RSVD_225"
					( Origin gPackager )
				)
				( objectStatus "TP_CPU1_RSVD_225" )
			)
			( signal "@baseboard_fab2_lib.baseboard_fab2(sch_1):tp_cpu1_rsvd_226"
				( attribute "CDS_PHYS_NET_NAME" "TP_CPU1_RSVD_226"
					( Origin gPackager )
				)
				( objectStatus "TP_CPU1_RSVD_226" )
			)
			( signal "@baseboard_fab2_lib.baseboard_fab2(sch_1):tp_cpu1_rsvd_227"
				( attribute "CDS_PHYS_NET_NAME" "TP_CPU1_RSVD_227"
					( Origin gPackager )
				)
				( objectStatus "TP_CPU1_RSVD_227" )
			)
			( signal "@baseboard_fab2_lib.baseboard_fab2(sch_1):tp_cpu1_rsvd_228"
				( attribute "CDS_PHYS_NET_NAME" "TP_CPU1_RSVD_228"
					( Origin gPackager )
				)
				( objectStatus "TP_CPU1_RSVD_228" )
			)
			( signal "@baseboard_fab2_lib.baseboard_fab2(sch_1):tp_cpu1_rsvd_229"
				( attribute "CDS_PHYS_NET_NAME" "TP_CPU1_RSVD_229"
					( Origin gPackager )
				)
				( objectStatus "TP_CPU1_RSVD_229" )
			)
			( signal "@baseboard_fab2_lib.baseboard_fab2(sch_1):tp_cpu1_rsvd_230"
				( attribute "CDS_PHYS_NET_NAME" "TP_CPU1_RSVD_230"
					( Origin gPackager )
				)
				( objectStatus "TP_CPU1_RSVD_230" )
			)
			( signal "@baseboard_fab2_lib.baseboard_fab2(sch_1):tp_cpu1_rsvd_231"
				( attribute "CDS_PHYS_NET_NAME" "TP_CPU1_RSVD_231"
					( Origin gPackager )
				)
				( objectStatus "TP_CPU1_RSVD_231" )
			)
			( signal "@baseboard_fab2_lib.baseboard_fab2(sch_1):tp_cpu1_rsvd_232"
				( attribute "CDS_PHYS_NET_NAME" "TP_CPU1_RSVD_232"
					( Origin gPackager )
				)
				( objectStatus "TP_CPU1_RSVD_232" )
			)
			( signal "@baseboard_fab2_lib.baseboard_fab2(sch_1):tp_cpu1_rsvd_233"
				( attribute "CDS_PHYS_NET_NAME" "TP_CPU1_RSVD_233"
					( Origin gPackager )
				)
				( objectStatus "TP_CPU1_RSVD_233" )
			)
			( signal "@baseboard_fab2_lib.baseboard_fab2(sch_1):tp_cpu1_rsvd_234"
				( attribute "CDS_PHYS_NET_NAME" "TP_CPU1_RSVD_234"
					( Origin gPackager )
				)
				( objectStatus "TP_CPU1_RSVD_234" )
			)
			( signal "@baseboard_fab2_lib.baseboard_fab2(sch_1):tp_cpu1_rsvd_235"
				( attribute "CDS_PHYS_NET_NAME" "TP_CPU1_RSVD_235"
					( Origin gPackager )
				)
				( objectStatus "TP_CPU1_RSVD_235" )
			)
			( signal "@baseboard_fab2_lib.baseboard_fab2(sch_1):tp_cpu1_rsvd_236"
				( attribute "CDS_PHYS_NET_NAME" "TP_CPU1_RSVD_236"
					( Origin gPackager )
				)
				( objectStatus "TP_CPU1_RSVD_236" )
			)
			( signal "@baseboard_fab2_lib.baseboard_fab2(sch_1):tp_cpu1_rsvd_237"
				( attribute "CDS_PHYS_NET_NAME" "TP_CPU1_RSVD_237"
					( Origin gPackager )
				)
				( objectStatus "TP_CPU1_RSVD_237" )
			)
			( signal "@baseboard_fab2_lib.baseboard_fab2(sch_1):tp_cpu1_rsvd_238"
				( attribute "CDS_PHYS_NET_NAME" "TP_CPU1_RSVD_238"
					( Origin gPackager )
				)
				( objectStatus "TP_CPU1_RSVD_238" )
			)
			( signal "@baseboard_fab2_lib.baseboard_fab2(sch_1):tp_cpu1_rsvd_239"
				( attribute "CDS_PHYS_NET_NAME" "TP_CPU1_RSVD_239"
					( Origin gPackager )
				)
				( objectStatus "TP_CPU1_RSVD_239" )
			)
			( signal "@baseboard_fab2_lib.baseboard_fab2(sch_1):tp_cpu1_rsvd_240"
				( attribute "CDS_PHYS_NET_NAME" "TP_CPU1_RSVD_240"
					( Origin gPackager )
				)
				( objectStatus "TP_CPU1_RSVD_240" )
			)
			( signal "@baseboard_fab2_lib.baseboard_fab2(sch_1):tp_cpu1_rsvd_241"
				( attribute "CDS_PHYS_NET_NAME" "TP_CPU1_RSVD_241"
					( Origin gPackager )
				)
				( objectStatus "TP_CPU1_RSVD_241" )
			)
			( signal "@baseboard_fab2_lib.baseboard_fab2(sch_1):tp_cpu1_rsvd_242"
				( attribute "CDS_PHYS_NET_NAME" "TP_CPU1_RSVD_242"
					( Origin gPackager )
				)
				( objectStatus "TP_CPU1_RSVD_242" )
			)
			( signal "@baseboard_fab2_lib.baseboard_fab2(sch_1):tp_cpu1_rsvd_243"
				( attribute "CDS_PHYS_NET_NAME" "TP_CPU1_RSVD_243"
					( Origin gPackager )
				)
				( objectStatus "TP_CPU1_RSVD_243" )
			)
			( signal "@baseboard_fab2_lib.baseboard_fab2(sch_1):tp_cpu1_rsvd_244"
				( attribute "CDS_PHYS_NET_NAME" "TP_CPU1_RSVD_244"
					( Origin gPackager )
				)
				( objectStatus "TP_CPU1_RSVD_244" )
			)
			( signal "@baseboard_fab2_lib.baseboard_fab2(sch_1):tp_cpu1_rsvd_245"
				( attribute "CDS_PHYS_NET_NAME" "TP_CPU1_RSVD_245"
					( Origin gPackager )
				)
				( objectStatus "TP_CPU1_RSVD_245" )
			)
			( signal "@baseboard_fab2_lib.baseboard_fab2(sch_1):tp_cpu1_rsvd_246"
				( attribute "CDS_PHYS_NET_NAME" "TP_CPU1_RSVD_246"
					( Origin gPackager )
				)
				( objectStatus "TP_CPU1_RSVD_246" )
			)
			( signal "@baseboard_fab2_lib.baseboard_fab2(sch_1):tp_cpu1_rsvd_247"
				( attribute "CDS_PHYS_NET_NAME" "TP_CPU1_RSVD_247"
					( Origin gPackager )
				)
				( objectStatus "TP_CPU1_RSVD_247" )
			)
			( signal "@baseboard_fab2_lib.baseboard_fab2(sch_1):tp_cpu1_rsvd_248"
				( attribute "CDS_PHYS_NET_NAME" "TP_CPU1_RSVD_248"
					( Origin gPackager )
				)
				( objectStatus "TP_CPU1_RSVD_248" )
			)
			( signal "@baseboard_fab2_lib.baseboard_fab2(sch_1):tp_cpu1_rsvd_249"
				( attribute "CDS_PHYS_NET_NAME" "TP_CPU1_RSVD_249"
					( Origin gPackager )
				)
				( objectStatus "TP_CPU1_RSVD_249" )
			)
			( signal "@baseboard_fab2_lib.baseboard_fab2(sch_1):tp_cpu1_rsvd_250"
				( attribute "CDS_PHYS_NET_NAME" "TP_CPU1_RSVD_250"
					( Origin gPackager )
				)
				( objectStatus "TP_CPU1_RSVD_250" )
			)
			( signal "@baseboard_fab2_lib.baseboard_fab2(sch_1):tp_cpu1_rsvd_251"
				( attribute "CDS_PHYS_NET_NAME" "TP_CPU1_RSVD_251"
					( Origin gPackager )
				)
				( objectStatus "TP_CPU1_RSVD_251" )
			)
			( signal "@baseboard_fab2_lib.baseboard_fab2(sch_1):tp_cpu1_rsvd_252"
				( attribute "CDS_PHYS_NET_NAME" "TP_CPU1_RSVD_252"
					( Origin gPackager )
				)
				( objectStatus "TP_CPU1_RSVD_252" )
			)
			( signal "@baseboard_fab2_lib.baseboard_fab2(sch_1):tp_cpu1_rsvd_253"
				( attribute "CDS_PHYS_NET_NAME" "TP_CPU1_RSVD_253"
					( Origin gPackager )
				)
				( objectStatus "TP_CPU1_RSVD_253" )
			)
			( signal "@baseboard_fab2_lib.baseboard_fab2(sch_1):tp_cpu1_rsvd_254"
				( attribute "CDS_PHYS_NET_NAME" "TP_CPU1_RSVD_254"
					( Origin gPackager )
				)
				( objectStatus "TP_CPU1_RSVD_254" )
			)
			( signal "@baseboard_fab2_lib.baseboard_fab2(sch_1):tp_cpu1_rsvd_256"
				( attribute "CDS_PHYS_NET_NAME" "TP_CPU1_RSVD_256"
					( Origin gPackager )
				)
				( objectStatus "TP_CPU1_RSVD_256" )
			)
			( signal "@baseboard_fab2_lib.baseboard_fab2(sch_1):tp_cpu1_rsvd_258"
				( attribute "CDS_PHYS_NET_NAME" "TP_CPU1_RSVD_258"
					( Origin gPackager )
				)
				( objectStatus "TP_CPU1_RSVD_258" )
			)
			( signal "@baseboard_fab2_lib.baseboard_fab2(sch_1):tp_cpu1_rsvd_259"
				( attribute "CDS_PHYS_NET_NAME" "TP_CPU1_RSVD_259"
					( Origin gPackager )
				)
				( objectStatus "TP_CPU1_RSVD_259" )
			)
			( signal "@baseboard_fab2_lib.baseboard_fab2(sch_1):tp_cpu1_rsvd_260"
				( attribute "CDS_PHYS_NET_NAME" "TP_CPU1_RSVD_260"
					( Origin gPackager )
				)
				( objectStatus "TP_CPU1_RSVD_260" )
			)
			( signal "@baseboard_fab2_lib.baseboard_fab2(sch_1):tp_cpu1_rsvd_261"
				( attribute "CDS_PHYS_NET_NAME" "TP_CPU1_RSVD_261"
					( Origin gPackager )
				)
				( objectStatus "TP_CPU1_RSVD_261" )
			)
			( signal "@baseboard_fab2_lib.baseboard_fab2(sch_1):tp_cpu1_rsvd_262"
				( attribute "CDS_PHYS_NET_NAME" "TP_CPU1_RSVD_262"
					( Origin gPackager )
				)
				( objectStatus "TP_CPU1_RSVD_262" )
			)
			( signal "@baseboard_fab2_lib.baseboard_fab2(sch_1):tp_cpu1_rsvd_263"
				( attribute "CDS_PHYS_NET_NAME" "TP_CPU1_RSVD_263"
					( Origin gPackager )
				)
				( objectStatus "TP_CPU1_RSVD_263" )
			)
			( signal "@baseboard_fab2_lib.baseboard_fab2(sch_1):tp_cpu1_rsvd_264"
				( attribute "CDS_PHYS_NET_NAME" "TP_CPU1_RSVD_264"
					( Origin gPackager )
				)
				( objectStatus "TP_CPU1_RSVD_264" )
			)
			( signal "@baseboard_fab2_lib.baseboard_fab2(sch_1):tp_cpu1_rsvd_265"
				( attribute "CDS_PHYS_NET_NAME" "TP_CPU1_RSVD_265"
					( Origin gPackager )
				)
				( objectStatus "TP_CPU1_RSVD_265" )
			)
			( signal "@baseboard_fab2_lib.baseboard_fab2(sch_1):tp_cpu1_rsvd_266"
				( attribute "CDS_PHYS_NET_NAME" "TP_CPU1_RSVD_266"
					( Origin gPackager )
				)
				( objectStatus "TP_CPU1_RSVD_266" )
			)
			( signal "@baseboard_fab2_lib.baseboard_fab2(sch_1):tp_cpu1_rsvd_267"
				( attribute "CDS_PHYS_NET_NAME" "TP_CPU1_RSVD_267"
					( Origin gPackager )
				)
				( objectStatus "TP_CPU1_RSVD_267" )
			)
			( signal "@baseboard_fab2_lib.baseboard_fab2(sch_1):tp_cpu1_rsvd_268"
				( attribute "CDS_PHYS_NET_NAME" "TP_CPU1_RSVD_268"
					( Origin gPackager )
				)
				( objectStatus "TP_CPU1_RSVD_268" )
			)
			( signal "@baseboard_fab2_lib.baseboard_fab2(sch_1):tp_cpu1_rsvd_269"
				( attribute "CDS_PHYS_NET_NAME" "TP_CPU1_RSVD_269"
					( Origin gPackager )
				)
				( objectStatus "TP_CPU1_RSVD_269" )
			)
			( signal "@baseboard_fab2_lib.baseboard_fab2(sch_1):tp_cpu1_rsvd_270"
				( attribute "CDS_PHYS_NET_NAME" "TP_CPU1_RSVD_270"
					( Origin gPackager )
				)
				( objectStatus "TP_CPU1_RSVD_270" )
			)
			( signal "@baseboard_fab2_lib.baseboard_fab2(sch_1):tp_cpu1_rsvd_271"
				( attribute "CDS_PHYS_NET_NAME" "TP_CPU1_RSVD_271"
					( Origin gPackager )
				)
				( objectStatus "TP_CPU1_RSVD_271" )
			)
			( signal "@baseboard_fab2_lib.baseboard_fab2(sch_1):tp_cpu1_rsvd_272"
				( attribute "CDS_PHYS_NET_NAME" "TP_CPU1_RSVD_272"
					( Origin gPackager )
				)
				( objectStatus "TP_CPU1_RSVD_272" )
			)
			( signal "@baseboard_fab2_lib.baseboard_fab2(sch_1):tp_cpu1_rsvd_273"
				( attribute "CDS_PHYS_NET_NAME" "TP_CPU1_RSVD_273"
					( Origin gPackager )
				)
				( objectStatus "TP_CPU1_RSVD_273" )
			)
			( signal "@baseboard_fab2_lib.baseboard_fab2(sch_1):tp_cpu1_rsvd_274"
				( attribute "CDS_PHYS_NET_NAME" "TP_CPU1_RSVD_274"
					( Origin gPackager )
				)
				( objectStatus "TP_CPU1_RSVD_274" )
			)
			( signal "@baseboard_fab2_lib.baseboard_fab2(sch_1):tp_cpu1_rsvd_275"
				( attribute "CDS_PHYS_NET_NAME" "TP_CPU1_RSVD_275"
					( Origin gPackager )
				)
				( objectStatus "TP_CPU1_RSVD_275" )
			)
			( signal "@baseboard_fab2_lib.baseboard_fab2(sch_1):tp_cpu1_rsvd_276"
				( attribute "CDS_PHYS_NET_NAME" "TP_CPU1_RSVD_276"
					( Origin gPackager )
				)
				( objectStatus "TP_CPU1_RSVD_276" )
			)
			( signal "@baseboard_fab2_lib.baseboard_fab2(sch_1):tp_cpu1_rsvd_277"
				( attribute "CDS_PHYS_NET_NAME" "TP_CPU1_RSVD_277"
					( Origin gPackager )
				)
				( objectStatus "TP_CPU1_RSVD_277" )
			)
			( signal "@baseboard_fab2_lib.baseboard_fab2(sch_1):tp_cpu1_rsvd_278"
				( attribute "CDS_PHYS_NET_NAME" "TP_CPU1_RSVD_278"
					( Origin gPackager )
				)
				( objectStatus "TP_CPU1_RSVD_278" )
			)
			( signal "@baseboard_fab2_lib.baseboard_fab2(sch_1):tp_cpu1_rsvd_279"
				( attribute "CDS_PHYS_NET_NAME" "TP_CPU1_RSVD_279"
					( Origin gPackager )
				)
				( objectStatus "TP_CPU1_RSVD_279" )
			)
			( signal "@baseboard_fab2_lib.baseboard_fab2(sch_1):tp_cpu1_rsvd_280"
				( attribute "CDS_PHYS_NET_NAME" "TP_CPU1_RSVD_280"
					( Origin gPackager )
				)
				( objectStatus "TP_CPU1_RSVD_280" )
			)
			( signal "@baseboard_fab2_lib.baseboard_fab2(sch_1):tp_cpu1_rsvd_281"
				( attribute "CDS_PHYS_NET_NAME" "TP_CPU1_RSVD_281"
					( Origin gPackager )
				)
				( objectStatus "TP_CPU1_RSVD_281" )
			)
			( signal "@baseboard_fab2_lib.baseboard_fab2(sch_1):tp_cpu1_rsvd_282"
				( attribute "CDS_PHYS_NET_NAME" "TP_CPU1_RSVD_282"
					( Origin gPackager )
				)
				( objectStatus "TP_CPU1_RSVD_282" )
			)
			( signal "@baseboard_fab2_lib.baseboard_fab2(sch_1):tp_cpu1_rsvd_283"
				( attribute "CDS_PHYS_NET_NAME" "TP_CPU1_RSVD_283"
					( Origin gPackager )
				)
				( objectStatus "TP_CPU1_RSVD_283" )
			)
			( signal "@baseboard_fab2_lib.baseboard_fab2(sch_1):tp_cpu1_rsvd_284"
				( attribute "CDS_PHYS_NET_NAME" "TP_CPU1_RSVD_284"
					( Origin gPackager )
				)
				( objectStatus "TP_CPU1_RSVD_284" )
			)
			( signal "@baseboard_fab2_lib.baseboard_fab2(sch_1):tp_cpu1_rsvd_285"
				( attribute "CDS_PHYS_NET_NAME" "TP_CPU1_RSVD_285"
					( Origin gPackager )
				)
				( objectStatus "TP_CPU1_RSVD_285" )
			)
			( signal "@baseboard_fab2_lib.baseboard_fab2(sch_1):tp_cpu1_rsvd_286"
				( attribute "CDS_PHYS_NET_NAME" "TP_CPU1_RSVD_286"
					( Origin gPackager )
				)
				( objectStatus "TP_CPU1_RSVD_286" )
			)
			( signal "@baseboard_fab2_lib.baseboard_fab2(sch_1):tp_cpu1_rsvd_287"
				( attribute "CDS_PHYS_NET_NAME" "TP_CPU1_RSVD_287"
					( Origin gPackager )
				)
				( objectStatus "TP_CPU1_RSVD_287" )
			)
			( signal "@baseboard_fab2_lib.baseboard_fab2(sch_1):tp_cpu1_rsvd_288"
				( attribute "CDS_PHYS_NET_NAME" "TP_CPU1_RSVD_288"
					( Origin gPackager )
				)
				( objectStatus "TP_CPU1_RSVD_288" )
			)
			( signal "@baseboard_fab2_lib.baseboard_fab2(sch_1):tp_cpu1_rsvd_289"
				( attribute "CDS_PHYS_NET_NAME" "TP_CPU1_RSVD_289"
					( Origin gPackager )
				)
				( objectStatus "TP_CPU1_RSVD_289" )
			)
			( signal "@baseboard_fab2_lib.baseboard_fab2(sch_1):tp_cpu1_rsvd_290"
				( attribute "CDS_PHYS_NET_NAME" "TP_CPU1_RSVD_290"
					( Origin gPackager )
				)
				( objectStatus "TP_CPU1_RSVD_290" )
			)
			( signal "@baseboard_fab2_lib.baseboard_fab2(sch_1):tp_cpu1_rsvd_291"
				( attribute "CDS_PHYS_NET_NAME" "TP_CPU1_RSVD_291"
					( Origin gPackager )
				)
				( objectStatus "TP_CPU1_RSVD_291" )
			)
			( signal "@baseboard_fab2_lib.baseboard_fab2(sch_1):tp_cpu1_rsvd_292"
				( attribute "CDS_PHYS_NET_NAME" "TP_CPU1_RSVD_292"
					( Origin gPackager )
				)
				( objectStatus "TP_CPU1_RSVD_292" )
			)
			( signal "@baseboard_fab2_lib.baseboard_fab2(sch_1):tp_cpu1_rsvd_293"
				( attribute "CDS_PHYS_NET_NAME" "TP_CPU1_RSVD_293"
					( Origin gPackager )
				)
				( objectStatus "TP_CPU1_RSVD_293" )
			)
			( signal "@baseboard_fab2_lib.baseboard_fab2(sch_1):tp_cpu1_rsvd_298"
				( attribute "CDS_PHYS_NET_NAME" "TP_CPU1_RSVD_298"
					( Origin gPackager )
				)
				( objectStatus "TP_CPU1_RSVD_298" )
			)
			( signal "@baseboard_fab2_lib.baseboard_fab2(sch_1):tp_cpu1_rsvd_299"
				( attribute "CDS_PHYS_NET_NAME" "TP_CPU1_RSVD_299"
					( Origin gPackager )
				)
				( objectStatus "TP_CPU1_RSVD_299" )
			)
			( signal "@baseboard_fab2_lib.baseboard_fab2(sch_1):tp_cpu1_rsvd_300"
				( attribute "CDS_PHYS_NET_NAME" "TP_CPU1_RSVD_300"
					( Origin gPackager )
				)
				( objectStatus "TP_CPU1_RSVD_300" )
			)
			( signal "@baseboard_fab2_lib.baseboard_fab2(sch_1):tp_cpu1_rsvd_303"
				( attribute "CDS_PHYS_NET_NAME" "TP_CPU1_RSVD_303"
					( Origin gPackager )
				)
				( objectStatus "TP_CPU1_RSVD_303" )
			)
			( signal "@baseboard_fab2_lib.baseboard_fab2(sch_1):tp_cpu1_rsvd_304"
				( attribute "CDS_PHYS_NET_NAME" "TP_CPU1_RSVD_304"
					( Origin gPackager )
				)
				( objectStatus "TP_CPU1_RSVD_304" )
			)
			( signal "@baseboard_fab2_lib.baseboard_fab2(sch_1):tp_cpu1_rsvd_test_11"
				( attribute "CDS_PHYS_NET_NAME" "TP_CPU1_RSVD_TEST_11"
					( Origin gPackager )
				)
				( objectStatus "TP_CPU1_RSVD_TEST_11" )
			)
			( signal "@baseboard_fab2_lib.baseboard_fab2(sch_1):tp_cpu1_rsvd_test_3"
				( attribute "CDS_PHYS_NET_NAME" "TP_CPU1_RSVD_TEST_3"
					( Origin gPackager )
				)
				( objectStatus "TP_CPU1_RSVD_TEST_3" )
			)
			( signal "@baseboard_fab2_lib.baseboard_fab2(sch_1):tp_cpu1_rsvd_test_4"
				( attribute "CDS_PHYS_NET_NAME" "TP_CPU1_RSVD_TEST_4"
					( Origin gPackager )
				)
				( objectStatus "TP_CPU1_RSVD_TEST_4" )
			)
			( signal "@baseboard_fab2_lib.baseboard_fab2(sch_1):tp_cpu1_rsvd_test_5"
				( attribute "CDS_PHYS_NET_NAME" "TP_CPU1_RSVD_TEST_5"
					( Origin gPackager )
				)
				( objectStatus "TP_CPU1_RSVD_TEST_5" )
			)
			( signal "@baseboard_fab2_lib.baseboard_fab2(sch_1):vsense_p1v8mcp_cpu1_skt_vrtn"
				( attribute "CDS_PHYS_NET_NAME" "VSENSE_P1V8MCP_CPU1_SKT_VRTN"
					( Origin gPackager )
				)
				( objectStatus "VSENSE_P1V8MCP_CPU1_SKT_VRTN" )
			)
			( signal "@baseboard_fab2_lib.baseboard_fab2(sch_1):vsense_p1v8mcp_cpu1_skt_vsen"
				( attribute "CDS_PHYS_NET_NAME" "VSENSE_P1V8MCP_CPU1_SKT_VSEN"
					( Origin gPackager )
				)
				( objectStatus "VSENSE_P1V8MCP_CPU1_SKT_VSEN" )
			)
			( signal "@baseboard_fab2_lib.baseboard_fab2(sch_1):m_g_act_n"
				( attribute "CDS_PHYS_NET_NAME" "M_G_ACT_N"
					( Origin gPackager )
				)
				( objectStatus "M_G_ACT_N" )
			)
			( signal "@baseboard_fab2_lib.baseboard_fab2(sch_1):m_g_alert_n"
				( attribute "CDS_PHYS_NET_NAME" "M_G_ALERT_N"
					( Origin gPackager )
				)
				( objectStatus "M_G_ALERT_N" )
			)
			( signal "@baseboard_fab2_lib.baseboard_fab2(sch_1):m_g_ba(0)"
				( attribute "CDS_PHYS_NET_NAME" "M_G_BA<0>"
					( Origin gPackager )
				)
				( attribute "PNN" "M_G_BA<0>"
					( Origin gPackager )
				)
				( objectStatus "M_G_BA<0>" )
			)
			( signal "@baseboard_fab2_lib.baseboard_fab2(sch_1):m_g_ba(1)"
				( attribute "CDS_PHYS_NET_NAME" "M_G_BA<1>"
					( Origin gPackager )
				)
				( attribute "PNN" "M_G_BA<1>"
					( Origin gPackager )
				)
				( objectStatus "M_G_BA<1>" )
			)
			( signal "@baseboard_fab2_lib.baseboard_fab2(sch_1):m_g_bg(0)"
				( attribute "CDS_PHYS_NET_NAME" "M_G_BG<0>"
					( Origin gPackager )
				)
				( attribute "PNN" "M_G_BG<0>"
					( Origin gPackager )
				)
				( objectStatus "M_G_BG<0>" )
			)
			( signal "@baseboard_fab2_lib.baseboard_fab2(sch_1):m_g_bg(1)"
				( attribute "CDS_PHYS_NET_NAME" "M_G_BG<1>"
					( Origin gPackager )
				)
				( attribute "PNN" "M_G_BG<1>"
					( Origin gPackager )
				)
				( objectStatus "M_G_BG<1>" )
			)
			( signal "@baseboard_fab2_lib.baseboard_fab2(sch_1):m_g_c(2)"
				( attribute "CDS_PHYS_NET_NAME" "M_G_C<2>"
					( Origin gPackager )
				)
				( attribute "PNN" "M_G_C<2>"
					( Origin gPackager )
				)
				( objectStatus "M_G_C<2>" )
			)
			( signal "@baseboard_fab2_lib.baseboard_fab2(sch_1):m_g_cke(0)"
				( attribute "CDS_PHYS_NET_NAME" "M_G_CKE<0>"
					( Origin gPackager )
				)
				( attribute "PNN" "M_G_CKE<0>"
					( Origin gPackager )
				)
				( objectStatus "M_G_CKE<0>" )
			)
			( signal "@baseboard_fab2_lib.baseboard_fab2(sch_1):m_g_cke(1)"
				( attribute "CDS_PHYS_NET_NAME" "M_G_CKE<1>"
					( Origin gPackager )
				)
				( attribute "PNN" "M_G_CKE<1>"
					( Origin gPackager )
				)
				( objectStatus "M_G_CKE<1>" )
			)
			( signal "@baseboard_fab2_lib.baseboard_fab2(sch_1):m_g_cke(2)"
				( attribute "CDS_PHYS_NET_NAME" "M_G_CKE<2>"
					( Origin gPackager )
				)
				( attribute "PNN" "M_G_CKE<2>"
					( Origin gPackager )
				)
				( objectStatus "M_G_CKE<2>" )
			)
			( signal "@baseboard_fab2_lib.baseboard_fab2(sch_1):m_g_cke(3)"
				( attribute "CDS_PHYS_NET_NAME" "M_G_CKE<3>"
					( Origin gPackager )
				)
				( attribute "PNN" "M_G_CKE<3>"
					( Origin gPackager )
				)
				( objectStatus "M_G_CKE<3>" )
			)
			( signal "@baseboard_fab2_lib.baseboard_fab2(sch_1):m_g_clk_dn(0)"
				( attribute "CDS_PHYS_NET_NAME" "M_G_CLK_DN<0>"
					( Origin gPackager )
				)
				( attribute "PNN" "M_G_CLK_DN<0>"
					( Origin gPackager )
				)
				( objectStatus "M_G_CLK_DN<0>" )
			)
			( signal "@baseboard_fab2_lib.baseboard_fab2(sch_1):m_g_clk_dn(1)"
				( attribute "CDS_PHYS_NET_NAME" "M_G_CLK_DN<1>"
					( Origin gPackager )
				)
				( attribute "PNN" "M_G_CLK_DN<1>"
					( Origin gPackager )
				)
				( objectStatus "M_G_CLK_DN<1>" )
			)
			( signal "@baseboard_fab2_lib.baseboard_fab2(sch_1):m_g_clk_dn(2)"
				( attribute "CDS_PHYS_NET_NAME" "M_G_CLK_DN<2>"
					( Origin gPackager )
				)
				( attribute "PNN" "M_G_CLK_DN<2>"
					( Origin gPackager )
				)
				( objectStatus "M_G_CLK_DN<2>" )
			)
			( signal "@baseboard_fab2_lib.baseboard_fab2(sch_1):m_g_clk_dn(3)"
				( attribute "CDS_PHYS_NET_NAME" "M_G_CLK_DN<3>"
					( Origin gPackager )
				)
				( attribute "PNN" "M_G_CLK_DN<3>"
					( Origin gPackager )
				)
				( objectStatus "M_G_CLK_DN<3>" )
			)
			( signal "@baseboard_fab2_lib.baseboard_fab2(sch_1):m_g_clk_dp(0)"
				( attribute "CDS_PHYS_NET_NAME" "M_G_CLK_DP<0>"
					( Origin gPackager )
				)
				( attribute "PNN" "M_G_CLK_DP<0>"
					( Origin gPackager )
				)
				( objectStatus "M_G_CLK_DP<0>" )
			)
			( signal "@baseboard_fab2_lib.baseboard_fab2(sch_1):m_g_clk_dp(1)"
				( attribute "CDS_PHYS_NET_NAME" "M_G_CLK_DP<1>"
					( Origin gPackager )
				)
				( attribute "PNN" "M_G_CLK_DP<1>"
					( Origin gPackager )
				)
				( objectStatus "M_G_CLK_DP<1>" )
			)
			( signal "@baseboard_fab2_lib.baseboard_fab2(sch_1):m_g_clk_dp(2)"
				( attribute "CDS_PHYS_NET_NAME" "M_G_CLK_DP<2>"
					( Origin gPackager )
				)
				( attribute "PNN" "M_G_CLK_DP<2>"
					( Origin gPackager )
				)
				( objectStatus "M_G_CLK_DP<2>" )
			)
			( signal "@baseboard_fab2_lib.baseboard_fab2(sch_1):m_g_clk_dp(3)"
				( attribute "CDS_PHYS_NET_NAME" "M_G_CLK_DP<3>"
					( Origin gPackager )
				)
				( attribute "PNN" "M_G_CLK_DP<3>"
					( Origin gPackager )
				)
				( objectStatus "M_G_CLK_DP<3>" )
			)
			( signal "@baseboard_fab2_lib.baseboard_fab2(sch_1):m_g_cs_n(0)"
				( attribute "CDS_PHYS_NET_NAME" "M_G_CS_N<0>"
					( Origin gPackager )
				)
				( attribute "PNN" "M_G_CS_N<0>"
					( Origin gPackager )
				)
				( objectStatus "M_G_CS_N<0>" )
			)
			( signal "@baseboard_fab2_lib.baseboard_fab2(sch_1):m_g_cs_n(1)"
				( attribute "CDS_PHYS_NET_NAME" "M_G_CS_N<1>"
					( Origin gPackager )
				)
				( attribute "PNN" "M_G_CS_N<1>"
					( Origin gPackager )
				)
				( objectStatus "M_G_CS_N<1>" )
			)
			( signal "@baseboard_fab2_lib.baseboard_fab2(sch_1):m_g_cs_n(2)"
				( attribute "CDS_PHYS_NET_NAME" "M_G_CS_N<2>"
					( Origin gPackager )
				)
				( attribute "PNN" "M_G_CS_N<2>"
					( Origin gPackager )
				)
				( objectStatus "M_G_CS_N<2>" )
			)
			( signal "@baseboard_fab2_lib.baseboard_fab2(sch_1):m_g_cs_n(3)"
				( attribute "CDS_PHYS_NET_NAME" "M_G_CS_N<3>"
					( Origin gPackager )
				)
				( attribute "PNN" "M_G_CS_N<3>"
					( Origin gPackager )
				)
				( objectStatus "M_G_CS_N<3>" )
			)
			( signal "@baseboard_fab2_lib.baseboard_fab2(sch_1):m_g_cs_n(4)"
				( attribute "CDS_PHYS_NET_NAME" "M_G_CS_N<4>"
					( Origin gPackager )
				)
				( attribute "PNN" "M_G_CS_N<4>"
					( Origin gPackager )
				)
				( objectStatus "M_G_CS_N<4>" )
			)
			( signal "@baseboard_fab2_lib.baseboard_fab2(sch_1):m_g_cs_n(5)"
				( attribute "CDS_PHYS_NET_NAME" "M_G_CS_N<5>"
					( Origin gPackager )
				)
				( attribute "PNN" "M_G_CS_N<5>"
					( Origin gPackager )
				)
				( objectStatus "M_G_CS_N<5>" )
			)
			( signal "@baseboard_fab2_lib.baseboard_fab2(sch_1):m_g_cs_n(6)"
				( attribute "CDS_PHYS_NET_NAME" "M_G_CS_N<6>"
					( Origin gPackager )
				)
				( attribute "PNN" "M_G_CS_N<6>"
					( Origin gPackager )
				)
				( objectStatus "M_G_CS_N<6>" )
			)
			( signal "@baseboard_fab2_lib.baseboard_fab2(sch_1):m_g_cs_n(7)"
				( attribute "CDS_PHYS_NET_NAME" "M_G_CS_N<7>"
					( Origin gPackager )
				)
				( attribute "PNN" "M_G_CS_N<7>"
					( Origin gPackager )
				)
				( objectStatus "M_G_CS_N<7>" )
			)
			( signal "@baseboard_fab2_lib.baseboard_fab2(sch_1):m_g_dq(0)"
				( attribute "CDS_PHYS_NET_NAME" "M_G_DQ<0>"
					( Origin gPackager )
				)
				( attribute "PNN" "M_G_DQ<0>"
					( Origin gPackager )
				)
				( objectStatus "M_G_DQ<0>" )
			)
			( signal "@baseboard_fab2_lib.baseboard_fab2(sch_1):m_g_dq(1)"
				( attribute "CDS_PHYS_NET_NAME" "M_G_DQ<1>"
					( Origin gPackager )
				)
				( attribute "PNN" "M_G_DQ<1>"
					( Origin gPackager )
				)
				( objectStatus "M_G_DQ<1>" )
			)
			( signal "@baseboard_fab2_lib.baseboard_fab2(sch_1):m_g_dq(2)"
				( attribute "CDS_PHYS_NET_NAME" "M_G_DQ<2>"
					( Origin gPackager )
				)
				( attribute "PNN" "M_G_DQ<2>"
					( Origin gPackager )
				)
				( objectStatus "M_G_DQ<2>" )
			)
			( signal "@baseboard_fab2_lib.baseboard_fab2(sch_1):m_g_dq(3)"
				( attribute "CDS_PHYS_NET_NAME" "M_G_DQ<3>"
					( Origin gPackager )
				)
				( attribute "PNN" "M_G_DQ<3>"
					( Origin gPackager )
				)
				( objectStatus "M_G_DQ<3>" )
			)
			( signal "@baseboard_fab2_lib.baseboard_fab2(sch_1):m_g_dq(4)"
				( attribute "CDS_PHYS_NET_NAME" "M_G_DQ<4>"
					( Origin gPackager )
				)
				( attribute "PNN" "M_G_DQ<4>"
					( Origin gPackager )
				)
				( objectStatus "M_G_DQ<4>" )
			)
			( signal "@baseboard_fab2_lib.baseboard_fab2(sch_1):m_g_dq(5)"
				( attribute "CDS_PHYS_NET_NAME" "M_G_DQ<5>"
					( Origin gPackager )
				)
				( attribute "PNN" "M_G_DQ<5>"
					( Origin gPackager )
				)
				( objectStatus "M_G_DQ<5>" )
			)
			( signal "@baseboard_fab2_lib.baseboard_fab2(sch_1):m_g_dq(6)"
				( attribute "CDS_PHYS_NET_NAME" "M_G_DQ<6>"
					( Origin gPackager )
				)
				( attribute "PNN" "M_G_DQ<6>"
					( Origin gPackager )
				)
				( objectStatus "M_G_DQ<6>" )
			)
			( signal "@baseboard_fab2_lib.baseboard_fab2(sch_1):m_g_dq(7)"
				( attribute "CDS_PHYS_NET_NAME" "M_G_DQ<7>"
					( Origin gPackager )
				)
				( attribute "PNN" "M_G_DQ<7>"
					( Origin gPackager )
				)
				( objectStatus "M_G_DQ<7>" )
			)
			( signal "@baseboard_fab2_lib.baseboard_fab2(sch_1):m_g_dq(8)"
				( attribute "CDS_PHYS_NET_NAME" "M_G_DQ<8>"
					( Origin gPackager )
				)
				( attribute "PNN" "M_G_DQ<8>"
					( Origin gPackager )
				)
				( objectStatus "M_G_DQ<8>" )
			)
			( signal "@baseboard_fab2_lib.baseboard_fab2(sch_1):m_g_dq(9)"
				( attribute "CDS_PHYS_NET_NAME" "M_G_DQ<9>"
					( Origin gPackager )
				)
				( attribute "PNN" "M_G_DQ<9>"
					( Origin gPackager )
				)
				( objectStatus "M_G_DQ<9>" )
			)
			( signal "@baseboard_fab2_lib.baseboard_fab2(sch_1):m_g_dq(10)"
				( attribute "CDS_PHYS_NET_NAME" "M_G_DQ<10>"
					( Origin gPackager )
				)
				( attribute "PNN" "M_G_DQ<10>"
					( Origin gPackager )
				)
				( objectStatus "M_G_DQ<10>" )
			)
			( signal "@baseboard_fab2_lib.baseboard_fab2(sch_1):m_g_dq(11)"
				( attribute "CDS_PHYS_NET_NAME" "M_G_DQ<11>"
					( Origin gPackager )
				)
				( attribute "PNN" "M_G_DQ<11>"
					( Origin gPackager )
				)
				( objectStatus "M_G_DQ<11>" )
			)
			( signal "@baseboard_fab2_lib.baseboard_fab2(sch_1):m_g_dq(12)"
				( attribute "CDS_PHYS_NET_NAME" "M_G_DQ<12>"
					( Origin gPackager )
				)
				( attribute "PNN" "M_G_DQ<12>"
					( Origin gPackager )
				)
				( objectStatus "M_G_DQ<12>" )
			)
			( signal "@baseboard_fab2_lib.baseboard_fab2(sch_1):m_g_dq(13)"
				( attribute "CDS_PHYS_NET_NAME" "M_G_DQ<13>"
					( Origin gPackager )
				)
				( attribute "PNN" "M_G_DQ<13>"
					( Origin gPackager )
				)
				( objectStatus "M_G_DQ<13>" )
			)
			( signal "@baseboard_fab2_lib.baseboard_fab2(sch_1):m_g_dq(14)"
				( attribute "CDS_PHYS_NET_NAME" "M_G_DQ<14>"
					( Origin gPackager )
				)
				( attribute "PNN" "M_G_DQ<14>"
					( Origin gPackager )
				)
				( objectStatus "M_G_DQ<14>" )
			)
			( signal "@baseboard_fab2_lib.baseboard_fab2(sch_1):m_g_dq(15)"
				( attribute "CDS_PHYS_NET_NAME" "M_G_DQ<15>"
					( Origin gPackager )
				)
				( attribute "PNN" "M_G_DQ<15>"
					( Origin gPackager )
				)
				( objectStatus "M_G_DQ<15>" )
			)
			( signal "@baseboard_fab2_lib.baseboard_fab2(sch_1):m_g_dq(16)"
				( attribute "CDS_PHYS_NET_NAME" "M_G_DQ<16>"
					( Origin gPackager )
				)
				( attribute "PNN" "M_G_DQ<16>"
					( Origin gPackager )
				)
				( objectStatus "M_G_DQ<16>" )
			)
			( signal "@baseboard_fab2_lib.baseboard_fab2(sch_1):m_g_dq(17)"
				( attribute "CDS_PHYS_NET_NAME" "M_G_DQ<17>"
					( Origin gPackager )
				)
				( attribute "PNN" "M_G_DQ<17>"
					( Origin gPackager )
				)
				( objectStatus "M_G_DQ<17>" )
			)
			( signal "@baseboard_fab2_lib.baseboard_fab2(sch_1):m_g_dq(18)"
				( attribute "CDS_PHYS_NET_NAME" "M_G_DQ<18>"
					( Origin gPackager )
				)
				( attribute "PNN" "M_G_DQ<18>"
					( Origin gPackager )
				)
				( objectStatus "M_G_DQ<18>" )
			)
			( signal "@baseboard_fab2_lib.baseboard_fab2(sch_1):m_g_dq(19)"
				( attribute "CDS_PHYS_NET_NAME" "M_G_DQ<19>"
					( Origin gPackager )
				)
				( attribute "PNN" "M_G_DQ<19>"
					( Origin gPackager )
				)
				( objectStatus "M_G_DQ<19>" )
			)
			( signal "@baseboard_fab2_lib.baseboard_fab2(sch_1):m_g_dq(20)"
				( attribute "CDS_PHYS_NET_NAME" "M_G_DQ<20>"
					( Origin gPackager )
				)
				( attribute "PNN" "M_G_DQ<20>"
					( Origin gPackager )
				)
				( objectStatus "M_G_DQ<20>" )
			)
			( signal "@baseboard_fab2_lib.baseboard_fab2(sch_1):m_g_dq(21)"
				( attribute "CDS_PHYS_NET_NAME" "M_G_DQ<21>"
					( Origin gPackager )
				)
				( attribute "PNN" "M_G_DQ<21>"
					( Origin gPackager )
				)
				( objectStatus "M_G_DQ<21>" )
			)
			( signal "@baseboard_fab2_lib.baseboard_fab2(sch_1):m_g_dq(22)"
				( attribute "CDS_PHYS_NET_NAME" "M_G_DQ<22>"
					( Origin gPackager )
				)
				( attribute "PNN" "M_G_DQ<22>"
					( Origin gPackager )
				)
				( objectStatus "M_G_DQ<22>" )
			)
			( signal "@baseboard_fab2_lib.baseboard_fab2(sch_1):m_g_dq(23)"
				( attribute "CDS_PHYS_NET_NAME" "M_G_DQ<23>"
					( Origin gPackager )
				)
				( attribute "PNN" "M_G_DQ<23>"
					( Origin gPackager )
				)
				( objectStatus "M_G_DQ<23>" )
			)
			( signal "@baseboard_fab2_lib.baseboard_fab2(sch_1):m_g_dq(24)"
				( attribute "CDS_PHYS_NET_NAME" "M_G_DQ<24>"
					( Origin gPackager )
				)
				( attribute "PNN" "M_G_DQ<24>"
					( Origin gPackager )
				)
				( objectStatus "M_G_DQ<24>" )
			)
			( signal "@baseboard_fab2_lib.baseboard_fab2(sch_1):m_g_dq(25)"
				( attribute "CDS_PHYS_NET_NAME" "M_G_DQ<25>"
					( Origin gPackager )
				)
				( attribute "PNN" "M_G_DQ<25>"
					( Origin gPackager )
				)
				( objectStatus "M_G_DQ<25>" )
			)
			( signal "@baseboard_fab2_lib.baseboard_fab2(sch_1):m_g_dq(26)"
				( attribute "CDS_PHYS_NET_NAME" "M_G_DQ<26>"
					( Origin gPackager )
				)
				( attribute "PNN" "M_G_DQ<26>"
					( Origin gPackager )
				)
				( objectStatus "M_G_DQ<26>" )
			)
			( signal "@baseboard_fab2_lib.baseboard_fab2(sch_1):m_g_dq(27)"
				( attribute "CDS_PHYS_NET_NAME" "M_G_DQ<27>"
					( Origin gPackager )
				)
				( attribute "PNN" "M_G_DQ<27>"
					( Origin gPackager )
				)
				( objectStatus "M_G_DQ<27>" )
			)
			( signal "@baseboard_fab2_lib.baseboard_fab2(sch_1):m_g_dq(28)"
				( attribute "CDS_PHYS_NET_NAME" "M_G_DQ<28>"
					( Origin gPackager )
				)
				( attribute "PNN" "M_G_DQ<28>"
					( Origin gPackager )
				)
				( objectStatus "M_G_DQ<28>" )
			)
			( signal "@baseboard_fab2_lib.baseboard_fab2(sch_1):m_g_dq(29)"
				( attribute "CDS_PHYS_NET_NAME" "M_G_DQ<29>"
					( Origin gPackager )
				)
				( attribute "PNN" "M_G_DQ<29>"
					( Origin gPackager )
				)
				( objectStatus "M_G_DQ<29>" )
			)
			( signal "@baseboard_fab2_lib.baseboard_fab2(sch_1):m_g_dq(30)"
				( attribute "CDS_PHYS_NET_NAME" "M_G_DQ<30>"
					( Origin gPackager )
				)
				( attribute "PNN" "M_G_DQ<30>"
					( Origin gPackager )
				)
				( objectStatus "M_G_DQ<30>" )
			)
			( signal "@baseboard_fab2_lib.baseboard_fab2(sch_1):m_g_dq(31)"
				( attribute "CDS_PHYS_NET_NAME" "M_G_DQ<31>"
					( Origin gPackager )
				)
				( attribute "PNN" "M_G_DQ<31>"
					( Origin gPackager )
				)
				( objectStatus "M_G_DQ<31>" )
			)
			( signal "@baseboard_fab2_lib.baseboard_fab2(sch_1):m_g_dq(32)"
				( attribute "CDS_PHYS_NET_NAME" "M_G_DQ<32>"
					( Origin gPackager )
				)
				( attribute "PNN" "M_G_DQ<32>"
					( Origin gPackager )
				)
				( objectStatus "M_G_DQ<32>" )
			)
			( signal "@baseboard_fab2_lib.baseboard_fab2(sch_1):m_g_dq(33)"
				( attribute "CDS_PHYS_NET_NAME" "M_G_DQ<33>"
					( Origin gPackager )
				)
				( attribute "PNN" "M_G_DQ<33>"
					( Origin gPackager )
				)
				( objectStatus "M_G_DQ<33>" )
			)
			( signal "@baseboard_fab2_lib.baseboard_fab2(sch_1):m_g_dq(34)"
				( attribute "CDS_PHYS_NET_NAME" "M_G_DQ<34>"
					( Origin gPackager )
				)
				( attribute "PNN" "M_G_DQ<34>"
					( Origin gPackager )
				)
				( objectStatus "M_G_DQ<34>" )
			)
			( signal "@baseboard_fab2_lib.baseboard_fab2(sch_1):m_g_dq(35)"
				( attribute "CDS_PHYS_NET_NAME" "M_G_DQ<35>"
					( Origin gPackager )
				)
				( attribute "PNN" "M_G_DQ<35>"
					( Origin gPackager )
				)
				( objectStatus "M_G_DQ<35>" )
			)
			( signal "@baseboard_fab2_lib.baseboard_fab2(sch_1):m_g_dq(36)"
				( attribute "CDS_PHYS_NET_NAME" "M_G_DQ<36>"
					( Origin gPackager )
				)
				( attribute "PNN" "M_G_DQ<36>"
					( Origin gPackager )
				)
				( objectStatus "M_G_DQ<36>" )
			)
			( signal "@baseboard_fab2_lib.baseboard_fab2(sch_1):m_g_dq(37)"
				( attribute "CDS_PHYS_NET_NAME" "M_G_DQ<37>"
					( Origin gPackager )
				)
				( attribute "PNN" "M_G_DQ<37>"
					( Origin gPackager )
				)
				( objectStatus "M_G_DQ<37>" )
			)
			( signal "@baseboard_fab2_lib.baseboard_fab2(sch_1):m_g_dq(38)"
				( attribute "CDS_PHYS_NET_NAME" "M_G_DQ<38>"
					( Origin gPackager )
				)
				( attribute "PNN" "M_G_DQ<38>"
					( Origin gPackager )
				)
				( objectStatus "M_G_DQ<38>" )
			)
			( signal "@baseboard_fab2_lib.baseboard_fab2(sch_1):m_g_dq(39)"
				( attribute "CDS_PHYS_NET_NAME" "M_G_DQ<39>"
					( Origin gPackager )
				)
				( attribute "PNN" "M_G_DQ<39>"
					( Origin gPackager )
				)
				( objectStatus "M_G_DQ<39>" )
			)
			( signal "@baseboard_fab2_lib.baseboard_fab2(sch_1):m_g_dq(40)"
				( attribute "CDS_PHYS_NET_NAME" "M_G_DQ<40>"
					( Origin gPackager )
				)
				( attribute "PNN" "M_G_DQ<40>"
					( Origin gPackager )
				)
				( objectStatus "M_G_DQ<40>" )
			)
			( signal "@baseboard_fab2_lib.baseboard_fab2(sch_1):m_g_dq(41)"
				( attribute "CDS_PHYS_NET_NAME" "M_G_DQ<41>"
					( Origin gPackager )
				)
				( attribute "PNN" "M_G_DQ<41>"
					( Origin gPackager )
				)
				( objectStatus "M_G_DQ<41>" )
			)
			( signal "@baseboard_fab2_lib.baseboard_fab2(sch_1):m_g_dq(42)"
				( attribute "CDS_PHYS_NET_NAME" "M_G_DQ<42>"
					( Origin gPackager )
				)
				( attribute "PNN" "M_G_DQ<42>"
					( Origin gPackager )
				)
				( objectStatus "M_G_DQ<42>" )
			)
			( signal "@baseboard_fab2_lib.baseboard_fab2(sch_1):m_g_dq(43)"
				( attribute "CDS_PHYS_NET_NAME" "M_G_DQ<43>"
					( Origin gPackager )
				)
				( attribute "PNN" "M_G_DQ<43>"
					( Origin gPackager )
				)
				( objectStatus "M_G_DQ<43>" )
			)
			( signal "@baseboard_fab2_lib.baseboard_fab2(sch_1):m_g_dq(44)"
				( attribute "CDS_PHYS_NET_NAME" "M_G_DQ<44>"
					( Origin gPackager )
				)
				( attribute "PNN" "M_G_DQ<44>"
					( Origin gPackager )
				)
				( objectStatus "M_G_DQ<44>" )
			)
			( signal "@baseboard_fab2_lib.baseboard_fab2(sch_1):m_g_dq(45)"
				( attribute "CDS_PHYS_NET_NAME" "M_G_DQ<45>"
					( Origin gPackager )
				)
				( attribute "PNN" "M_G_DQ<45>"
					( Origin gPackager )
				)
				( objectStatus "M_G_DQ<45>" )
			)
			( signal "@baseboard_fab2_lib.baseboard_fab2(sch_1):m_g_dq(46)"
				( attribute "CDS_PHYS_NET_NAME" "M_G_DQ<46>"
					( Origin gPackager )
				)
				( attribute "PNN" "M_G_DQ<46>"
					( Origin gPackager )
				)
				( objectStatus "M_G_DQ<46>" )
			)
			( signal "@baseboard_fab2_lib.baseboard_fab2(sch_1):m_g_dq(47)"
				( attribute "CDS_PHYS_NET_NAME" "M_G_DQ<47>"
					( Origin gPackager )
				)
				( attribute "PNN" "M_G_DQ<47>"
					( Origin gPackager )
				)
				( objectStatus "M_G_DQ<47>" )
			)
			( signal "@baseboard_fab2_lib.baseboard_fab2(sch_1):m_g_dq(48)"
				( attribute "CDS_PHYS_NET_NAME" "M_G_DQ<48>"
					( Origin gPackager )
				)
				( attribute "PNN" "M_G_DQ<48>"
					( Origin gPackager )
				)
				( objectStatus "M_G_DQ<48>" )
			)
			( signal "@baseboard_fab2_lib.baseboard_fab2(sch_1):m_g_dq(49)"
				( attribute "CDS_PHYS_NET_NAME" "M_G_DQ<49>"
					( Origin gPackager )
				)
				( attribute "PNN" "M_G_DQ<49>"
					( Origin gPackager )
				)
				( objectStatus "M_G_DQ<49>" )
			)
			( signal "@baseboard_fab2_lib.baseboard_fab2(sch_1):m_g_dq(50)"
				( attribute "CDS_PHYS_NET_NAME" "M_G_DQ<50>"
					( Origin gPackager )
				)
				( attribute "PNN" "M_G_DQ<50>"
					( Origin gPackager )
				)
				( objectStatus "M_G_DQ<50>" )
			)
			( signal "@baseboard_fab2_lib.baseboard_fab2(sch_1):m_g_dq(51)"
				( attribute "CDS_PHYS_NET_NAME" "M_G_DQ<51>"
					( Origin gPackager )
				)
				( attribute "PNN" "M_G_DQ<51>"
					( Origin gPackager )
				)
				( objectStatus "M_G_DQ<51>" )
			)
			( signal "@baseboard_fab2_lib.baseboard_fab2(sch_1):m_g_dq(52)"
				( attribute "CDS_PHYS_NET_NAME" "M_G_DQ<52>"
					( Origin gPackager )
				)
				( attribute "PNN" "M_G_DQ<52>"
					( Origin gPackager )
				)
				( objectStatus "M_G_DQ<52>" )
			)
			( signal "@baseboard_fab2_lib.baseboard_fab2(sch_1):m_g_dq(53)"
				( attribute "CDS_PHYS_NET_NAME" "M_G_DQ<53>"
					( Origin gPackager )
				)
				( attribute "PNN" "M_G_DQ<53>"
					( Origin gPackager )
				)
				( objectStatus "M_G_DQ<53>" )
			)
			( signal "@baseboard_fab2_lib.baseboard_fab2(sch_1):m_g_dq(54)"
				( attribute "CDS_PHYS_NET_NAME" "M_G_DQ<54>"
					( Origin gPackager )
				)
				( attribute "PNN" "M_G_DQ<54>"
					( Origin gPackager )
				)
				( objectStatus "M_G_DQ<54>" )
			)
			( signal "@baseboard_fab2_lib.baseboard_fab2(sch_1):m_g_dq(55)"
				( attribute "CDS_PHYS_NET_NAME" "M_G_DQ<55>"
					( Origin gPackager )
				)
				( attribute "PNN" "M_G_DQ<55>"
					( Origin gPackager )
				)
				( objectStatus "M_G_DQ<55>" )
			)
			( signal "@baseboard_fab2_lib.baseboard_fab2(sch_1):m_g_dq(56)"
				( attribute "CDS_PHYS_NET_NAME" "M_G_DQ<56>"
					( Origin gPackager )
				)
				( attribute "PNN" "M_G_DQ<56>"
					( Origin gPackager )
				)
				( objectStatus "M_G_DQ<56>" )
			)
			( signal "@baseboard_fab2_lib.baseboard_fab2(sch_1):m_g_dq(57)"
				( attribute "CDS_PHYS_NET_NAME" "M_G_DQ<57>"
					( Origin gPackager )
				)
				( attribute "PNN" "M_G_DQ<57>"
					( Origin gPackager )
				)
				( objectStatus "M_G_DQ<57>" )
			)
			( signal "@baseboard_fab2_lib.baseboard_fab2(sch_1):m_g_dq(58)"
				( attribute "CDS_PHYS_NET_NAME" "M_G_DQ<58>"
					( Origin gPackager )
				)
				( attribute "PNN" "M_G_DQ<58>"
					( Origin gPackager )
				)
				( objectStatus "M_G_DQ<58>" )
			)
			( signal "@baseboard_fab2_lib.baseboard_fab2(sch_1):m_g_dq(59)"
				( attribute "CDS_PHYS_NET_NAME" "M_G_DQ<59>"
					( Origin gPackager )
				)
				( attribute "PNN" "M_G_DQ<59>"
					( Origin gPackager )
				)
				( objectStatus "M_G_DQ<59>" )
			)
			( signal "@baseboard_fab2_lib.baseboard_fab2(sch_1):m_g_dq(60)"
				( attribute "CDS_PHYS_NET_NAME" "M_G_DQ<60>"
					( Origin gPackager )
				)
				( attribute "PNN" "M_G_DQ<60>"
					( Origin gPackager )
				)
				( objectStatus "M_G_DQ<60>" )
			)
			( signal "@baseboard_fab2_lib.baseboard_fab2(sch_1):m_g_dq(61)"
				( attribute "CDS_PHYS_NET_NAME" "M_G_DQ<61>"
					( Origin gPackager )
				)
				( attribute "PNN" "M_G_DQ<61>"
					( Origin gPackager )
				)
				( objectStatus "M_G_DQ<61>" )
			)
			( signal "@baseboard_fab2_lib.baseboard_fab2(sch_1):m_g_dq(62)"
				( attribute "CDS_PHYS_NET_NAME" "M_G_DQ<62>"
					( Origin gPackager )
				)
				( attribute "PNN" "M_G_DQ<62>"
					( Origin gPackager )
				)
				( objectStatus "M_G_DQ<62>" )
			)
			( signal "@baseboard_fab2_lib.baseboard_fab2(sch_1):m_g_dq(63)"
				( attribute "CDS_PHYS_NET_NAME" "M_G_DQ<63>"
					( Origin gPackager )
				)
				( attribute "PNN" "M_G_DQ<63>"
					( Origin gPackager )
				)
				( objectStatus "M_G_DQ<63>" )
			)
			( signal "@baseboard_fab2_lib.baseboard_fab2(sch_1):m_g_dqs_dn(0)"
				( attribute "CDS_PHYS_NET_NAME" "M_G_DQS_DN<0>"
					( Origin gPackager )
				)
				( attribute "PNN" "M_G_DQS_DN<0>"
					( Origin gPackager )
				)
				( objectStatus "M_G_DQS_DN<0>" )
			)
			( signal "@baseboard_fab2_lib.baseboard_fab2(sch_1):m_g_dqs_dn(1)"
				( attribute "CDS_PHYS_NET_NAME" "M_G_DQS_DN<1>"
					( Origin gPackager )
				)
				( attribute "PNN" "M_G_DQS_DN<1>"
					( Origin gPackager )
				)
				( objectStatus "M_G_DQS_DN<1>" )
			)
			( signal "@baseboard_fab2_lib.baseboard_fab2(sch_1):m_g_dqs_dn(2)"
				( attribute "CDS_PHYS_NET_NAME" "M_G_DQS_DN<2>"
					( Origin gPackager )
				)
				( attribute "PNN" "M_G_DQS_DN<2>"
					( Origin gPackager )
				)
				( objectStatus "M_G_DQS_DN<2>" )
			)
			( signal "@baseboard_fab2_lib.baseboard_fab2(sch_1):m_g_dqs_dn(3)"
				( attribute "CDS_PHYS_NET_NAME" "M_G_DQS_DN<3>"
					( Origin gPackager )
				)
				( attribute "PNN" "M_G_DQS_DN<3>"
					( Origin gPackager )
				)
				( objectStatus "M_G_DQS_DN<3>" )
			)
			( signal "@baseboard_fab2_lib.baseboard_fab2(sch_1):m_g_dqs_dn(4)"
				( attribute "CDS_PHYS_NET_NAME" "M_G_DQS_DN<4>"
					( Origin gPackager )
				)
				( attribute "PNN" "M_G_DQS_DN<4>"
					( Origin gPackager )
				)
				( objectStatus "M_G_DQS_DN<4>" )
			)
			( signal "@baseboard_fab2_lib.baseboard_fab2(sch_1):m_g_dqs_dn(5)"
				( attribute "CDS_PHYS_NET_NAME" "M_G_DQS_DN<5>"
					( Origin gPackager )
				)
				( attribute "PNN" "M_G_DQS_DN<5>"
					( Origin gPackager )
				)
				( objectStatus "M_G_DQS_DN<5>" )
			)
			( signal "@baseboard_fab2_lib.baseboard_fab2(sch_1):m_g_dqs_dn(6)"
				( attribute "CDS_PHYS_NET_NAME" "M_G_DQS_DN<6>"
					( Origin gPackager )
				)
				( attribute "PNN" "M_G_DQS_DN<6>"
					( Origin gPackager )
				)
				( objectStatus "M_G_DQS_DN<6>" )
			)
			( signal "@baseboard_fab2_lib.baseboard_fab2(sch_1):m_g_dqs_dn(7)"
				( attribute "CDS_PHYS_NET_NAME" "M_G_DQS_DN<7>"
					( Origin gPackager )
				)
				( attribute "PNN" "M_G_DQS_DN<7>"
					( Origin gPackager )
				)
				( objectStatus "M_G_DQS_DN<7>" )
			)
			( signal "@baseboard_fab2_lib.baseboard_fab2(sch_1):m_g_dqs_dn(8)"
				( attribute "CDS_PHYS_NET_NAME" "M_G_DQS_DN<8>"
					( Origin gPackager )
				)
				( attribute "PNN" "M_G_DQS_DN<8>"
					( Origin gPackager )
				)
				( objectStatus "M_G_DQS_DN<8>" )
			)
			( signal "@baseboard_fab2_lib.baseboard_fab2(sch_1):m_g_dqs_dn(9)"
				( attribute "CDS_PHYS_NET_NAME" "M_G_DQS_DN<9>"
					( Origin gPackager )
				)
				( attribute "PNN" "M_G_DQS_DN<9>"
					( Origin gPackager )
				)
				( objectStatus "M_G_DQS_DN<9>" )
			)
			( signal "@baseboard_fab2_lib.baseboard_fab2(sch_1):m_g_dqs_dn(10)"
				( attribute "CDS_PHYS_NET_NAME" "M_G_DQS_DN<10>"
					( Origin gPackager )
				)
				( attribute "PNN" "M_G_DQS_DN<10>"
					( Origin gPackager )
				)
				( objectStatus "M_G_DQS_DN<10>" )
			)
			( signal "@baseboard_fab2_lib.baseboard_fab2(sch_1):m_g_dqs_dn(11)"
				( attribute "CDS_PHYS_NET_NAME" "M_G_DQS_DN<11>"
					( Origin gPackager )
				)
				( attribute "PNN" "M_G_DQS_DN<11>"
					( Origin gPackager )
				)
				( objectStatus "M_G_DQS_DN<11>" )
			)
			( signal "@baseboard_fab2_lib.baseboard_fab2(sch_1):m_g_dqs_dn(12)"
				( attribute "CDS_PHYS_NET_NAME" "M_G_DQS_DN<12>"
					( Origin gPackager )
				)
				( attribute "PNN" "M_G_DQS_DN<12>"
					( Origin gPackager )
				)
				( objectStatus "M_G_DQS_DN<12>" )
			)
			( signal "@baseboard_fab2_lib.baseboard_fab2(sch_1):m_g_dqs_dn(13)"
				( attribute "CDS_PHYS_NET_NAME" "M_G_DQS_DN<13>"
					( Origin gPackager )
				)
				( attribute "PNN" "M_G_DQS_DN<13>"
					( Origin gPackager )
				)
				( objectStatus "M_G_DQS_DN<13>" )
			)
			( signal "@baseboard_fab2_lib.baseboard_fab2(sch_1):m_g_dqs_dn(14)"
				( attribute "CDS_PHYS_NET_NAME" "M_G_DQS_DN<14>"
					( Origin gPackager )
				)
				( attribute "PNN" "M_G_DQS_DN<14>"
					( Origin gPackager )
				)
				( objectStatus "M_G_DQS_DN<14>" )
			)
			( signal "@baseboard_fab2_lib.baseboard_fab2(sch_1):m_g_dqs_dn(15)"
				( attribute "CDS_PHYS_NET_NAME" "M_G_DQS_DN<15>"
					( Origin gPackager )
				)
				( attribute "PNN" "M_G_DQS_DN<15>"
					( Origin gPackager )
				)
				( objectStatus "M_G_DQS_DN<15>" )
			)
			( signal "@baseboard_fab2_lib.baseboard_fab2(sch_1):m_g_dqs_dn(16)"
				( attribute "CDS_PHYS_NET_NAME" "M_G_DQS_DN<16>"
					( Origin gPackager )
				)
				( attribute "PNN" "M_G_DQS_DN<16>"
					( Origin gPackager )
				)
				( objectStatus "M_G_DQS_DN<16>" )
			)
			( signal "@baseboard_fab2_lib.baseboard_fab2(sch_1):m_g_dqs_dn(17)"
				( attribute "CDS_PHYS_NET_NAME" "M_G_DQS_DN<17>"
					( Origin gPackager )
				)
				( attribute "PNN" "M_G_DQS_DN<17>"
					( Origin gPackager )
				)
				( objectStatus "M_G_DQS_DN<17>" )
			)
			( signal "@baseboard_fab2_lib.baseboard_fab2(sch_1):m_g_dqs_dp(0)"
				( attribute "CDS_PHYS_NET_NAME" "M_G_DQS_DP<0>"
					( Origin gPackager )
				)
				( attribute "PNN" "M_G_DQS_DP<0>"
					( Origin gPackager )
				)
				( objectStatus "M_G_DQS_DP<0>" )
			)
			( signal "@baseboard_fab2_lib.baseboard_fab2(sch_1):m_g_dqs_dp(1)"
				( attribute "CDS_PHYS_NET_NAME" "M_G_DQS_DP<1>"
					( Origin gPackager )
				)
				( attribute "PNN" "M_G_DQS_DP<1>"
					( Origin gPackager )
				)
				( objectStatus "M_G_DQS_DP<1>" )
			)
			( signal "@baseboard_fab2_lib.baseboard_fab2(sch_1):m_g_dqs_dp(2)"
				( attribute "CDS_PHYS_NET_NAME" "M_G_DQS_DP<2>"
					( Origin gPackager )
				)
				( attribute "PNN" "M_G_DQS_DP<2>"
					( Origin gPackager )
				)
				( objectStatus "M_G_DQS_DP<2>" )
			)
			( signal "@baseboard_fab2_lib.baseboard_fab2(sch_1):m_g_dqs_dp(3)"
				( attribute "CDS_PHYS_NET_NAME" "M_G_DQS_DP<3>"
					( Origin gPackager )
				)
				( attribute "PNN" "M_G_DQS_DP<3>"
					( Origin gPackager )
				)
				( objectStatus "M_G_DQS_DP<3>" )
			)
			( signal "@baseboard_fab2_lib.baseboard_fab2(sch_1):m_g_dqs_dp(4)"
				( attribute "CDS_PHYS_NET_NAME" "M_G_DQS_DP<4>"
					( Origin gPackager )
				)
				( attribute "PNN" "M_G_DQS_DP<4>"
					( Origin gPackager )
				)
				( objectStatus "M_G_DQS_DP<4>" )
			)
			( signal "@baseboard_fab2_lib.baseboard_fab2(sch_1):m_g_dqs_dp(5)"
				( attribute "CDS_PHYS_NET_NAME" "M_G_DQS_DP<5>"
					( Origin gPackager )
				)
				( attribute "PNN" "M_G_DQS_DP<5>"
					( Origin gPackager )
				)
				( objectStatus "M_G_DQS_DP<5>" )
			)
			( signal "@baseboard_fab2_lib.baseboard_fab2(sch_1):m_g_dqs_dp(6)"
				( attribute "CDS_PHYS_NET_NAME" "M_G_DQS_DP<6>"
					( Origin gPackager )
				)
				( attribute "PNN" "M_G_DQS_DP<6>"
					( Origin gPackager )
				)
				( objectStatus "M_G_DQS_DP<6>" )
			)
			( signal "@baseboard_fab2_lib.baseboard_fab2(sch_1):m_g_dqs_dp(7)"
				( attribute "CDS_PHYS_NET_NAME" "M_G_DQS_DP<7>"
					( Origin gPackager )
				)
				( attribute "PNN" "M_G_DQS_DP<7>"
					( Origin gPackager )
				)
				( objectStatus "M_G_DQS_DP<7>" )
			)
			( signal "@baseboard_fab2_lib.baseboard_fab2(sch_1):m_g_dqs_dp(8)"
				( attribute "CDS_PHYS_NET_NAME" "M_G_DQS_DP<8>"
					( Origin gPackager )
				)
				( attribute "PNN" "M_G_DQS_DP<8>"
					( Origin gPackager )
				)
				( objectStatus "M_G_DQS_DP<8>" )
			)
			( signal "@baseboard_fab2_lib.baseboard_fab2(sch_1):m_g_dqs_dp(9)"
				( attribute "CDS_PHYS_NET_NAME" "M_G_DQS_DP<9>"
					( Origin gPackager )
				)
				( attribute "PNN" "M_G_DQS_DP<9>"
					( Origin gPackager )
				)
				( objectStatus "M_G_DQS_DP<9>" )
			)
			( signal "@baseboard_fab2_lib.baseboard_fab2(sch_1):m_g_dqs_dp(10)"
				( attribute "CDS_PHYS_NET_NAME" "M_G_DQS_DP<10>"
					( Origin gPackager )
				)
				( attribute "PNN" "M_G_DQS_DP<10>"
					( Origin gPackager )
				)
				( objectStatus "M_G_DQS_DP<10>" )
			)
			( signal "@baseboard_fab2_lib.baseboard_fab2(sch_1):m_g_dqs_dp(11)"
				( attribute "CDS_PHYS_NET_NAME" "M_G_DQS_DP<11>"
					( Origin gPackager )
				)
				( attribute "PNN" "M_G_DQS_DP<11>"
					( Origin gPackager )
				)
				( objectStatus "M_G_DQS_DP<11>" )
			)
			( signal "@baseboard_fab2_lib.baseboard_fab2(sch_1):m_g_dqs_dp(12)"
				( attribute "CDS_PHYS_NET_NAME" "M_G_DQS_DP<12>"
					( Origin gPackager )
				)
				( attribute "PNN" "M_G_DQS_DP<12>"
					( Origin gPackager )
				)
				( objectStatus "M_G_DQS_DP<12>" )
			)
			( signal "@baseboard_fab2_lib.baseboard_fab2(sch_1):m_g_dqs_dp(13)"
				( attribute "CDS_PHYS_NET_NAME" "M_G_DQS_DP<13>"
					( Origin gPackager )
				)
				( attribute "PNN" "M_G_DQS_DP<13>"
					( Origin gPackager )
				)
				( objectStatus "M_G_DQS_DP<13>" )
			)
			( signal "@baseboard_fab2_lib.baseboard_fab2(sch_1):m_g_dqs_dp(14)"
				( attribute "CDS_PHYS_NET_NAME" "M_G_DQS_DP<14>"
					( Origin gPackager )
				)
				( attribute "PNN" "M_G_DQS_DP<14>"
					( Origin gPackager )
				)
				( objectStatus "M_G_DQS_DP<14>" )
			)
			( signal "@baseboard_fab2_lib.baseboard_fab2(sch_1):m_g_dqs_dp(15)"
				( attribute "CDS_PHYS_NET_NAME" "M_G_DQS_DP<15>"
					( Origin gPackager )
				)
				( attribute "PNN" "M_G_DQS_DP<15>"
					( Origin gPackager )
				)
				( objectStatus "M_G_DQS_DP<15>" )
			)
			( signal "@baseboard_fab2_lib.baseboard_fab2(sch_1):m_g_dqs_dp(16)"
				( attribute "CDS_PHYS_NET_NAME" "M_G_DQS_DP<16>"
					( Origin gPackager )
				)
				( attribute "PNN" "M_G_DQS_DP<16>"
					( Origin gPackager )
				)
				( objectStatus "M_G_DQS_DP<16>" )
			)
			( signal "@baseboard_fab2_lib.baseboard_fab2(sch_1):m_g_dqs_dp(17)"
				( attribute "CDS_PHYS_NET_NAME" "M_G_DQS_DP<17>"
					( Origin gPackager )
				)
				( attribute "PNN" "M_G_DQS_DP<17>"
					( Origin gPackager )
				)
				( objectStatus "M_G_DQS_DP<17>" )
			)
			( signal "@baseboard_fab2_lib.baseboard_fab2(sch_1):m_g_ecc(0)"
				( attribute "CDS_PHYS_NET_NAME" "M_G_ECC<0>"
					( Origin gPackager )
				)
				( attribute "PNN" "M_G_ECC<0>"
					( Origin gPackager )
				)
				( objectStatus "M_G_ECC<0>" )
			)
			( signal "@baseboard_fab2_lib.baseboard_fab2(sch_1):m_g_ecc(1)"
				( attribute "CDS_PHYS_NET_NAME" "M_G_ECC<1>"
					( Origin gPackager )
				)
				( attribute "PNN" "M_G_ECC<1>"
					( Origin gPackager )
				)
				( objectStatus "M_G_ECC<1>" )
			)
			( signal "@baseboard_fab2_lib.baseboard_fab2(sch_1):m_g_ecc(2)"
				( attribute "CDS_PHYS_NET_NAME" "M_G_ECC<2>"
					( Origin gPackager )
				)
				( attribute "PNN" "M_G_ECC<2>"
					( Origin gPackager )
				)
				( objectStatus "M_G_ECC<2>" )
			)
			( signal "@baseboard_fab2_lib.baseboard_fab2(sch_1):m_g_ecc(3)"
				( attribute "CDS_PHYS_NET_NAME" "M_G_ECC<3>"
					( Origin gPackager )
				)
				( attribute "PNN" "M_G_ECC<3>"
					( Origin gPackager )
				)
				( objectStatus "M_G_ECC<3>" )
			)
			( signal "@baseboard_fab2_lib.baseboard_fab2(sch_1):m_g_ecc(4)"
				( attribute "CDS_PHYS_NET_NAME" "M_G_ECC<4>"
					( Origin gPackager )
				)
				( attribute "PNN" "M_G_ECC<4>"
					( Origin gPackager )
				)
				( objectStatus "M_G_ECC<4>" )
			)
			( signal "@baseboard_fab2_lib.baseboard_fab2(sch_1):m_g_ecc(5)"
				( attribute "CDS_PHYS_NET_NAME" "M_G_ECC<5>"
					( Origin gPackager )
				)
				( attribute "PNN" "M_G_ECC<5>"
					( Origin gPackager )
				)
				( objectStatus "M_G_ECC<5>" )
			)
			( signal "@baseboard_fab2_lib.baseboard_fab2(sch_1):m_g_ecc(6)"
				( attribute "CDS_PHYS_NET_NAME" "M_G_ECC<6>"
					( Origin gPackager )
				)
				( attribute "PNN" "M_G_ECC<6>"
					( Origin gPackager )
				)
				( objectStatus "M_G_ECC<6>" )
			)
			( signal "@baseboard_fab2_lib.baseboard_fab2(sch_1):m_g_ecc(7)"
				( attribute "CDS_PHYS_NET_NAME" "M_G_ECC<7>"
					( Origin gPackager )
				)
				( attribute "PNN" "M_G_ECC<7>"
					( Origin gPackager )
				)
				( objectStatus "M_G_ECC<7>" )
			)
			( signal "@baseboard_fab2_lib.baseboard_fab2(sch_1):m_g_ma(0)"
				( attribute "CDS_PHYS_NET_NAME" "M_G_MA<0>"
					( Origin gPackager )
				)
				( attribute "PNN" "M_G_MA<0>"
					( Origin gPackager )
				)
				( objectStatus "M_G_MA<0>" )
			)
			( signal "@baseboard_fab2_lib.baseboard_fab2(sch_1):m_g_ma(1)"
				( attribute "CDS_PHYS_NET_NAME" "M_G_MA<1>"
					( Origin gPackager )
				)
				( attribute "PNN" "M_G_MA<1>"
					( Origin gPackager )
				)
				( objectStatus "M_G_MA<1>" )
			)
			( signal "@baseboard_fab2_lib.baseboard_fab2(sch_1):m_g_ma(2)"
				( attribute "CDS_PHYS_NET_NAME" "M_G_MA<2>"
					( Origin gPackager )
				)
				( attribute "PNN" "M_G_MA<2>"
					( Origin gPackager )
				)
				( objectStatus "M_G_MA<2>" )
			)
			( signal "@baseboard_fab2_lib.baseboard_fab2(sch_1):m_g_ma(3)"
				( attribute "CDS_PHYS_NET_NAME" "M_G_MA<3>"
					( Origin gPackager )
				)
				( attribute "PNN" "M_G_MA<3>"
					( Origin gPackager )
				)
				( objectStatus "M_G_MA<3>" )
			)
			( signal "@baseboard_fab2_lib.baseboard_fab2(sch_1):m_g_ma(4)"
				( attribute "CDS_PHYS_NET_NAME" "M_G_MA<4>"
					( Origin gPackager )
				)
				( attribute "PNN" "M_G_MA<4>"
					( Origin gPackager )
				)
				( objectStatus "M_G_MA<4>" )
			)
			( signal "@baseboard_fab2_lib.baseboard_fab2(sch_1):m_g_ma(5)"
				( attribute "CDS_PHYS_NET_NAME" "M_G_MA<5>"
					( Origin gPackager )
				)
				( attribute "PNN" "M_G_MA<5>"
					( Origin gPackager )
				)
				( objectStatus "M_G_MA<5>" )
			)
			( signal "@baseboard_fab2_lib.baseboard_fab2(sch_1):m_g_ma(6)"
				( attribute "CDS_PHYS_NET_NAME" "M_G_MA<6>"
					( Origin gPackager )
				)
				( attribute "PNN" "M_G_MA<6>"
					( Origin gPackager )
				)
				( objectStatus "M_G_MA<6>" )
			)
			( signal "@baseboard_fab2_lib.baseboard_fab2(sch_1):m_g_ma(7)"
				( attribute "CDS_PHYS_NET_NAME" "M_G_MA<7>"
					( Origin gPackager )
				)
				( attribute "PNN" "M_G_MA<7>"
					( Origin gPackager )
				)
				( objectStatus "M_G_MA<7>" )
			)
			( signal "@baseboard_fab2_lib.baseboard_fab2(sch_1):m_g_ma(8)"
				( attribute "CDS_PHYS_NET_NAME" "M_G_MA<8>"
					( Origin gPackager )
				)
				( attribute "PNN" "M_G_MA<8>"
					( Origin gPackager )
				)
				( objectStatus "M_G_MA<8>" )
			)
			( signal "@baseboard_fab2_lib.baseboard_fab2(sch_1):m_g_ma(9)"
				( attribute "CDS_PHYS_NET_NAME" "M_G_MA<9>"
					( Origin gPackager )
				)
				( attribute "PNN" "M_G_MA<9>"
					( Origin gPackager )
				)
				( objectStatus "M_G_MA<9>" )
			)
			( signal "@baseboard_fab2_lib.baseboard_fab2(sch_1):m_g_ma(10)"
				( attribute "CDS_PHYS_NET_NAME" "M_G_MA<10>"
					( Origin gPackager )
				)
				( attribute "PNN" "M_G_MA<10>"
					( Origin gPackager )
				)
				( objectStatus "M_G_MA<10>" )
			)
			( signal "@baseboard_fab2_lib.baseboard_fab2(sch_1):m_g_ma(11)"
				( attribute "CDS_PHYS_NET_NAME" "M_G_MA<11>"
					( Origin gPackager )
				)
				( attribute "PNN" "M_G_MA<11>"
					( Origin gPackager )
				)
				( objectStatus "M_G_MA<11>" )
			)
			( signal "@baseboard_fab2_lib.baseboard_fab2(sch_1):m_g_ma(12)"
				( attribute "CDS_PHYS_NET_NAME" "M_G_MA<12>"
					( Origin gPackager )
				)
				( attribute "PNN" "M_G_MA<12>"
					( Origin gPackager )
				)
				( objectStatus "M_G_MA<12>" )
			)
			( signal "@baseboard_fab2_lib.baseboard_fab2(sch_1):m_g_ma(13)"
				( attribute "CDS_PHYS_NET_NAME" "M_G_MA<13>"
					( Origin gPackager )
				)
				( attribute "PNN" "M_G_MA<13>"
					( Origin gPackager )
				)
				( objectStatus "M_G_MA<13>" )
			)
			( signal "@baseboard_fab2_lib.baseboard_fab2(sch_1):m_g_ma(14)"
				( attribute "CDS_PHYS_NET_NAME" "M_G_MA<14>"
					( Origin gPackager )
				)
				( attribute "PNN" "M_G_MA<14>"
					( Origin gPackager )
				)
				( objectStatus "M_G_MA<14>" )
			)
			( signal "@baseboard_fab2_lib.baseboard_fab2(sch_1):m_g_ma(15)"
				( attribute "CDS_PHYS_NET_NAME" "M_G_MA<15>"
					( Origin gPackager )
				)
				( attribute "PNN" "M_G_MA<15>"
					( Origin gPackager )
				)
				( objectStatus "M_G_MA<15>" )
			)
			( signal "@baseboard_fab2_lib.baseboard_fab2(sch_1):m_g_ma(16)"
				( attribute "CDS_PHYS_NET_NAME" "M_G_MA<16>"
					( Origin gPackager )
				)
				( attribute "PNN" "M_G_MA<16>"
					( Origin gPackager )
				)
				( objectStatus "M_G_MA<16>" )
			)
			( signal "@baseboard_fab2_lib.baseboard_fab2(sch_1):m_g_ma(17)"
				( attribute "CDS_PHYS_NET_NAME" "M_G_MA<17>"
					( Origin gPackager )
				)
				( attribute "PNN" "M_G_MA<17>"
					( Origin gPackager )
				)
				( objectStatus "M_G_MA<17>" )
			)
			( signal "@baseboard_fab2_lib.baseboard_fab2(sch_1):m_g_odt(0)"
				( attribute "CDS_PHYS_NET_NAME" "M_G_ODT<0>"
					( Origin gPackager )
				)
				( attribute "PNN" "M_G_ODT<0>"
					( Origin gPackager )
				)
				( objectStatus "M_G_ODT<0>" )
			)
			( signal "@baseboard_fab2_lib.baseboard_fab2(sch_1):m_g_odt(1)"
				( attribute "CDS_PHYS_NET_NAME" "M_G_ODT<1>"
					( Origin gPackager )
				)
				( attribute "PNN" "M_G_ODT<1>"
					( Origin gPackager )
				)
				( objectStatus "M_G_ODT<1>" )
			)
			( signal "@baseboard_fab2_lib.baseboard_fab2(sch_1):m_g_odt(2)"
				( attribute "CDS_PHYS_NET_NAME" "M_G_ODT<2>"
					( Origin gPackager )
				)
				( attribute "PNN" "M_G_ODT<2>"
					( Origin gPackager )
				)
				( objectStatus "M_G_ODT<2>" )
			)
			( signal "@baseboard_fab2_lib.baseboard_fab2(sch_1):m_g_odt(3)"
				( attribute "CDS_PHYS_NET_NAME" "M_G_ODT<3>"
					( Origin gPackager )
				)
				( attribute "PNN" "M_G_ODT<3>"
					( Origin gPackager )
				)
				( objectStatus "M_G_ODT<3>" )
			)
			( signal "@baseboard_fab2_lib.baseboard_fab2(sch_1):m_g_par"
				( attribute "CDS_PHYS_NET_NAME" "M_G_PAR"
					( Origin gPackager )
				)
				( objectStatus "M_G_PAR" )
			)
			( signal "@baseboard_fab2_lib.baseboard_fab2(sch_1):m_h_act_n"
				( attribute "CDS_PHYS_NET_NAME" "M_H_ACT_N"
					( Origin gPackager )
				)
				( objectStatus "M_H_ACT_N" )
			)
			( signal "@baseboard_fab2_lib.baseboard_fab2(sch_1):m_h_alert_n"
				( attribute "CDS_PHYS_NET_NAME" "M_H_ALERT_N"
					( Origin gPackager )
				)
				( objectStatus "M_H_ALERT_N" )
			)
			( signal "@baseboard_fab2_lib.baseboard_fab2(sch_1):m_h_ba(0)"
				( attribute "CDS_PHYS_NET_NAME" "M_H_BA<0>"
					( Origin gPackager )
				)
				( attribute "PNN" "M_H_BA<0>"
					( Origin gPackager )
				)
				( objectStatus "M_H_BA<0>" )
			)
			( signal "@baseboard_fab2_lib.baseboard_fab2(sch_1):m_h_ba(1)"
				( attribute "CDS_PHYS_NET_NAME" "M_H_BA<1>"
					( Origin gPackager )
				)
				( attribute "PNN" "M_H_BA<1>"
					( Origin gPackager )
				)
				( objectStatus "M_H_BA<1>" )
			)
			( signal "@baseboard_fab2_lib.baseboard_fab2(sch_1):m_h_bg(0)"
				( attribute "CDS_PHYS_NET_NAME" "M_H_BG<0>"
					( Origin gPackager )
				)
				( attribute "PNN" "M_H_BG<0>"
					( Origin gPackager )
				)
				( objectStatus "M_H_BG<0>" )
			)
			( signal "@baseboard_fab2_lib.baseboard_fab2(sch_1):m_h_bg(1)"
				( attribute "CDS_PHYS_NET_NAME" "M_H_BG<1>"
					( Origin gPackager )
				)
				( attribute "PNN" "M_H_BG<1>"
					( Origin gPackager )
				)
				( objectStatus "M_H_BG<1>" )
			)
			( signal "@baseboard_fab2_lib.baseboard_fab2(sch_1):m_h_c(2)"
				( attribute "CDS_PHYS_NET_NAME" "M_H_C<2>"
					( Origin gPackager )
				)
				( attribute "PNN" "M_H_C<2>"
					( Origin gPackager )
				)
				( objectStatus "M_H_C<2>" )
			)
			( signal "@baseboard_fab2_lib.baseboard_fab2(sch_1):m_h_cke(0)"
				( attribute "CDS_PHYS_NET_NAME" "M_H_CKE<0>"
					( Origin gPackager )
				)
				( attribute "PNN" "M_H_CKE<0>"
					( Origin gPackager )
				)
				( objectStatus "M_H_CKE<0>" )
			)
			( signal "@baseboard_fab2_lib.baseboard_fab2(sch_1):m_h_cke(1)"
				( attribute "CDS_PHYS_NET_NAME" "M_H_CKE<1>"
					( Origin gPackager )
				)
				( attribute "PNN" "M_H_CKE<1>"
					( Origin gPackager )
				)
				( objectStatus "M_H_CKE<1>" )
			)
			( signal "@baseboard_fab2_lib.baseboard_fab2(sch_1):m_h_cke(2)"
				( attribute "CDS_PHYS_NET_NAME" "M_H_CKE<2>"
					( Origin gPackager )
				)
				( attribute "PNN" "M_H_CKE<2>"
					( Origin gPackager )
				)
				( objectStatus "M_H_CKE<2>" )
			)
			( signal "@baseboard_fab2_lib.baseboard_fab2(sch_1):m_h_cke(3)"
				( attribute "CDS_PHYS_NET_NAME" "M_H_CKE<3>"
					( Origin gPackager )
				)
				( attribute "PNN" "M_H_CKE<3>"
					( Origin gPackager )
				)
				( objectStatus "M_H_CKE<3>" )
			)
			( signal "@baseboard_fab2_lib.baseboard_fab2(sch_1):m_h_clk_dn(0)"
				( attribute "CDS_PHYS_NET_NAME" "M_H_CLK_DN<0>"
					( Origin gPackager )
				)
				( attribute "PNN" "M_H_CLK_DN<0>"
					( Origin gPackager )
				)
				( objectStatus "M_H_CLK_DN<0>" )
			)
			( signal "@baseboard_fab2_lib.baseboard_fab2(sch_1):m_h_clk_dn(1)"
				( attribute "CDS_PHYS_NET_NAME" "M_H_CLK_DN<1>"
					( Origin gPackager )
				)
				( attribute "PNN" "M_H_CLK_DN<1>"
					( Origin gPackager )
				)
				( objectStatus "M_H_CLK_DN<1>" )
			)
			( signal "@baseboard_fab2_lib.baseboard_fab2(sch_1):m_h_clk_dn(2)"
				( attribute "CDS_PHYS_NET_NAME" "M_H_CLK_DN<2>"
					( Origin gPackager )
				)
				( attribute "PNN" "M_H_CLK_DN<2>"
					( Origin gPackager )
				)
				( objectStatus "M_H_CLK_DN<2>" )
			)
			( signal "@baseboard_fab2_lib.baseboard_fab2(sch_1):m_h_clk_dn(3)"
				( attribute "CDS_PHYS_NET_NAME" "M_H_CLK_DN<3>"
					( Origin gPackager )
				)
				( attribute "PNN" "M_H_CLK_DN<3>"
					( Origin gPackager )
				)
				( objectStatus "M_H_CLK_DN<3>" )
			)
			( signal "@baseboard_fab2_lib.baseboard_fab2(sch_1):m_h_clk_dp(0)"
				( attribute "CDS_PHYS_NET_NAME" "M_H_CLK_DP<0>"
					( Origin gPackager )
				)
				( attribute "PNN" "M_H_CLK_DP<0>"
					( Origin gPackager )
				)
				( objectStatus "M_H_CLK_DP<0>" )
			)
			( signal "@baseboard_fab2_lib.baseboard_fab2(sch_1):m_h_clk_dp(1)"
				( attribute "CDS_PHYS_NET_NAME" "M_H_CLK_DP<1>"
					( Origin gPackager )
				)
				( attribute "PNN" "M_H_CLK_DP<1>"
					( Origin gPackager )
				)
				( objectStatus "M_H_CLK_DP<1>" )
			)
			( signal "@baseboard_fab2_lib.baseboard_fab2(sch_1):m_h_clk_dp(2)"
				( attribute "CDS_PHYS_NET_NAME" "M_H_CLK_DP<2>"
					( Origin gPackager )
				)
				( attribute "PNN" "M_H_CLK_DP<2>"
					( Origin gPackager )
				)
				( objectStatus "M_H_CLK_DP<2>" )
			)
			( signal "@baseboard_fab2_lib.baseboard_fab2(sch_1):m_h_clk_dp(3)"
				( attribute "CDS_PHYS_NET_NAME" "M_H_CLK_DP<3>"
					( Origin gPackager )
				)
				( attribute "PNN" "M_H_CLK_DP<3>"
					( Origin gPackager )
				)
				( objectStatus "M_H_CLK_DP<3>" )
			)
			( signal "@baseboard_fab2_lib.baseboard_fab2(sch_1):m_h_cs_n(0)"
				( attribute "CDS_PHYS_NET_NAME" "M_H_CS_N<0>"
					( Origin gPackager )
				)
				( attribute "PNN" "M_H_CS_N<0>"
					( Origin gPackager )
				)
				( objectStatus "M_H_CS_N<0>" )
			)
			( signal "@baseboard_fab2_lib.baseboard_fab2(sch_1):m_h_cs_n(1)"
				( attribute "CDS_PHYS_NET_NAME" "M_H_CS_N<1>"
					( Origin gPackager )
				)
				( attribute "PNN" "M_H_CS_N<1>"
					( Origin gPackager )
				)
				( objectStatus "M_H_CS_N<1>" )
			)
			( signal "@baseboard_fab2_lib.baseboard_fab2(sch_1):m_h_cs_n(2)"
				( attribute "CDS_PHYS_NET_NAME" "M_H_CS_N<2>"
					( Origin gPackager )
				)
				( attribute "PNN" "M_H_CS_N<2>"
					( Origin gPackager )
				)
				( objectStatus "M_H_CS_N<2>" )
			)
			( signal "@baseboard_fab2_lib.baseboard_fab2(sch_1):m_h_cs_n(3)"
				( attribute "CDS_PHYS_NET_NAME" "M_H_CS_N<3>"
					( Origin gPackager )
				)
				( attribute "PNN" "M_H_CS_N<3>"
					( Origin gPackager )
				)
				( objectStatus "M_H_CS_N<3>" )
			)
			( signal "@baseboard_fab2_lib.baseboard_fab2(sch_1):m_h_cs_n(4)"
				( attribute "CDS_PHYS_NET_NAME" "M_H_CS_N<4>"
					( Origin gPackager )
				)
				( attribute "PNN" "M_H_CS_N<4>"
					( Origin gPackager )
				)
				( objectStatus "M_H_CS_N<4>" )
			)
			( signal "@baseboard_fab2_lib.baseboard_fab2(sch_1):m_h_cs_n(5)"
				( attribute "CDS_PHYS_NET_NAME" "M_H_CS_N<5>"
					( Origin gPackager )
				)
				( attribute "PNN" "M_H_CS_N<5>"
					( Origin gPackager )
				)
				( objectStatus "M_H_CS_N<5>" )
			)
			( signal "@baseboard_fab2_lib.baseboard_fab2(sch_1):m_h_cs_n(6)"
				( attribute "CDS_PHYS_NET_NAME" "M_H_CS_N<6>"
					( Origin gPackager )
				)
				( attribute "PNN" "M_H_CS_N<6>"
					( Origin gPackager )
				)
				( objectStatus "M_H_CS_N<6>" )
			)
			( signal "@baseboard_fab2_lib.baseboard_fab2(sch_1):m_h_cs_n(7)"
				( attribute "CDS_PHYS_NET_NAME" "M_H_CS_N<7>"
					( Origin gPackager )
				)
				( attribute "PNN" "M_H_CS_N<7>"
					( Origin gPackager )
				)
				( objectStatus "M_H_CS_N<7>" )
			)
			( signal "@baseboard_fab2_lib.baseboard_fab2(sch_1):m_h_dq(0)"
				( attribute "CDS_PHYS_NET_NAME" "M_H_DQ<0>"
					( Origin gPackager )
				)
				( attribute "PNN" "M_H_DQ<0>"
					( Origin gPackager )
				)
				( objectStatus "M_H_DQ<0>" )
			)
			( signal "@baseboard_fab2_lib.baseboard_fab2(sch_1):m_h_dq(1)"
				( attribute "CDS_PHYS_NET_NAME" "M_H_DQ<1>"
					( Origin gPackager )
				)
				( attribute "PNN" "M_H_DQ<1>"
					( Origin gPackager )
				)
				( objectStatus "M_H_DQ<1>" )
			)
			( signal "@baseboard_fab2_lib.baseboard_fab2(sch_1):m_h_dq(2)"
				( attribute "CDS_PHYS_NET_NAME" "M_H_DQ<2>"
					( Origin gPackager )
				)
				( attribute "PNN" "M_H_DQ<2>"
					( Origin gPackager )
				)
				( objectStatus "M_H_DQ<2>" )
			)
			( signal "@baseboard_fab2_lib.baseboard_fab2(sch_1):m_h_dq(3)"
				( attribute "CDS_PHYS_NET_NAME" "M_H_DQ<3>"
					( Origin gPackager )
				)
				( attribute "PNN" "M_H_DQ<3>"
					( Origin gPackager )
				)
				( objectStatus "M_H_DQ<3>" )
			)
			( signal "@baseboard_fab2_lib.baseboard_fab2(sch_1):m_h_dq(4)"
				( attribute "CDS_PHYS_NET_NAME" "M_H_DQ<4>"
					( Origin gPackager )
				)
				( attribute "PNN" "M_H_DQ<4>"
					( Origin gPackager )
				)
				( objectStatus "M_H_DQ<4>" )
			)
			( signal "@baseboard_fab2_lib.baseboard_fab2(sch_1):m_h_dq(5)"
				( attribute "CDS_PHYS_NET_NAME" "M_H_DQ<5>"
					( Origin gPackager )
				)
				( attribute "PNN" "M_H_DQ<5>"
					( Origin gPackager )
				)
				( objectStatus "M_H_DQ<5>" )
			)
			( signal "@baseboard_fab2_lib.baseboard_fab2(sch_1):m_h_dq(6)"
				( attribute "CDS_PHYS_NET_NAME" "M_H_DQ<6>"
					( Origin gPackager )
				)
				( attribute "PNN" "M_H_DQ<6>"
					( Origin gPackager )
				)
				( objectStatus "M_H_DQ<6>" )
			)
			( signal "@baseboard_fab2_lib.baseboard_fab2(sch_1):m_h_dq(7)"
				( attribute "CDS_PHYS_NET_NAME" "M_H_DQ<7>"
					( Origin gPackager )
				)
				( attribute "PNN" "M_H_DQ<7>"
					( Origin gPackager )
				)
				( objectStatus "M_H_DQ<7>" )
			)
			( signal "@baseboard_fab2_lib.baseboard_fab2(sch_1):m_h_dq(8)"
				( attribute "CDS_PHYS_NET_NAME" "M_H_DQ<8>"
					( Origin gPackager )
				)
				( attribute "PNN" "M_H_DQ<8>"
					( Origin gPackager )
				)
				( objectStatus "M_H_DQ<8>" )
			)
			( signal "@baseboard_fab2_lib.baseboard_fab2(sch_1):m_h_dq(9)"
				( attribute "CDS_PHYS_NET_NAME" "M_H_DQ<9>"
					( Origin gPackager )
				)
				( attribute "PNN" "M_H_DQ<9>"
					( Origin gPackager )
				)
				( objectStatus "M_H_DQ<9>" )
			)
			( signal "@baseboard_fab2_lib.baseboard_fab2(sch_1):m_h_dq(10)"
				( attribute "CDS_PHYS_NET_NAME" "M_H_DQ<10>"
					( Origin gPackager )
				)
				( attribute "PNN" "M_H_DQ<10>"
					( Origin gPackager )
				)
				( objectStatus "M_H_DQ<10>" )
			)
			( signal "@baseboard_fab2_lib.baseboard_fab2(sch_1):m_h_dq(11)"
				( attribute "CDS_PHYS_NET_NAME" "M_H_DQ<11>"
					( Origin gPackager )
				)
				( attribute "PNN" "M_H_DQ<11>"
					( Origin gPackager )
				)
				( objectStatus "M_H_DQ<11>" )
			)
			( signal "@baseboard_fab2_lib.baseboard_fab2(sch_1):m_h_dq(12)"
				( attribute "CDS_PHYS_NET_NAME" "M_H_DQ<12>"
					( Origin gPackager )
				)
				( attribute "PNN" "M_H_DQ<12>"
					( Origin gPackager )
				)
				( objectStatus "M_H_DQ<12>" )
			)
			( signal "@baseboard_fab2_lib.baseboard_fab2(sch_1):m_h_dq(13)"
				( attribute "CDS_PHYS_NET_NAME" "M_H_DQ<13>"
					( Origin gPackager )
				)
				( attribute "PNN" "M_H_DQ<13>"
					( Origin gPackager )
				)
				( objectStatus "M_H_DQ<13>" )
			)
			( signal "@baseboard_fab2_lib.baseboard_fab2(sch_1):m_h_dq(14)"
				( attribute "CDS_PHYS_NET_NAME" "M_H_DQ<14>"
					( Origin gPackager )
				)
				( attribute "PNN" "M_H_DQ<14>"
					( Origin gPackager )
				)
				( objectStatus "M_H_DQ<14>" )
			)
			( signal "@baseboard_fab2_lib.baseboard_fab2(sch_1):m_h_dq(15)"
				( attribute "CDS_PHYS_NET_NAME" "M_H_DQ<15>"
					( Origin gPackager )
				)
				( attribute "PNN" "M_H_DQ<15>"
					( Origin gPackager )
				)
				( objectStatus "M_H_DQ<15>" )
			)
			( signal "@baseboard_fab2_lib.baseboard_fab2(sch_1):m_h_dq(16)"
				( attribute "CDS_PHYS_NET_NAME" "M_H_DQ<16>"
					( Origin gPackager )
				)
				( attribute "PNN" "M_H_DQ<16>"
					( Origin gPackager )
				)
				( objectStatus "M_H_DQ<16>" )
			)
			( signal "@baseboard_fab2_lib.baseboard_fab2(sch_1):m_h_dq(17)"
				( attribute "CDS_PHYS_NET_NAME" "M_H_DQ<17>"
					( Origin gPackager )
				)
				( attribute "PNN" "M_H_DQ<17>"
					( Origin gPackager )
				)
				( objectStatus "M_H_DQ<17>" )
			)
			( signal "@baseboard_fab2_lib.baseboard_fab2(sch_1):m_h_dq(18)"
				( attribute "CDS_PHYS_NET_NAME" "M_H_DQ<18>"
					( Origin gPackager )
				)
				( attribute "PNN" "M_H_DQ<18>"
					( Origin gPackager )
				)
				( objectStatus "M_H_DQ<18>" )
			)
			( signal "@baseboard_fab2_lib.baseboard_fab2(sch_1):m_h_dq(19)"
				( attribute "CDS_PHYS_NET_NAME" "M_H_DQ<19>"
					( Origin gPackager )
				)
				( attribute "PNN" "M_H_DQ<19>"
					( Origin gPackager )
				)
				( objectStatus "M_H_DQ<19>" )
			)
			( signal "@baseboard_fab2_lib.baseboard_fab2(sch_1):m_h_dq(20)"
				( attribute "CDS_PHYS_NET_NAME" "M_H_DQ<20>"
					( Origin gPackager )
				)
				( attribute "PNN" "M_H_DQ<20>"
					( Origin gPackager )
				)
				( objectStatus "M_H_DQ<20>" )
			)
			( signal "@baseboard_fab2_lib.baseboard_fab2(sch_1):m_h_dq(21)"
				( attribute "CDS_PHYS_NET_NAME" "M_H_DQ<21>"
					( Origin gPackager )
				)
				( attribute "PNN" "M_H_DQ<21>"
					( Origin gPackager )
				)
				( objectStatus "M_H_DQ<21>" )
			)
			( signal "@baseboard_fab2_lib.baseboard_fab2(sch_1):m_h_dq(22)"
				( attribute "CDS_PHYS_NET_NAME" "M_H_DQ<22>"
					( Origin gPackager )
				)
				( attribute "PNN" "M_H_DQ<22>"
					( Origin gPackager )
				)
				( objectStatus "M_H_DQ<22>" )
			)
			( signal "@baseboard_fab2_lib.baseboard_fab2(sch_1):m_h_dq(23)"
				( attribute "CDS_PHYS_NET_NAME" "M_H_DQ<23>"
					( Origin gPackager )
				)
				( attribute "PNN" "M_H_DQ<23>"
					( Origin gPackager )
				)
				( objectStatus "M_H_DQ<23>" )
			)
			( signal "@baseboard_fab2_lib.baseboard_fab2(sch_1):m_h_dq(24)"
				( attribute "CDS_PHYS_NET_NAME" "M_H_DQ<24>"
					( Origin gPackager )
				)
				( attribute "PNN" "M_H_DQ<24>"
					( Origin gPackager )
				)
				( objectStatus "M_H_DQ<24>" )
			)
			( signal "@baseboard_fab2_lib.baseboard_fab2(sch_1):m_h_dq(25)"
				( attribute "CDS_PHYS_NET_NAME" "M_H_DQ<25>"
					( Origin gPackager )
				)
				( attribute "PNN" "M_H_DQ<25>"
					( Origin gPackager )
				)
				( objectStatus "M_H_DQ<25>" )
			)
			( signal "@baseboard_fab2_lib.baseboard_fab2(sch_1):m_h_dq(26)"
				( attribute "CDS_PHYS_NET_NAME" "M_H_DQ<26>"
					( Origin gPackager )
				)
				( attribute "PNN" "M_H_DQ<26>"
					( Origin gPackager )
				)
				( objectStatus "M_H_DQ<26>" )
			)
			( signal "@baseboard_fab2_lib.baseboard_fab2(sch_1):m_h_dq(27)"
				( attribute "CDS_PHYS_NET_NAME" "M_H_DQ<27>"
					( Origin gPackager )
				)
				( attribute "PNN" "M_H_DQ<27>"
					( Origin gPackager )
				)
				( objectStatus "M_H_DQ<27>" )
			)
			( signal "@baseboard_fab2_lib.baseboard_fab2(sch_1):m_h_dq(28)"
				( attribute "CDS_PHYS_NET_NAME" "M_H_DQ<28>"
					( Origin gPackager )
				)
				( attribute "PNN" "M_H_DQ<28>"
					( Origin gPackager )
				)
				( objectStatus "M_H_DQ<28>" )
			)
			( signal "@baseboard_fab2_lib.baseboard_fab2(sch_1):m_h_dq(29)"
				( attribute "CDS_PHYS_NET_NAME" "M_H_DQ<29>"
					( Origin gPackager )
				)
				( attribute "PNN" "M_H_DQ<29>"
					( Origin gPackager )
				)
				( objectStatus "M_H_DQ<29>" )
			)
			( signal "@baseboard_fab2_lib.baseboard_fab2(sch_1):m_h_dq(30)"
				( attribute "CDS_PHYS_NET_NAME" "M_H_DQ<30>"
					( Origin gPackager )
				)
				( attribute "PNN" "M_H_DQ<30>"
					( Origin gPackager )
				)
				( objectStatus "M_H_DQ<30>" )
			)
			( signal "@baseboard_fab2_lib.baseboard_fab2(sch_1):m_h_dq(31)"
				( attribute "CDS_PHYS_NET_NAME" "M_H_DQ<31>"
					( Origin gPackager )
				)
				( attribute "PNN" "M_H_DQ<31>"
					( Origin gPackager )
				)
				( objectStatus "M_H_DQ<31>" )
			)
			( signal "@baseboard_fab2_lib.baseboard_fab2(sch_1):m_h_dq(32)"
				( attribute "CDS_PHYS_NET_NAME" "M_H_DQ<32>"
					( Origin gPackager )
				)
				( attribute "PNN" "M_H_DQ<32>"
					( Origin gPackager )
				)
				( objectStatus "M_H_DQ<32>" )
			)
			( signal "@baseboard_fab2_lib.baseboard_fab2(sch_1):m_h_dq(33)"
				( attribute "CDS_PHYS_NET_NAME" "M_H_DQ<33>"
					( Origin gPackager )
				)
				( attribute "PNN" "M_H_DQ<33>"
					( Origin gPackager )
				)
				( objectStatus "M_H_DQ<33>" )
			)
			( signal "@baseboard_fab2_lib.baseboard_fab2(sch_1):m_h_dq(34)"
				( attribute "CDS_PHYS_NET_NAME" "M_H_DQ<34>"
					( Origin gPackager )
				)
				( attribute "PNN" "M_H_DQ<34>"
					( Origin gPackager )
				)
				( objectStatus "M_H_DQ<34>" )
			)
			( signal "@baseboard_fab2_lib.baseboard_fab2(sch_1):m_h_dq(35)"
				( attribute "CDS_PHYS_NET_NAME" "M_H_DQ<35>"
					( Origin gPackager )
				)
				( attribute "PNN" "M_H_DQ<35>"
					( Origin gPackager )
				)
				( objectStatus "M_H_DQ<35>" )
			)
			( signal "@baseboard_fab2_lib.baseboard_fab2(sch_1):m_h_dq(36)"
				( attribute "CDS_PHYS_NET_NAME" "M_H_DQ<36>"
					( Origin gPackager )
				)
				( attribute "PNN" "M_H_DQ<36>"
					( Origin gPackager )
				)
				( objectStatus "M_H_DQ<36>" )
			)
			( signal "@baseboard_fab2_lib.baseboard_fab2(sch_1):m_h_dq(37)"
				( attribute "CDS_PHYS_NET_NAME" "M_H_DQ<37>"
					( Origin gPackager )
				)
				( attribute "PNN" "M_H_DQ<37>"
					( Origin gPackager )
				)
				( objectStatus "M_H_DQ<37>" )
			)
			( signal "@baseboard_fab2_lib.baseboard_fab2(sch_1):m_h_dq(38)"
				( attribute "CDS_PHYS_NET_NAME" "M_H_DQ<38>"
					( Origin gPackager )
				)
				( attribute "PNN" "M_H_DQ<38>"
					( Origin gPackager )
				)
				( objectStatus "M_H_DQ<38>" )
			)
			( signal "@baseboard_fab2_lib.baseboard_fab2(sch_1):m_h_dq(39)"
				( attribute "CDS_PHYS_NET_NAME" "M_H_DQ<39>"
					( Origin gPackager )
				)
				( attribute "PNN" "M_H_DQ<39>"
					( Origin gPackager )
				)
				( objectStatus "M_H_DQ<39>" )
			)
			( signal "@baseboard_fab2_lib.baseboard_fab2(sch_1):m_h_dq(40)"
				( attribute "CDS_PHYS_NET_NAME" "M_H_DQ<40>"
					( Origin gPackager )
				)
				( attribute "PNN" "M_H_DQ<40>"
					( Origin gPackager )
				)
				( objectStatus "M_H_DQ<40>" )
			)
			( signal "@baseboard_fab2_lib.baseboard_fab2(sch_1):m_h_dq(41)"
				( attribute "CDS_PHYS_NET_NAME" "M_H_DQ<41>"
					( Origin gPackager )
				)
				( attribute "PNN" "M_H_DQ<41>"
					( Origin gPackager )
				)
				( objectStatus "M_H_DQ<41>" )
			)
			( signal "@baseboard_fab2_lib.baseboard_fab2(sch_1):m_h_dq(42)"
				( attribute "CDS_PHYS_NET_NAME" "M_H_DQ<42>"
					( Origin gPackager )
				)
				( attribute "PNN" "M_H_DQ<42>"
					( Origin gPackager )
				)
				( objectStatus "M_H_DQ<42>" )
			)
			( signal "@baseboard_fab2_lib.baseboard_fab2(sch_1):m_h_dq(43)"
				( attribute "CDS_PHYS_NET_NAME" "M_H_DQ<43>"
					( Origin gPackager )
				)
				( attribute "PNN" "M_H_DQ<43>"
					( Origin gPackager )
				)
				( objectStatus "M_H_DQ<43>" )
			)
			( signal "@baseboard_fab2_lib.baseboard_fab2(sch_1):m_h_dq(44)"
				( attribute "CDS_PHYS_NET_NAME" "M_H_DQ<44>"
					( Origin gPackager )
				)
				( attribute "PNN" "M_H_DQ<44>"
					( Origin gPackager )
				)
				( objectStatus "M_H_DQ<44>" )
			)
			( signal "@baseboard_fab2_lib.baseboard_fab2(sch_1):m_h_dq(45)"
				( attribute "CDS_PHYS_NET_NAME" "M_H_DQ<45>"
					( Origin gPackager )
				)
				( attribute "PNN" "M_H_DQ<45>"
					( Origin gPackager )
				)
				( objectStatus "M_H_DQ<45>" )
			)
			( signal "@baseboard_fab2_lib.baseboard_fab2(sch_1):m_h_dq(46)"
				( attribute "CDS_PHYS_NET_NAME" "M_H_DQ<46>"
					( Origin gPackager )
				)
				( attribute "PNN" "M_H_DQ<46>"
					( Origin gPackager )
				)
				( objectStatus "M_H_DQ<46>" )
			)
			( signal "@baseboard_fab2_lib.baseboard_fab2(sch_1):m_h_dq(47)"
				( attribute "CDS_PHYS_NET_NAME" "M_H_DQ<47>"
					( Origin gPackager )
				)
				( attribute "PNN" "M_H_DQ<47>"
					( Origin gPackager )
				)
				( objectStatus "M_H_DQ<47>" )
			)
			( signal "@baseboard_fab2_lib.baseboard_fab2(sch_1):m_h_dq(48)"
				( attribute "CDS_PHYS_NET_NAME" "M_H_DQ<48>"
					( Origin gPackager )
				)
				( attribute "PNN" "M_H_DQ<48>"
					( Origin gPackager )
				)
				( objectStatus "M_H_DQ<48>" )
			)
			( signal "@baseboard_fab2_lib.baseboard_fab2(sch_1):m_h_dq(49)"
				( attribute "CDS_PHYS_NET_NAME" "M_H_DQ<49>"
					( Origin gPackager )
				)
				( attribute "PNN" "M_H_DQ<49>"
					( Origin gPackager )
				)
				( objectStatus "M_H_DQ<49>" )
			)
			( signal "@baseboard_fab2_lib.baseboard_fab2(sch_1):m_h_dq(50)"
				( attribute "CDS_PHYS_NET_NAME" "M_H_DQ<50>"
					( Origin gPackager )
				)
				( attribute "PNN" "M_H_DQ<50>"
					( Origin gPackager )
				)
				( objectStatus "M_H_DQ<50>" )
			)
			( signal "@baseboard_fab2_lib.baseboard_fab2(sch_1):m_h_dq(51)"
				( attribute "CDS_PHYS_NET_NAME" "M_H_DQ<51>"
					( Origin gPackager )
				)
				( attribute "PNN" "M_H_DQ<51>"
					( Origin gPackager )
				)
				( objectStatus "M_H_DQ<51>" )
			)
			( signal "@baseboard_fab2_lib.baseboard_fab2(sch_1):m_h_dq(52)"
				( attribute "CDS_PHYS_NET_NAME" "M_H_DQ<52>"
					( Origin gPackager )
				)
				( attribute "PNN" "M_H_DQ<52>"
					( Origin gPackager )
				)
				( objectStatus "M_H_DQ<52>" )
			)
			( signal "@baseboard_fab2_lib.baseboard_fab2(sch_1):m_h_dq(53)"
				( attribute "CDS_PHYS_NET_NAME" "M_H_DQ<53>"
					( Origin gPackager )
				)
				( attribute "PNN" "M_H_DQ<53>"
					( Origin gPackager )
				)
				( objectStatus "M_H_DQ<53>" )
			)
			( signal "@baseboard_fab2_lib.baseboard_fab2(sch_1):m_h_dq(54)"
				( attribute "CDS_PHYS_NET_NAME" "M_H_DQ<54>"
					( Origin gPackager )
				)
				( attribute "PNN" "M_H_DQ<54>"
					( Origin gPackager )
				)
				( objectStatus "M_H_DQ<54>" )
			)
			( signal "@baseboard_fab2_lib.baseboard_fab2(sch_1):m_h_dq(55)"
				( attribute "CDS_PHYS_NET_NAME" "M_H_DQ<55>"
					( Origin gPackager )
				)
				( attribute "PNN" "M_H_DQ<55>"
					( Origin gPackager )
				)
				( objectStatus "M_H_DQ<55>" )
			)
			( signal "@baseboard_fab2_lib.baseboard_fab2(sch_1):m_h_dq(56)"
				( attribute "CDS_PHYS_NET_NAME" "M_H_DQ<56>"
					( Origin gPackager )
				)
				( attribute "PNN" "M_H_DQ<56>"
					( Origin gPackager )
				)
				( objectStatus "M_H_DQ<56>" )
			)
			( signal "@baseboard_fab2_lib.baseboard_fab2(sch_1):m_h_dq(57)"
				( attribute "CDS_PHYS_NET_NAME" "M_H_DQ<57>"
					( Origin gPackager )
				)
				( attribute "PNN" "M_H_DQ<57>"
					( Origin gPackager )
				)
				( objectStatus "M_H_DQ<57>" )
			)
			( signal "@baseboard_fab2_lib.baseboard_fab2(sch_1):m_h_dq(58)"
				( attribute "CDS_PHYS_NET_NAME" "M_H_DQ<58>"
					( Origin gPackager )
				)
				( attribute "PNN" "M_H_DQ<58>"
					( Origin gPackager )
				)
				( objectStatus "M_H_DQ<58>" )
			)
			( signal "@baseboard_fab2_lib.baseboard_fab2(sch_1):m_h_dq(59)"
				( attribute "CDS_PHYS_NET_NAME" "M_H_DQ<59>"
					( Origin gPackager )
				)
				( attribute "PNN" "M_H_DQ<59>"
					( Origin gPackager )
				)
				( objectStatus "M_H_DQ<59>" )
			)
			( signal "@baseboard_fab2_lib.baseboard_fab2(sch_1):m_h_dq(60)"
				( attribute "CDS_PHYS_NET_NAME" "M_H_DQ<60>"
					( Origin gPackager )
				)
				( attribute "PNN" "M_H_DQ<60>"
					( Origin gPackager )
				)
				( objectStatus "M_H_DQ<60>" )
			)
			( signal "@baseboard_fab2_lib.baseboard_fab2(sch_1):m_h_dq(61)"
				( attribute "CDS_PHYS_NET_NAME" "M_H_DQ<61>"
					( Origin gPackager )
				)
				( attribute "PNN" "M_H_DQ<61>"
					( Origin gPackager )
				)
				( objectStatus "M_H_DQ<61>" )
			)
			( signal "@baseboard_fab2_lib.baseboard_fab2(sch_1):m_h_dq(62)"
				( attribute "CDS_PHYS_NET_NAME" "M_H_DQ<62>"
					( Origin gPackager )
				)
				( attribute "PNN" "M_H_DQ<62>"
					( Origin gPackager )
				)
				( objectStatus "M_H_DQ<62>" )
			)
			( signal "@baseboard_fab2_lib.baseboard_fab2(sch_1):m_h_dq(63)"
				( attribute "CDS_PHYS_NET_NAME" "M_H_DQ<63>"
					( Origin gPackager )
				)
				( attribute "PNN" "M_H_DQ<63>"
					( Origin gPackager )
				)
				( objectStatus "M_H_DQ<63>" )
			)
			( signal "@baseboard_fab2_lib.baseboard_fab2(sch_1):m_h_dqs_dn(0)"
				( attribute "CDS_PHYS_NET_NAME" "M_H_DQS_DN<0>"
					( Origin gPackager )
				)
				( attribute "PNN" "M_H_DQS_DN<0>"
					( Origin gPackager )
				)
				( objectStatus "M_H_DQS_DN<0>" )
			)
			( signal "@baseboard_fab2_lib.baseboard_fab2(sch_1):m_h_dqs_dn(1)"
				( attribute "CDS_PHYS_NET_NAME" "M_H_DQS_DN<1>"
					( Origin gPackager )
				)
				( attribute "PNN" "M_H_DQS_DN<1>"
					( Origin gPackager )
				)
				( objectStatus "M_H_DQS_DN<1>" )
			)
			( signal "@baseboard_fab2_lib.baseboard_fab2(sch_1):m_h_dqs_dn(2)"
				( attribute "CDS_PHYS_NET_NAME" "M_H_DQS_DN<2>"
					( Origin gPackager )
				)
				( attribute "PNN" "M_H_DQS_DN<2>"
					( Origin gPackager )
				)
				( objectStatus "M_H_DQS_DN<2>" )
			)
			( signal "@baseboard_fab2_lib.baseboard_fab2(sch_1):m_h_dqs_dn(3)"
				( attribute "CDS_PHYS_NET_NAME" "M_H_DQS_DN<3>"
					( Origin gPackager )
				)
				( attribute "PNN" "M_H_DQS_DN<3>"
					( Origin gPackager )
				)
				( objectStatus "M_H_DQS_DN<3>" )
			)
			( signal "@baseboard_fab2_lib.baseboard_fab2(sch_1):m_h_dqs_dn(4)"
				( attribute "CDS_PHYS_NET_NAME" "M_H_DQS_DN<4>"
					( Origin gPackager )
				)
				( attribute "PNN" "M_H_DQS_DN<4>"
					( Origin gPackager )
				)
				( objectStatus "M_H_DQS_DN<4>" )
			)
			( signal "@baseboard_fab2_lib.baseboard_fab2(sch_1):m_h_dqs_dn(5)"
				( attribute "CDS_PHYS_NET_NAME" "M_H_DQS_DN<5>"
					( Origin gPackager )
				)
				( attribute "PNN" "M_H_DQS_DN<5>"
					( Origin gPackager )
				)
				( objectStatus "M_H_DQS_DN<5>" )
			)
			( signal "@baseboard_fab2_lib.baseboard_fab2(sch_1):m_h_dqs_dn(6)"
				( attribute "CDS_PHYS_NET_NAME" "M_H_DQS_DN<6>"
					( Origin gPackager )
				)
				( attribute "PNN" "M_H_DQS_DN<6>"
					( Origin gPackager )
				)
				( objectStatus "M_H_DQS_DN<6>" )
			)
			( signal "@baseboard_fab2_lib.baseboard_fab2(sch_1):m_h_dqs_dn(7)"
				( attribute "CDS_PHYS_NET_NAME" "M_H_DQS_DN<7>"
					( Origin gPackager )
				)
				( attribute "PNN" "M_H_DQS_DN<7>"
					( Origin gPackager )
				)
				( objectStatus "M_H_DQS_DN<7>" )
			)
			( signal "@baseboard_fab2_lib.baseboard_fab2(sch_1):m_h_dqs_dn(8)"
				( attribute "CDS_PHYS_NET_NAME" "M_H_DQS_DN<8>"
					( Origin gPackager )
				)
				( attribute "PNN" "M_H_DQS_DN<8>"
					( Origin gPackager )
				)
				( objectStatus "M_H_DQS_DN<8>" )
			)
			( signal "@baseboard_fab2_lib.baseboard_fab2(sch_1):m_h_dqs_dn(9)"
				( attribute "CDS_PHYS_NET_NAME" "M_H_DQS_DN<9>"
					( Origin gPackager )
				)
				( attribute "PNN" "M_H_DQS_DN<9>"
					( Origin gPackager )
				)
				( objectStatus "M_H_DQS_DN<9>" )
			)
			( signal "@baseboard_fab2_lib.baseboard_fab2(sch_1):m_h_dqs_dn(10)"
				( attribute "CDS_PHYS_NET_NAME" "M_H_DQS_DN<10>"
					( Origin gPackager )
				)
				( attribute "PNN" "M_H_DQS_DN<10>"
					( Origin gPackager )
				)
				( objectStatus "M_H_DQS_DN<10>" )
			)
			( signal "@baseboard_fab2_lib.baseboard_fab2(sch_1):m_h_dqs_dn(11)"
				( attribute "CDS_PHYS_NET_NAME" "M_H_DQS_DN<11>"
					( Origin gPackager )
				)
				( attribute "PNN" "M_H_DQS_DN<11>"
					( Origin gPackager )
				)
				( objectStatus "M_H_DQS_DN<11>" )
			)
			( signal "@baseboard_fab2_lib.baseboard_fab2(sch_1):m_h_dqs_dn(12)"
				( attribute "CDS_PHYS_NET_NAME" "M_H_DQS_DN<12>"
					( Origin gPackager )
				)
				( attribute "PNN" "M_H_DQS_DN<12>"
					( Origin gPackager )
				)
				( objectStatus "M_H_DQS_DN<12>" )
			)
			( signal "@baseboard_fab2_lib.baseboard_fab2(sch_1):m_h_dqs_dn(13)"
				( attribute "CDS_PHYS_NET_NAME" "M_H_DQS_DN<13>"
					( Origin gPackager )
				)
				( attribute "PNN" "M_H_DQS_DN<13>"
					( Origin gPackager )
				)
				( objectStatus "M_H_DQS_DN<13>" )
			)
			( signal "@baseboard_fab2_lib.baseboard_fab2(sch_1):m_h_dqs_dn(14)"
				( attribute "CDS_PHYS_NET_NAME" "M_H_DQS_DN<14>"
					( Origin gPackager )
				)
				( attribute "PNN" "M_H_DQS_DN<14>"
					( Origin gPackager )
				)
				( objectStatus "M_H_DQS_DN<14>" )
			)
			( signal "@baseboard_fab2_lib.baseboard_fab2(sch_1):m_h_dqs_dn(15)"
				( attribute "CDS_PHYS_NET_NAME" "M_H_DQS_DN<15>"
					( Origin gPackager )
				)
				( attribute "PNN" "M_H_DQS_DN<15>"
					( Origin gPackager )
				)
				( objectStatus "M_H_DQS_DN<15>" )
			)
			( signal "@baseboard_fab2_lib.baseboard_fab2(sch_1):m_h_dqs_dn(16)"
				( attribute "CDS_PHYS_NET_NAME" "M_H_DQS_DN<16>"
					( Origin gPackager )
				)
				( attribute "PNN" "M_H_DQS_DN<16>"
					( Origin gPackager )
				)
				( objectStatus "M_H_DQS_DN<16>" )
			)
			( signal "@baseboard_fab2_lib.baseboard_fab2(sch_1):m_h_dqs_dn(17)"
				( attribute "CDS_PHYS_NET_NAME" "M_H_DQS_DN<17>"
					( Origin gPackager )
				)
				( attribute "PNN" "M_H_DQS_DN<17>"
					( Origin gPackager )
				)
				( objectStatus "M_H_DQS_DN<17>" )
			)
			( signal "@baseboard_fab2_lib.baseboard_fab2(sch_1):m_h_dqs_dp(0)"
				( attribute "CDS_PHYS_NET_NAME" "M_H_DQS_DP<0>"
					( Origin gPackager )
				)
				( attribute "PNN" "M_H_DQS_DP<0>"
					( Origin gPackager )
				)
				( objectStatus "M_H_DQS_DP<0>" )
			)
			( signal "@baseboard_fab2_lib.baseboard_fab2(sch_1):m_h_dqs_dp(1)"
				( attribute "CDS_PHYS_NET_NAME" "M_H_DQS_DP<1>"
					( Origin gPackager )
				)
				( attribute "PNN" "M_H_DQS_DP<1>"
					( Origin gPackager )
				)
				( objectStatus "M_H_DQS_DP<1>" )
			)
			( signal "@baseboard_fab2_lib.baseboard_fab2(sch_1):m_h_dqs_dp(2)"
				( attribute "CDS_PHYS_NET_NAME" "M_H_DQS_DP<2>"
					( Origin gPackager )
				)
				( attribute "PNN" "M_H_DQS_DP<2>"
					( Origin gPackager )
				)
				( objectStatus "M_H_DQS_DP<2>" )
			)
			( signal "@baseboard_fab2_lib.baseboard_fab2(sch_1):m_h_dqs_dp(3)"
				( attribute "CDS_PHYS_NET_NAME" "M_H_DQS_DP<3>"
					( Origin gPackager )
				)
				( attribute "PNN" "M_H_DQS_DP<3>"
					( Origin gPackager )
				)
				( objectStatus "M_H_DQS_DP<3>" )
			)
			( signal "@baseboard_fab2_lib.baseboard_fab2(sch_1):m_h_dqs_dp(4)"
				( attribute "CDS_PHYS_NET_NAME" "M_H_DQS_DP<4>"
					( Origin gPackager )
				)
				( attribute "PNN" "M_H_DQS_DP<4>"
					( Origin gPackager )
				)
				( objectStatus "M_H_DQS_DP<4>" )
			)
			( signal "@baseboard_fab2_lib.baseboard_fab2(sch_1):m_h_dqs_dp(5)"
				( attribute "CDS_PHYS_NET_NAME" "M_H_DQS_DP<5>"
					( Origin gPackager )
				)
				( attribute "PNN" "M_H_DQS_DP<5>"
					( Origin gPackager )
				)
				( objectStatus "M_H_DQS_DP<5>" )
			)
			( signal "@baseboard_fab2_lib.baseboard_fab2(sch_1):m_h_dqs_dp(6)"
				( attribute "CDS_PHYS_NET_NAME" "M_H_DQS_DP<6>"
					( Origin gPackager )
				)
				( attribute "PNN" "M_H_DQS_DP<6>"
					( Origin gPackager )
				)
				( objectStatus "M_H_DQS_DP<6>" )
			)
			( signal "@baseboard_fab2_lib.baseboard_fab2(sch_1):m_h_dqs_dp(7)"
				( attribute "CDS_PHYS_NET_NAME" "M_H_DQS_DP<7>"
					( Origin gPackager )
				)
				( attribute "PNN" "M_H_DQS_DP<7>"
					( Origin gPackager )
				)
				( objectStatus "M_H_DQS_DP<7>" )
			)
			( signal "@baseboard_fab2_lib.baseboard_fab2(sch_1):m_h_dqs_dp(8)"
				( attribute "CDS_PHYS_NET_NAME" "M_H_DQS_DP<8>"
					( Origin gPackager )
				)
				( attribute "PNN" "M_H_DQS_DP<8>"
					( Origin gPackager )
				)
				( objectStatus "M_H_DQS_DP<8>" )
			)
			( signal "@baseboard_fab2_lib.baseboard_fab2(sch_1):m_h_dqs_dp(9)"
				( attribute "CDS_PHYS_NET_NAME" "M_H_DQS_DP<9>"
					( Origin gPackager )
				)
				( attribute "PNN" "M_H_DQS_DP<9>"
					( Origin gPackager )
				)
				( objectStatus "M_H_DQS_DP<9>" )
			)
			( signal "@baseboard_fab2_lib.baseboard_fab2(sch_1):m_h_dqs_dp(10)"
				( attribute "CDS_PHYS_NET_NAME" "M_H_DQS_DP<10>"
					( Origin gPackager )
				)
				( attribute "PNN" "M_H_DQS_DP<10>"
					( Origin gPackager )
				)
				( objectStatus "M_H_DQS_DP<10>" )
			)
			( signal "@baseboard_fab2_lib.baseboard_fab2(sch_1):m_h_dqs_dp(11)"
				( attribute "CDS_PHYS_NET_NAME" "M_H_DQS_DP<11>"
					( Origin gPackager )
				)
				( attribute "PNN" "M_H_DQS_DP<11>"
					( Origin gPackager )
				)
				( objectStatus "M_H_DQS_DP<11>" )
			)
			( signal "@baseboard_fab2_lib.baseboard_fab2(sch_1):m_h_dqs_dp(12)"
				( attribute "CDS_PHYS_NET_NAME" "M_H_DQS_DP<12>"
					( Origin gPackager )
				)
				( attribute "PNN" "M_H_DQS_DP<12>"
					( Origin gPackager )
				)
				( objectStatus "M_H_DQS_DP<12>" )
			)
			( signal "@baseboard_fab2_lib.baseboard_fab2(sch_1):m_h_dqs_dp(13)"
				( attribute "CDS_PHYS_NET_NAME" "M_H_DQS_DP<13>"
					( Origin gPackager )
				)
				( attribute "PNN" "M_H_DQS_DP<13>"
					( Origin gPackager )
				)
				( objectStatus "M_H_DQS_DP<13>" )
			)
			( signal "@baseboard_fab2_lib.baseboard_fab2(sch_1):m_h_dqs_dp(14)"
				( attribute "CDS_PHYS_NET_NAME" "M_H_DQS_DP<14>"
					( Origin gPackager )
				)
				( attribute "PNN" "M_H_DQS_DP<14>"
					( Origin gPackager )
				)
				( objectStatus "M_H_DQS_DP<14>" )
			)
			( signal "@baseboard_fab2_lib.baseboard_fab2(sch_1):m_h_dqs_dp(15)"
				( attribute "CDS_PHYS_NET_NAME" "M_H_DQS_DP<15>"
					( Origin gPackager )
				)
				( attribute "PNN" "M_H_DQS_DP<15>"
					( Origin gPackager )
				)
				( objectStatus "M_H_DQS_DP<15>" )
			)
			( signal "@baseboard_fab2_lib.baseboard_fab2(sch_1):m_h_dqs_dp(16)"
				( attribute "CDS_PHYS_NET_NAME" "M_H_DQS_DP<16>"
					( Origin gPackager )
				)
				( attribute "PNN" "M_H_DQS_DP<16>"
					( Origin gPackager )
				)
				( objectStatus "M_H_DQS_DP<16>" )
			)
			( signal "@baseboard_fab2_lib.baseboard_fab2(sch_1):m_h_dqs_dp(17)"
				( attribute "CDS_PHYS_NET_NAME" "M_H_DQS_DP<17>"
					( Origin gPackager )
				)
				( attribute "PNN" "M_H_DQS_DP<17>"
					( Origin gPackager )
				)
				( objectStatus "M_H_DQS_DP<17>" )
			)
			( signal "@baseboard_fab2_lib.baseboard_fab2(sch_1):m_h_ecc(0)"
				( attribute "CDS_PHYS_NET_NAME" "M_H_ECC<0>"
					( Origin gPackager )
				)
				( attribute "PNN" "M_H_ECC<0>"
					( Origin gPackager )
				)
				( objectStatus "M_H_ECC<0>" )
			)
			( signal "@baseboard_fab2_lib.baseboard_fab2(sch_1):m_h_ecc(1)"
				( attribute "CDS_PHYS_NET_NAME" "M_H_ECC<1>"
					( Origin gPackager )
				)
				( attribute "PNN" "M_H_ECC<1>"
					( Origin gPackager )
				)
				( objectStatus "M_H_ECC<1>" )
			)
			( signal "@baseboard_fab2_lib.baseboard_fab2(sch_1):m_h_ecc(2)"
				( attribute "CDS_PHYS_NET_NAME" "M_H_ECC<2>"
					( Origin gPackager )
				)
				( attribute "PNN" "M_H_ECC<2>"
					( Origin gPackager )
				)
				( objectStatus "M_H_ECC<2>" )
			)
			( signal "@baseboard_fab2_lib.baseboard_fab2(sch_1):m_h_ecc(3)"
				( attribute "CDS_PHYS_NET_NAME" "M_H_ECC<3>"
					( Origin gPackager )
				)
				( attribute "PNN" "M_H_ECC<3>"
					( Origin gPackager )
				)
				( objectStatus "M_H_ECC<3>" )
			)
			( signal "@baseboard_fab2_lib.baseboard_fab2(sch_1):m_h_ecc(4)"
				( attribute "CDS_PHYS_NET_NAME" "M_H_ECC<4>"
					( Origin gPackager )
				)
				( attribute "PNN" "M_H_ECC<4>"
					( Origin gPackager )
				)
				( objectStatus "M_H_ECC<4>" )
			)
			( signal "@baseboard_fab2_lib.baseboard_fab2(sch_1):m_h_ecc(5)"
				( attribute "CDS_PHYS_NET_NAME" "M_H_ECC<5>"
					( Origin gPackager )
				)
				( attribute "PNN" "M_H_ECC<5>"
					( Origin gPackager )
				)
				( objectStatus "M_H_ECC<5>" )
			)
			( signal "@baseboard_fab2_lib.baseboard_fab2(sch_1):m_h_ecc(6)"
				( attribute "CDS_PHYS_NET_NAME" "M_H_ECC<6>"
					( Origin gPackager )
				)
				( attribute "PNN" "M_H_ECC<6>"
					( Origin gPackager )
				)
				( objectStatus "M_H_ECC<6>" )
			)
			( signal "@baseboard_fab2_lib.baseboard_fab2(sch_1):m_h_ecc(7)"
				( attribute "CDS_PHYS_NET_NAME" "M_H_ECC<7>"
					( Origin gPackager )
				)
				( attribute "PNN" "M_H_ECC<7>"
					( Origin gPackager )
				)
				( objectStatus "M_H_ECC<7>" )
			)
			( signal "@baseboard_fab2_lib.baseboard_fab2(sch_1):m_h_ma(0)"
				( attribute "CDS_PHYS_NET_NAME" "M_H_MA<0>"
					( Origin gPackager )
				)
				( attribute "PNN" "M_H_MA<0>"
					( Origin gPackager )
				)
				( objectStatus "M_H_MA<0>" )
			)
			( signal "@baseboard_fab2_lib.baseboard_fab2(sch_1):m_h_ma(1)"
				( attribute "CDS_PHYS_NET_NAME" "M_H_MA<1>"
					( Origin gPackager )
				)
				( attribute "PNN" "M_H_MA<1>"
					( Origin gPackager )
				)
				( objectStatus "M_H_MA<1>" )
			)
			( signal "@baseboard_fab2_lib.baseboard_fab2(sch_1):m_h_ma(2)"
				( attribute "CDS_PHYS_NET_NAME" "M_H_MA<2>"
					( Origin gPackager )
				)
				( attribute "PNN" "M_H_MA<2>"
					( Origin gPackager )
				)
				( objectStatus "M_H_MA<2>" )
			)
			( signal "@baseboard_fab2_lib.baseboard_fab2(sch_1):m_h_ma(3)"
				( attribute "CDS_PHYS_NET_NAME" "M_H_MA<3>"
					( Origin gPackager )
				)
				( attribute "PNN" "M_H_MA<3>"
					( Origin gPackager )
				)
				( objectStatus "M_H_MA<3>" )
			)
			( signal "@baseboard_fab2_lib.baseboard_fab2(sch_1):m_h_ma(4)"
				( attribute "CDS_PHYS_NET_NAME" "M_H_MA<4>"
					( Origin gPackager )
				)
				( attribute "PNN" "M_H_MA<4>"
					( Origin gPackager )
				)
				( objectStatus "M_H_MA<4>" )
			)
			( signal "@baseboard_fab2_lib.baseboard_fab2(sch_1):m_h_ma(5)"
				( attribute "CDS_PHYS_NET_NAME" "M_H_MA<5>"
					( Origin gPackager )
				)
				( attribute "PNN" "M_H_MA<5>"
					( Origin gPackager )
				)
				( objectStatus "M_H_MA<5>" )
			)
			( signal "@baseboard_fab2_lib.baseboard_fab2(sch_1):m_h_ma(6)"
				( attribute "CDS_PHYS_NET_NAME" "M_H_MA<6>"
					( Origin gPackager )
				)
				( attribute "PNN" "M_H_MA<6>"
					( Origin gPackager )
				)
				( objectStatus "M_H_MA<6>" )
			)
			( signal "@baseboard_fab2_lib.baseboard_fab2(sch_1):m_h_ma(7)"
				( attribute "CDS_PHYS_NET_NAME" "M_H_MA<7>"
					( Origin gPackager )
				)
				( attribute "PNN" "M_H_MA<7>"
					( Origin gPackager )
				)
				( objectStatus "M_H_MA<7>" )
			)
			( signal "@baseboard_fab2_lib.baseboard_fab2(sch_1):m_h_ma(8)"
				( attribute "CDS_PHYS_NET_NAME" "M_H_MA<8>"
					( Origin gPackager )
				)
				( attribute "PNN" "M_H_MA<8>"
					( Origin gPackager )
				)
				( objectStatus "M_H_MA<8>" )
			)
			( signal "@baseboard_fab2_lib.baseboard_fab2(sch_1):m_h_ma(9)"
				( attribute "CDS_PHYS_NET_NAME" "M_H_MA<9>"
					( Origin gPackager )
				)
				( attribute "PNN" "M_H_MA<9>"
					( Origin gPackager )
				)
				( objectStatus "M_H_MA<9>" )
			)
			( signal "@baseboard_fab2_lib.baseboard_fab2(sch_1):m_h_ma(10)"
				( attribute "CDS_PHYS_NET_NAME" "M_H_MA<10>"
					( Origin gPackager )
				)
				( attribute "PNN" "M_H_MA<10>"
					( Origin gPackager )
				)
				( objectStatus "M_H_MA<10>" )
			)
			( signal "@baseboard_fab2_lib.baseboard_fab2(sch_1):m_h_ma(11)"
				( attribute "CDS_PHYS_NET_NAME" "M_H_MA<11>"
					( Origin gPackager )
				)
				( attribute "PNN" "M_H_MA<11>"
					( Origin gPackager )
				)
				( objectStatus "M_H_MA<11>" )
			)
			( signal "@baseboard_fab2_lib.baseboard_fab2(sch_1):m_h_ma(12)"
				( attribute "CDS_PHYS_NET_NAME" "M_H_MA<12>"
					( Origin gPackager )
				)
				( attribute "PNN" "M_H_MA<12>"
					( Origin gPackager )
				)
				( objectStatus "M_H_MA<12>" )
			)
			( signal "@baseboard_fab2_lib.baseboard_fab2(sch_1):m_h_ma(13)"
				( attribute "CDS_PHYS_NET_NAME" "M_H_MA<13>"
					( Origin gPackager )
				)
				( attribute "PNN" "M_H_MA<13>"
					( Origin gPackager )
				)
				( objectStatus "M_H_MA<13>" )
			)
			( signal "@baseboard_fab2_lib.baseboard_fab2(sch_1):m_h_ma(14)"
				( attribute "CDS_PHYS_NET_NAME" "M_H_MA<14>"
					( Origin gPackager )
				)
				( attribute "PNN" "M_H_MA<14>"
					( Origin gPackager )
				)
				( objectStatus "M_H_MA<14>" )
			)
			( signal "@baseboard_fab2_lib.baseboard_fab2(sch_1):m_h_ma(15)"
				( attribute "CDS_PHYS_NET_NAME" "M_H_MA<15>"
					( Origin gPackager )
				)
				( attribute "PNN" "M_H_MA<15>"
					( Origin gPackager )
				)
				( objectStatus "M_H_MA<15>" )
			)
			( signal "@baseboard_fab2_lib.baseboard_fab2(sch_1):m_h_ma(16)"
				( attribute "CDS_PHYS_NET_NAME" "M_H_MA<16>"
					( Origin gPackager )
				)
				( attribute "PNN" "M_H_MA<16>"
					( Origin gPackager )
				)
				( objectStatus "M_H_MA<16>" )
			)
			( signal "@baseboard_fab2_lib.baseboard_fab2(sch_1):m_h_ma(17)"
				( attribute "CDS_PHYS_NET_NAME" "M_H_MA<17>"
					( Origin gPackager )
				)
				( attribute "PNN" "M_H_MA<17>"
					( Origin gPackager )
				)
				( objectStatus "M_H_MA<17>" )
			)
			( signal "@baseboard_fab2_lib.baseboard_fab2(sch_1):m_h_odt(0)"
				( attribute "CDS_PHYS_NET_NAME" "M_H_ODT<0>"
					( Origin gPackager )
				)
				( attribute "PNN" "M_H_ODT<0>"
					( Origin gPackager )
				)
				( objectStatus "M_H_ODT<0>" )
			)
			( signal "@baseboard_fab2_lib.baseboard_fab2(sch_1):m_h_odt(1)"
				( attribute "CDS_PHYS_NET_NAME" "M_H_ODT<1>"
					( Origin gPackager )
				)
				( attribute "PNN" "M_H_ODT<1>"
					( Origin gPackager )
				)
				( objectStatus "M_H_ODT<1>" )
			)
			( signal "@baseboard_fab2_lib.baseboard_fab2(sch_1):m_h_odt(2)"
				( attribute "CDS_PHYS_NET_NAME" "M_H_ODT<2>"
					( Origin gPackager )
				)
				( attribute "PNN" "M_H_ODT<2>"
					( Origin gPackager )
				)
				( objectStatus "M_H_ODT<2>" )
			)
			( signal "@baseboard_fab2_lib.baseboard_fab2(sch_1):m_h_odt(3)"
				( attribute "CDS_PHYS_NET_NAME" "M_H_ODT<3>"
					( Origin gPackager )
				)
				( attribute "PNN" "M_H_ODT<3>"
					( Origin gPackager )
				)
				( objectStatus "M_H_ODT<3>" )
			)
			( signal "@baseboard_fab2_lib.baseboard_fab2(sch_1):m_h_par"
				( attribute "CDS_PHYS_NET_NAME" "M_H_PAR"
					( Origin gPackager )
				)
				( objectStatus "M_H_PAR" )
			)
			( signal "@baseboard_fab2_lib.baseboard_fab2(sch_1):m_j_act_n"
				( attribute "CDS_PHYS_NET_NAME" "M_J_ACT_N"
					( Origin gPackager )
				)
				( objectStatus "M_J_ACT_N" )
			)
			( signal "@baseboard_fab2_lib.baseboard_fab2(sch_1):m_j_alert_n"
				( attribute "CDS_PHYS_NET_NAME" "M_J_ALERT_N"
					( Origin gPackager )
				)
				( objectStatus "M_J_ALERT_N" )
			)
			( signal "@baseboard_fab2_lib.baseboard_fab2(sch_1):m_j_ba(0)"
				( attribute "CDS_PHYS_NET_NAME" "M_J_BA<0>"
					( Origin gPackager )
				)
				( attribute "PNN" "M_J_BA<0>"
					( Origin gPackager )
				)
				( objectStatus "M_J_BA<0>" )
			)
			( signal "@baseboard_fab2_lib.baseboard_fab2(sch_1):m_j_ba(1)"
				( attribute "CDS_PHYS_NET_NAME" "M_J_BA<1>"
					( Origin gPackager )
				)
				( attribute "PNN" "M_J_BA<1>"
					( Origin gPackager )
				)
				( objectStatus "M_J_BA<1>" )
			)
			( signal "@baseboard_fab2_lib.baseboard_fab2(sch_1):m_j_bg(0)"
				( attribute "CDS_PHYS_NET_NAME" "M_J_BG<0>"
					( Origin gPackager )
				)
				( attribute "PNN" "M_J_BG<0>"
					( Origin gPackager )
				)
				( objectStatus "M_J_BG<0>" )
			)
			( signal "@baseboard_fab2_lib.baseboard_fab2(sch_1):m_j_bg(1)"
				( attribute "CDS_PHYS_NET_NAME" "M_J_BG<1>"
					( Origin gPackager )
				)
				( attribute "PNN" "M_J_BG<1>"
					( Origin gPackager )
				)
				( objectStatus "M_J_BG<1>" )
			)
			( signal "@baseboard_fab2_lib.baseboard_fab2(sch_1):m_j_c(2)"
				( attribute "CDS_PHYS_NET_NAME" "M_J_C<2>"
					( Origin gPackager )
				)
				( attribute "PNN" "M_J_C<2>"
					( Origin gPackager )
				)
				( objectStatus "M_J_C<2>" )
			)
			( signal "@baseboard_fab2_lib.baseboard_fab2(sch_1):m_j_cke(0)"
				( attribute "CDS_PHYS_NET_NAME" "M_J_CKE<0>"
					( Origin gPackager )
				)
				( attribute "PNN" "M_J_CKE<0>"
					( Origin gPackager )
				)
				( objectStatus "M_J_CKE<0>" )
			)
			( signal "@baseboard_fab2_lib.baseboard_fab2(sch_1):m_j_cke(1)"
				( attribute "CDS_PHYS_NET_NAME" "M_J_CKE<1>"
					( Origin gPackager )
				)
				( attribute "PNN" "M_J_CKE<1>"
					( Origin gPackager )
				)
				( objectStatus "M_J_CKE<1>" )
			)
			( signal "@baseboard_fab2_lib.baseboard_fab2(sch_1):m_j_cke(2)"
				( attribute "CDS_PHYS_NET_NAME" "M_J_CKE<2>"
					( Origin gPackager )
				)
				( attribute "PNN" "M_J_CKE<2>"
					( Origin gPackager )
				)
				( objectStatus "M_J_CKE<2>" )
			)
			( signal "@baseboard_fab2_lib.baseboard_fab2(sch_1):m_j_cke(3)"
				( attribute "CDS_PHYS_NET_NAME" "M_J_CKE<3>"
					( Origin gPackager )
				)
				( attribute "PNN" "M_J_CKE<3>"
					( Origin gPackager )
				)
				( objectStatus "M_J_CKE<3>" )
			)
			( signal "@baseboard_fab2_lib.baseboard_fab2(sch_1):m_j_clk_dn(0)"
				( attribute "CDS_PHYS_NET_NAME" "M_J_CLK_DN<0>"
					( Origin gPackager )
				)
				( attribute "PNN" "M_J_CLK_DN<0>"
					( Origin gPackager )
				)
				( objectStatus "M_J_CLK_DN<0>" )
			)
			( signal "@baseboard_fab2_lib.baseboard_fab2(sch_1):m_j_clk_dn(1)"
				( attribute "CDS_PHYS_NET_NAME" "M_J_CLK_DN<1>"
					( Origin gPackager )
				)
				( attribute "PNN" "M_J_CLK_DN<1>"
					( Origin gPackager )
				)
				( objectStatus "M_J_CLK_DN<1>" )
			)
			( signal "@baseboard_fab2_lib.baseboard_fab2(sch_1):m_j_clk_dn(2)"
				( attribute "CDS_PHYS_NET_NAME" "M_J_CLK_DN<2>"
					( Origin gPackager )
				)
				( attribute "PNN" "M_J_CLK_DN<2>"
					( Origin gPackager )
				)
				( objectStatus "M_J_CLK_DN<2>" )
			)
			( signal "@baseboard_fab2_lib.baseboard_fab2(sch_1):m_j_clk_dn(3)"
				( attribute "CDS_PHYS_NET_NAME" "M_J_CLK_DN<3>"
					( Origin gPackager )
				)
				( attribute "PNN" "M_J_CLK_DN<3>"
					( Origin gPackager )
				)
				( objectStatus "M_J_CLK_DN<3>" )
			)
			( signal "@baseboard_fab2_lib.baseboard_fab2(sch_1):m_j_clk_dp(0)"
				( attribute "CDS_PHYS_NET_NAME" "M_J_CLK_DP<0>"
					( Origin gPackager )
				)
				( attribute "PNN" "M_J_CLK_DP<0>"
					( Origin gPackager )
				)
				( objectStatus "M_J_CLK_DP<0>" )
			)
			( signal "@baseboard_fab2_lib.baseboard_fab2(sch_1):m_j_clk_dp(1)"
				( attribute "CDS_PHYS_NET_NAME" "M_J_CLK_DP<1>"
					( Origin gPackager )
				)
				( attribute "PNN" "M_J_CLK_DP<1>"
					( Origin gPackager )
				)
				( objectStatus "M_J_CLK_DP<1>" )
			)
			( signal "@baseboard_fab2_lib.baseboard_fab2(sch_1):m_j_clk_dp(2)"
				( attribute "CDS_PHYS_NET_NAME" "M_J_CLK_DP<2>"
					( Origin gPackager )
				)
				( attribute "PNN" "M_J_CLK_DP<2>"
					( Origin gPackager )
				)
				( objectStatus "M_J_CLK_DP<2>" )
			)
			( signal "@baseboard_fab2_lib.baseboard_fab2(sch_1):m_j_clk_dp(3)"
				( attribute "CDS_PHYS_NET_NAME" "M_J_CLK_DP<3>"
					( Origin gPackager )
				)
				( attribute "PNN" "M_J_CLK_DP<3>"
					( Origin gPackager )
				)
				( objectStatus "M_J_CLK_DP<3>" )
			)
			( signal "@baseboard_fab2_lib.baseboard_fab2(sch_1):m_j_cs_n(0)"
				( attribute "CDS_PHYS_NET_NAME" "M_J_CS_N<0>"
					( Origin gPackager )
				)
				( attribute "PNN" "M_J_CS_N<0>"
					( Origin gPackager )
				)
				( objectStatus "M_J_CS_N<0>" )
			)
			( signal "@baseboard_fab2_lib.baseboard_fab2(sch_1):m_j_cs_n(1)"
				( attribute "CDS_PHYS_NET_NAME" "M_J_CS_N<1>"
					( Origin gPackager )
				)
				( attribute "PNN" "M_J_CS_N<1>"
					( Origin gPackager )
				)
				( objectStatus "M_J_CS_N<1>" )
			)
			( signal "@baseboard_fab2_lib.baseboard_fab2(sch_1):m_j_cs_n(2)"
				( attribute "CDS_PHYS_NET_NAME" "M_J_CS_N<2>"
					( Origin gPackager )
				)
				( attribute "PNN" "M_J_CS_N<2>"
					( Origin gPackager )
				)
				( objectStatus "M_J_CS_N<2>" )
			)
			( signal "@baseboard_fab2_lib.baseboard_fab2(sch_1):m_j_cs_n(3)"
				( attribute "CDS_PHYS_NET_NAME" "M_J_CS_N<3>"
					( Origin gPackager )
				)
				( attribute "PNN" "M_J_CS_N<3>"
					( Origin gPackager )
				)
				( objectStatus "M_J_CS_N<3>" )
			)
			( signal "@baseboard_fab2_lib.baseboard_fab2(sch_1):m_j_cs_n(4)"
				( attribute "CDS_PHYS_NET_NAME" "M_J_CS_N<4>"
					( Origin gPackager )
				)
				( attribute "PNN" "M_J_CS_N<4>"
					( Origin gPackager )
				)
				( objectStatus "M_J_CS_N<4>" )
			)
			( signal "@baseboard_fab2_lib.baseboard_fab2(sch_1):m_j_cs_n(5)"
				( attribute "CDS_PHYS_NET_NAME" "M_J_CS_N<5>"
					( Origin gPackager )
				)
				( attribute "PNN" "M_J_CS_N<5>"
					( Origin gPackager )
				)
				( objectStatus "M_J_CS_N<5>" )
			)
			( signal "@baseboard_fab2_lib.baseboard_fab2(sch_1):m_j_cs_n(6)"
				( attribute "CDS_PHYS_NET_NAME" "M_J_CS_N<6>"
					( Origin gPackager )
				)
				( attribute "PNN" "M_J_CS_N<6>"
					( Origin gPackager )
				)
				( objectStatus "M_J_CS_N<6>" )
			)
			( signal "@baseboard_fab2_lib.baseboard_fab2(sch_1):m_j_cs_n(7)"
				( attribute "CDS_PHYS_NET_NAME" "M_J_CS_N<7>"
					( Origin gPackager )
				)
				( attribute "PNN" "M_J_CS_N<7>"
					( Origin gPackager )
				)
				( objectStatus "M_J_CS_N<7>" )
			)
			( signal "@baseboard_fab2_lib.baseboard_fab2(sch_1):m_j_dq(0)"
				( attribute "CDS_PHYS_NET_NAME" "M_J_DQ<0>"
					( Origin gPackager )
				)
				( attribute "PNN" "M_J_DQ<0>"
					( Origin gPackager )
				)
				( objectStatus "M_J_DQ<0>" )
			)
			( signal "@baseboard_fab2_lib.baseboard_fab2(sch_1):m_j_dq(1)"
				( attribute "CDS_PHYS_NET_NAME" "M_J_DQ<1>"
					( Origin gPackager )
				)
				( attribute "PNN" "M_J_DQ<1>"
					( Origin gPackager )
				)
				( objectStatus "M_J_DQ<1>" )
			)
			( signal "@baseboard_fab2_lib.baseboard_fab2(sch_1):m_j_dq(2)"
				( attribute "CDS_PHYS_NET_NAME" "M_J_DQ<2>"
					( Origin gPackager )
				)
				( attribute "PNN" "M_J_DQ<2>"
					( Origin gPackager )
				)
				( objectStatus "M_J_DQ<2>" )
			)
			( signal "@baseboard_fab2_lib.baseboard_fab2(sch_1):m_j_dq(3)"
				( attribute "CDS_PHYS_NET_NAME" "M_J_DQ<3>"
					( Origin gPackager )
				)
				( attribute "PNN" "M_J_DQ<3>"
					( Origin gPackager )
				)
				( objectStatus "M_J_DQ<3>" )
			)
			( signal "@baseboard_fab2_lib.baseboard_fab2(sch_1):m_j_dq(4)"
				( attribute "CDS_PHYS_NET_NAME" "M_J_DQ<4>"
					( Origin gPackager )
				)
				( attribute "PNN" "M_J_DQ<4>"
					( Origin gPackager )
				)
				( objectStatus "M_J_DQ<4>" )
			)
			( signal "@baseboard_fab2_lib.baseboard_fab2(sch_1):m_j_dq(5)"
				( attribute "CDS_PHYS_NET_NAME" "M_J_DQ<5>"
					( Origin gPackager )
				)
				( attribute "PNN" "M_J_DQ<5>"
					( Origin gPackager )
				)
				( objectStatus "M_J_DQ<5>" )
			)
			( signal "@baseboard_fab2_lib.baseboard_fab2(sch_1):m_j_dq(6)"
				( attribute "CDS_PHYS_NET_NAME" "M_J_DQ<6>"
					( Origin gPackager )
				)
				( attribute "PNN" "M_J_DQ<6>"
					( Origin gPackager )
				)
				( objectStatus "M_J_DQ<6>" )
			)
			( signal "@baseboard_fab2_lib.baseboard_fab2(sch_1):m_j_dq(7)"
				( attribute "CDS_PHYS_NET_NAME" "M_J_DQ<7>"
					( Origin gPackager )
				)
				( attribute "PNN" "M_J_DQ<7>"
					( Origin gPackager )
				)
				( objectStatus "M_J_DQ<7>" )
			)
			( signal "@baseboard_fab2_lib.baseboard_fab2(sch_1):m_j_dq(8)"
				( attribute "CDS_PHYS_NET_NAME" "M_J_DQ<8>"
					( Origin gPackager )
				)
				( attribute "PNN" "M_J_DQ<8>"
					( Origin gPackager )
				)
				( objectStatus "M_J_DQ<8>" )
			)
			( signal "@baseboard_fab2_lib.baseboard_fab2(sch_1):m_j_dq(9)"
				( attribute "CDS_PHYS_NET_NAME" "M_J_DQ<9>"
					( Origin gPackager )
				)
				( attribute "PNN" "M_J_DQ<9>"
					( Origin gPackager )
				)
				( objectStatus "M_J_DQ<9>" )
			)
			( signal "@baseboard_fab2_lib.baseboard_fab2(sch_1):m_j_dq(10)"
				( attribute "CDS_PHYS_NET_NAME" "M_J_DQ<10>"
					( Origin gPackager )
				)
				( attribute "PNN" "M_J_DQ<10>"
					( Origin gPackager )
				)
				( objectStatus "M_J_DQ<10>" )
			)
			( signal "@baseboard_fab2_lib.baseboard_fab2(sch_1):m_j_dq(11)"
				( attribute "CDS_PHYS_NET_NAME" "M_J_DQ<11>"
					( Origin gPackager )
				)
				( attribute "PNN" "M_J_DQ<11>"
					( Origin gPackager )
				)
				( objectStatus "M_J_DQ<11>" )
			)
			( signal "@baseboard_fab2_lib.baseboard_fab2(sch_1):m_j_dq(12)"
				( attribute "CDS_PHYS_NET_NAME" "M_J_DQ<12>"
					( Origin gPackager )
				)
				( attribute "PNN" "M_J_DQ<12>"
					( Origin gPackager )
				)
				( objectStatus "M_J_DQ<12>" )
			)
			( signal "@baseboard_fab2_lib.baseboard_fab2(sch_1):m_j_dq(13)"
				( attribute "CDS_PHYS_NET_NAME" "M_J_DQ<13>"
					( Origin gPackager )
				)
				( attribute "PNN" "M_J_DQ<13>"
					( Origin gPackager )
				)
				( objectStatus "M_J_DQ<13>" )
			)
			( signal "@baseboard_fab2_lib.baseboard_fab2(sch_1):m_j_dq(14)"
				( attribute "CDS_PHYS_NET_NAME" "M_J_DQ<14>"
					( Origin gPackager )
				)
				( attribute "PNN" "M_J_DQ<14>"
					( Origin gPackager )
				)
				( objectStatus "M_J_DQ<14>" )
			)
			( signal "@baseboard_fab2_lib.baseboard_fab2(sch_1):m_j_dq(15)"
				( attribute "CDS_PHYS_NET_NAME" "M_J_DQ<15>"
					( Origin gPackager )
				)
				( attribute "PNN" "M_J_DQ<15>"
					( Origin gPackager )
				)
				( objectStatus "M_J_DQ<15>" )
			)
			( signal "@baseboard_fab2_lib.baseboard_fab2(sch_1):m_j_dq(16)"
				( attribute "CDS_PHYS_NET_NAME" "M_J_DQ<16>"
					( Origin gPackager )
				)
				( attribute "PNN" "M_J_DQ<16>"
					( Origin gPackager )
				)
				( objectStatus "M_J_DQ<16>" )
			)
			( signal "@baseboard_fab2_lib.baseboard_fab2(sch_1):m_j_dq(17)"
				( attribute "CDS_PHYS_NET_NAME" "M_J_DQ<17>"
					( Origin gPackager )
				)
				( attribute "PNN" "M_J_DQ<17>"
					( Origin gPackager )
				)
				( objectStatus "M_J_DQ<17>" )
			)
			( signal "@baseboard_fab2_lib.baseboard_fab2(sch_1):m_j_dq(18)"
				( attribute "CDS_PHYS_NET_NAME" "M_J_DQ<18>"
					( Origin gPackager )
				)
				( attribute "PNN" "M_J_DQ<18>"
					( Origin gPackager )
				)
				( objectStatus "M_J_DQ<18>" )
			)
			( signal "@baseboard_fab2_lib.baseboard_fab2(sch_1):m_j_dq(19)"
				( attribute "CDS_PHYS_NET_NAME" "M_J_DQ<19>"
					( Origin gPackager )
				)
				( attribute "PNN" "M_J_DQ<19>"
					( Origin gPackager )
				)
				( objectStatus "M_J_DQ<19>" )
			)
			( signal "@baseboard_fab2_lib.baseboard_fab2(sch_1):m_j_dq(20)"
				( attribute "CDS_PHYS_NET_NAME" "M_J_DQ<20>"
					( Origin gPackager )
				)
				( attribute "PNN" "M_J_DQ<20>"
					( Origin gPackager )
				)
				( objectStatus "M_J_DQ<20>" )
			)
			( signal "@baseboard_fab2_lib.baseboard_fab2(sch_1):m_j_dq(21)"
				( attribute "CDS_PHYS_NET_NAME" "M_J_DQ<21>"
					( Origin gPackager )
				)
				( attribute "PNN" "M_J_DQ<21>"
					( Origin gPackager )
				)
				( objectStatus "M_J_DQ<21>" )
			)
			( signal "@baseboard_fab2_lib.baseboard_fab2(sch_1):m_j_dq(22)"
				( attribute "CDS_PHYS_NET_NAME" "M_J_DQ<22>"
					( Origin gPackager )
				)
				( attribute "PNN" "M_J_DQ<22>"
					( Origin gPackager )
				)
				( objectStatus "M_J_DQ<22>" )
			)
			( signal "@baseboard_fab2_lib.baseboard_fab2(sch_1):m_j_dq(23)"
				( attribute "CDS_PHYS_NET_NAME" "M_J_DQ<23>"
					( Origin gPackager )
				)
				( attribute "PNN" "M_J_DQ<23>"
					( Origin gPackager )
				)
				( objectStatus "M_J_DQ<23>" )
			)
			( signal "@baseboard_fab2_lib.baseboard_fab2(sch_1):m_j_dq(24)"
				( attribute "CDS_PHYS_NET_NAME" "M_J_DQ<24>"
					( Origin gPackager )
				)
				( attribute "PNN" "M_J_DQ<24>"
					( Origin gPackager )
				)
				( objectStatus "M_J_DQ<24>" )
			)
			( signal "@baseboard_fab2_lib.baseboard_fab2(sch_1):m_j_dq(25)"
				( attribute "CDS_PHYS_NET_NAME" "M_J_DQ<25>"
					( Origin gPackager )
				)
				( attribute "PNN" "M_J_DQ<25>"
					( Origin gPackager )
				)
				( objectStatus "M_J_DQ<25>" )
			)
			( signal "@baseboard_fab2_lib.baseboard_fab2(sch_1):m_j_dq(26)"
				( attribute "CDS_PHYS_NET_NAME" "M_J_DQ<26>"
					( Origin gPackager )
				)
				( attribute "PNN" "M_J_DQ<26>"
					( Origin gPackager )
				)
				( objectStatus "M_J_DQ<26>" )
			)
			( signal "@baseboard_fab2_lib.baseboard_fab2(sch_1):m_j_dq(27)"
				( attribute "CDS_PHYS_NET_NAME" "M_J_DQ<27>"
					( Origin gPackager )
				)
				( attribute "PNN" "M_J_DQ<27>"
					( Origin gPackager )
				)
				( objectStatus "M_J_DQ<27>" )
			)
			( signal "@baseboard_fab2_lib.baseboard_fab2(sch_1):m_j_dq(28)"
				( attribute "CDS_PHYS_NET_NAME" "M_J_DQ<28>"
					( Origin gPackager )
				)
				( attribute "PNN" "M_J_DQ<28>"
					( Origin gPackager )
				)
				( objectStatus "M_J_DQ<28>" )
			)
			( signal "@baseboard_fab2_lib.baseboard_fab2(sch_1):m_j_dq(29)"
				( attribute "CDS_PHYS_NET_NAME" "M_J_DQ<29>"
					( Origin gPackager )
				)
				( attribute "PNN" "M_J_DQ<29>"
					( Origin gPackager )
				)
				( objectStatus "M_J_DQ<29>" )
			)
			( signal "@baseboard_fab2_lib.baseboard_fab2(sch_1):m_j_dq(30)"
				( attribute "CDS_PHYS_NET_NAME" "M_J_DQ<30>"
					( Origin gPackager )
				)
				( attribute "PNN" "M_J_DQ<30>"
					( Origin gPackager )
				)
				( objectStatus "M_J_DQ<30>" )
			)
			( signal "@baseboard_fab2_lib.baseboard_fab2(sch_1):m_j_dq(31)"
				( attribute "CDS_PHYS_NET_NAME" "M_J_DQ<31>"
					( Origin gPackager )
				)
				( attribute "PNN" "M_J_DQ<31>"
					( Origin gPackager )
				)
				( objectStatus "M_J_DQ<31>" )
			)
			( signal "@baseboard_fab2_lib.baseboard_fab2(sch_1):m_j_dq(32)"
				( attribute "CDS_PHYS_NET_NAME" "M_J_DQ<32>"
					( Origin gPackager )
				)
				( attribute "PNN" "M_J_DQ<32>"
					( Origin gPackager )
				)
				( objectStatus "M_J_DQ<32>" )
			)
			( signal "@baseboard_fab2_lib.baseboard_fab2(sch_1):m_j_dq(33)"
				( attribute "CDS_PHYS_NET_NAME" "M_J_DQ<33>"
					( Origin gPackager )
				)
				( attribute "PNN" "M_J_DQ<33>"
					( Origin gPackager )
				)
				( objectStatus "M_J_DQ<33>" )
			)
			( signal "@baseboard_fab2_lib.baseboard_fab2(sch_1):m_j_dq(34)"
				( attribute "CDS_PHYS_NET_NAME" "M_J_DQ<34>"
					( Origin gPackager )
				)
				( attribute "PNN" "M_J_DQ<34>"
					( Origin gPackager )
				)
				( objectStatus "M_J_DQ<34>" )
			)
			( signal "@baseboard_fab2_lib.baseboard_fab2(sch_1):m_j_dq(35)"
				( attribute "CDS_PHYS_NET_NAME" "M_J_DQ<35>"
					( Origin gPackager )
				)
				( attribute "PNN" "M_J_DQ<35>"
					( Origin gPackager )
				)
				( objectStatus "M_J_DQ<35>" )
			)
			( signal "@baseboard_fab2_lib.baseboard_fab2(sch_1):m_j_dq(36)"
				( attribute "CDS_PHYS_NET_NAME" "M_J_DQ<36>"
					( Origin gPackager )
				)
				( attribute "PNN" "M_J_DQ<36>"
					( Origin gPackager )
				)
				( objectStatus "M_J_DQ<36>" )
			)
			( signal "@baseboard_fab2_lib.baseboard_fab2(sch_1):m_j_dq(37)"
				( attribute "CDS_PHYS_NET_NAME" "M_J_DQ<37>"
					( Origin gPackager )
				)
				( attribute "PNN" "M_J_DQ<37>"
					( Origin gPackager )
				)
				( objectStatus "M_J_DQ<37>" )
			)
			( signal "@baseboard_fab2_lib.baseboard_fab2(sch_1):m_j_dq(38)"
				( attribute "CDS_PHYS_NET_NAME" "M_J_DQ<38>"
					( Origin gPackager )
				)
				( attribute "PNN" "M_J_DQ<38>"
					( Origin gPackager )
				)
				( objectStatus "M_J_DQ<38>" )
			)
			( signal "@baseboard_fab2_lib.baseboard_fab2(sch_1):m_j_dq(39)"
				( attribute "CDS_PHYS_NET_NAME" "M_J_DQ<39>"
					( Origin gPackager )
				)
				( attribute "PNN" "M_J_DQ<39>"
					( Origin gPackager )
				)
				( objectStatus "M_J_DQ<39>" )
			)
			( signal "@baseboard_fab2_lib.baseboard_fab2(sch_1):m_j_dq(40)"
				( attribute "CDS_PHYS_NET_NAME" "M_J_DQ<40>"
					( Origin gPackager )
				)
				( attribute "PNN" "M_J_DQ<40>"
					( Origin gPackager )
				)
				( objectStatus "M_J_DQ<40>" )
			)
			( signal "@baseboard_fab2_lib.baseboard_fab2(sch_1):m_j_dq(41)"
				( attribute "CDS_PHYS_NET_NAME" "M_J_DQ<41>"
					( Origin gPackager )
				)
				( attribute "PNN" "M_J_DQ<41>"
					( Origin gPackager )
				)
				( objectStatus "M_J_DQ<41>" )
			)
			( signal "@baseboard_fab2_lib.baseboard_fab2(sch_1):m_j_dq(42)"
				( attribute "CDS_PHYS_NET_NAME" "M_J_DQ<42>"
					( Origin gPackager )
				)
				( attribute "PNN" "M_J_DQ<42>"
					( Origin gPackager )
				)
				( objectStatus "M_J_DQ<42>" )
			)
			( signal "@baseboard_fab2_lib.baseboard_fab2(sch_1):m_j_dq(43)"
				( attribute "CDS_PHYS_NET_NAME" "M_J_DQ<43>"
					( Origin gPackager )
				)
				( attribute "PNN" "M_J_DQ<43>"
					( Origin gPackager )
				)
				( objectStatus "M_J_DQ<43>" )
			)
			( signal "@baseboard_fab2_lib.baseboard_fab2(sch_1):m_j_dq(44)"
				( attribute "CDS_PHYS_NET_NAME" "M_J_DQ<44>"
					( Origin gPackager )
				)
				( attribute "PNN" "M_J_DQ<44>"
					( Origin gPackager )
				)
				( objectStatus "M_J_DQ<44>" )
			)
			( signal "@baseboard_fab2_lib.baseboard_fab2(sch_1):m_j_dq(45)"
				( attribute "CDS_PHYS_NET_NAME" "M_J_DQ<45>"
					( Origin gPackager )
				)
				( attribute "PNN" "M_J_DQ<45>"
					( Origin gPackager )
				)
				( objectStatus "M_J_DQ<45>" )
			)
			( signal "@baseboard_fab2_lib.baseboard_fab2(sch_1):m_j_dq(46)"
				( attribute "CDS_PHYS_NET_NAME" "M_J_DQ<46>"
					( Origin gPackager )
				)
				( attribute "PNN" "M_J_DQ<46>"
					( Origin gPackager )
				)
				( objectStatus "M_J_DQ<46>" )
			)
			( signal "@baseboard_fab2_lib.baseboard_fab2(sch_1):m_j_dq(47)"
				( attribute "CDS_PHYS_NET_NAME" "M_J_DQ<47>"
					( Origin gPackager )
				)
				( attribute "PNN" "M_J_DQ<47>"
					( Origin gPackager )
				)
				( objectStatus "M_J_DQ<47>" )
			)
			( signal "@baseboard_fab2_lib.baseboard_fab2(sch_1):m_j_dq(48)"
				( attribute "CDS_PHYS_NET_NAME" "M_J_DQ<48>"
					( Origin gPackager )
				)
				( attribute "PNN" "M_J_DQ<48>"
					( Origin gPackager )
				)
				( objectStatus "M_J_DQ<48>" )
			)
			( signal "@baseboard_fab2_lib.baseboard_fab2(sch_1):m_j_dq(49)"
				( attribute "CDS_PHYS_NET_NAME" "M_J_DQ<49>"
					( Origin gPackager )
				)
				( attribute "PNN" "M_J_DQ<49>"
					( Origin gPackager )
				)
				( objectStatus "M_J_DQ<49>" )
			)
			( signal "@baseboard_fab2_lib.baseboard_fab2(sch_1):m_j_dq(50)"
				( attribute "CDS_PHYS_NET_NAME" "M_J_DQ<50>"
					( Origin gPackager )
				)
				( attribute "PNN" "M_J_DQ<50>"
					( Origin gPackager )
				)
				( objectStatus "M_J_DQ<50>" )
			)
			( signal "@baseboard_fab2_lib.baseboard_fab2(sch_1):m_j_dq(51)"
				( attribute "CDS_PHYS_NET_NAME" "M_J_DQ<51>"
					( Origin gPackager )
				)
				( attribute "PNN" "M_J_DQ<51>"
					( Origin gPackager )
				)
				( objectStatus "M_J_DQ<51>" )
			)
			( signal "@baseboard_fab2_lib.baseboard_fab2(sch_1):m_j_dq(52)"
				( attribute "CDS_PHYS_NET_NAME" "M_J_DQ<52>"
					( Origin gPackager )
				)
				( attribute "PNN" "M_J_DQ<52>"
					( Origin gPackager )
				)
				( objectStatus "M_J_DQ<52>" )
			)
			( signal "@baseboard_fab2_lib.baseboard_fab2(sch_1):m_j_dq(53)"
				( attribute "CDS_PHYS_NET_NAME" "M_J_DQ<53>"
					( Origin gPackager )
				)
				( attribute "PNN" "M_J_DQ<53>"
					( Origin gPackager )
				)
				( objectStatus "M_J_DQ<53>" )
			)
			( signal "@baseboard_fab2_lib.baseboard_fab2(sch_1):m_j_dq(54)"
				( attribute "CDS_PHYS_NET_NAME" "M_J_DQ<54>"
					( Origin gPackager )
				)
				( attribute "PNN" "M_J_DQ<54>"
					( Origin gPackager )
				)
				( objectStatus "M_J_DQ<54>" )
			)
			( signal "@baseboard_fab2_lib.baseboard_fab2(sch_1):m_j_dq(55)"
				( attribute "CDS_PHYS_NET_NAME" "M_J_DQ<55>"
					( Origin gPackager )
				)
				( attribute "PNN" "M_J_DQ<55>"
					( Origin gPackager )
				)
				( objectStatus "M_J_DQ<55>" )
			)
			( signal "@baseboard_fab2_lib.baseboard_fab2(sch_1):m_j_dq(56)"
				( attribute "CDS_PHYS_NET_NAME" "M_J_DQ<56>"
					( Origin gPackager )
				)
				( attribute "PNN" "M_J_DQ<56>"
					( Origin gPackager )
				)
				( objectStatus "M_J_DQ<56>" )
			)
			( signal "@baseboard_fab2_lib.baseboard_fab2(sch_1):m_j_dq(57)"
				( attribute "CDS_PHYS_NET_NAME" "M_J_DQ<57>"
					( Origin gPackager )
				)
				( attribute "PNN" "M_J_DQ<57>"
					( Origin gPackager )
				)
				( objectStatus "M_J_DQ<57>" )
			)
			( signal "@baseboard_fab2_lib.baseboard_fab2(sch_1):m_j_dq(58)"
				( attribute "CDS_PHYS_NET_NAME" "M_J_DQ<58>"
					( Origin gPackager )
				)
				( attribute "PNN" "M_J_DQ<58>"
					( Origin gPackager )
				)
				( objectStatus "M_J_DQ<58>" )
			)
			( signal "@baseboard_fab2_lib.baseboard_fab2(sch_1):m_j_dq(59)"
				( attribute "CDS_PHYS_NET_NAME" "M_J_DQ<59>"
					( Origin gPackager )
				)
				( attribute "PNN" "M_J_DQ<59>"
					( Origin gPackager )
				)
				( objectStatus "M_J_DQ<59>" )
			)
			( signal "@baseboard_fab2_lib.baseboard_fab2(sch_1):m_j_dq(60)"
				( attribute "CDS_PHYS_NET_NAME" "M_J_DQ<60>"
					( Origin gPackager )
				)
				( attribute "PNN" "M_J_DQ<60>"
					( Origin gPackager )
				)
				( objectStatus "M_J_DQ<60>" )
			)
			( signal "@baseboard_fab2_lib.baseboard_fab2(sch_1):m_j_dq(61)"
				( attribute "CDS_PHYS_NET_NAME" "M_J_DQ<61>"
					( Origin gPackager )
				)
				( attribute "PNN" "M_J_DQ<61>"
					( Origin gPackager )
				)
				( objectStatus "M_J_DQ<61>" )
			)
			( signal "@baseboard_fab2_lib.baseboard_fab2(sch_1):m_j_dq(62)"
				( attribute "CDS_PHYS_NET_NAME" "M_J_DQ<62>"
					( Origin gPackager )
				)
				( attribute "PNN" "M_J_DQ<62>"
					( Origin gPackager )
				)
				( objectStatus "M_J_DQ<62>" )
			)
			( signal "@baseboard_fab2_lib.baseboard_fab2(sch_1):m_j_dq(63)"
				( attribute "CDS_PHYS_NET_NAME" "M_J_DQ<63>"
					( Origin gPackager )
				)
				( attribute "PNN" "M_J_DQ<63>"
					( Origin gPackager )
				)
				( objectStatus "M_J_DQ<63>" )
			)
			( signal "@baseboard_fab2_lib.baseboard_fab2(sch_1):m_j_dqs_dn(0)"
				( attribute "CDS_PHYS_NET_NAME" "M_J_DQS_DN<0>"
					( Origin gPackager )
				)
				( attribute "PNN" "M_J_DQS_DN<0>"
					( Origin gPackager )
				)
				( objectStatus "M_J_DQS_DN<0>" )
			)
			( signal "@baseboard_fab2_lib.baseboard_fab2(sch_1):m_j_dqs_dn(1)"
				( attribute "CDS_PHYS_NET_NAME" "M_J_DQS_DN<1>"
					( Origin gPackager )
				)
				( attribute "PNN" "M_J_DQS_DN<1>"
					( Origin gPackager )
				)
				( objectStatus "M_J_DQS_DN<1>" )
			)
			( signal "@baseboard_fab2_lib.baseboard_fab2(sch_1):m_j_dqs_dn(2)"
				( attribute "CDS_PHYS_NET_NAME" "M_J_DQS_DN<2>"
					( Origin gPackager )
				)
				( attribute "PNN" "M_J_DQS_DN<2>"
					( Origin gPackager )
				)
				( objectStatus "M_J_DQS_DN<2>" )
			)
			( signal "@baseboard_fab2_lib.baseboard_fab2(sch_1):m_j_dqs_dn(3)"
				( attribute "CDS_PHYS_NET_NAME" "M_J_DQS_DN<3>"
					( Origin gPackager )
				)
				( attribute "PNN" "M_J_DQS_DN<3>"
					( Origin gPackager )
				)
				( objectStatus "M_J_DQS_DN<3>" )
			)
			( signal "@baseboard_fab2_lib.baseboard_fab2(sch_1):m_j_dqs_dn(4)"
				( attribute "CDS_PHYS_NET_NAME" "M_J_DQS_DN<4>"
					( Origin gPackager )
				)
				( attribute "PNN" "M_J_DQS_DN<4>"
					( Origin gPackager )
				)
				( objectStatus "M_J_DQS_DN<4>" )
			)
			( signal "@baseboard_fab2_lib.baseboard_fab2(sch_1):m_j_dqs_dn(5)"
				( attribute "CDS_PHYS_NET_NAME" "M_J_DQS_DN<5>"
					( Origin gPackager )
				)
				( attribute "PNN" "M_J_DQS_DN<5>"
					( Origin gPackager )
				)
				( objectStatus "M_J_DQS_DN<5>" )
			)
			( signal "@baseboard_fab2_lib.baseboard_fab2(sch_1):m_j_dqs_dn(6)"
				( attribute "CDS_PHYS_NET_NAME" "M_J_DQS_DN<6>"
					( Origin gPackager )
				)
				( attribute "PNN" "M_J_DQS_DN<6>"
					( Origin gPackager )
				)
				( objectStatus "M_J_DQS_DN<6>" )
			)
			( signal "@baseboard_fab2_lib.baseboard_fab2(sch_1):m_j_dqs_dn(7)"
				( attribute "CDS_PHYS_NET_NAME" "M_J_DQS_DN<7>"
					( Origin gPackager )
				)
				( attribute "PNN" "M_J_DQS_DN<7>"
					( Origin gPackager )
				)
				( objectStatus "M_J_DQS_DN<7>" )
			)
			( signal "@baseboard_fab2_lib.baseboard_fab2(sch_1):m_j_dqs_dn(8)"
				( attribute "CDS_PHYS_NET_NAME" "M_J_DQS_DN<8>"
					( Origin gPackager )
				)
				( attribute "PNN" "M_J_DQS_DN<8>"
					( Origin gPackager )
				)
				( objectStatus "M_J_DQS_DN<8>" )
			)
			( signal "@baseboard_fab2_lib.baseboard_fab2(sch_1):m_j_dqs_dn(9)"
				( attribute "CDS_PHYS_NET_NAME" "M_J_DQS_DN<9>"
					( Origin gPackager )
				)
				( attribute "PNN" "M_J_DQS_DN<9>"
					( Origin gPackager )
				)
				( objectStatus "M_J_DQS_DN<9>" )
			)
			( signal "@baseboard_fab2_lib.baseboard_fab2(sch_1):m_j_dqs_dn(10)"
				( attribute "CDS_PHYS_NET_NAME" "M_J_DQS_DN<10>"
					( Origin gPackager )
				)
				( attribute "PNN" "M_J_DQS_DN<10>"
					( Origin gPackager )
				)
				( objectStatus "M_J_DQS_DN<10>" )
			)
			( signal "@baseboard_fab2_lib.baseboard_fab2(sch_1):m_j_dqs_dn(11)"
				( attribute "CDS_PHYS_NET_NAME" "M_J_DQS_DN<11>"
					( Origin gPackager )
				)
				( attribute "PNN" "M_J_DQS_DN<11>"
					( Origin gPackager )
				)
				( objectStatus "M_J_DQS_DN<11>" )
			)
			( signal "@baseboard_fab2_lib.baseboard_fab2(sch_1):m_j_dqs_dn(12)"
				( attribute "CDS_PHYS_NET_NAME" "M_J_DQS_DN<12>"
					( Origin gPackager )
				)
				( attribute "PNN" "M_J_DQS_DN<12>"
					( Origin gPackager )
				)
				( objectStatus "M_J_DQS_DN<12>" )
			)
			( signal "@baseboard_fab2_lib.baseboard_fab2(sch_1):m_j_dqs_dn(13)"
				( attribute "CDS_PHYS_NET_NAME" "M_J_DQS_DN<13>"
					( Origin gPackager )
				)
				( attribute "PNN" "M_J_DQS_DN<13>"
					( Origin gPackager )
				)
				( objectStatus "M_J_DQS_DN<13>" )
			)
			( signal "@baseboard_fab2_lib.baseboard_fab2(sch_1):m_j_dqs_dn(14)"
				( attribute "CDS_PHYS_NET_NAME" "M_J_DQS_DN<14>"
					( Origin gPackager )
				)
				( attribute "PNN" "M_J_DQS_DN<14>"
					( Origin gPackager )
				)
				( objectStatus "M_J_DQS_DN<14>" )
			)
			( signal "@baseboard_fab2_lib.baseboard_fab2(sch_1):m_j_dqs_dn(15)"
				( attribute "CDS_PHYS_NET_NAME" "M_J_DQS_DN<15>"
					( Origin gPackager )
				)
				( attribute "PNN" "M_J_DQS_DN<15>"
					( Origin gPackager )
				)
				( objectStatus "M_J_DQS_DN<15>" )
			)
			( signal "@baseboard_fab2_lib.baseboard_fab2(sch_1):m_j_dqs_dn(16)"
				( attribute "CDS_PHYS_NET_NAME" "M_J_DQS_DN<16>"
					( Origin gPackager )
				)
				( attribute "PNN" "M_J_DQS_DN<16>"
					( Origin gPackager )
				)
				( objectStatus "M_J_DQS_DN<16>" )
			)
			( signal "@baseboard_fab2_lib.baseboard_fab2(sch_1):m_j_dqs_dn(17)"
				( attribute "CDS_PHYS_NET_NAME" "M_J_DQS_DN<17>"
					( Origin gPackager )
				)
				( attribute "PNN" "M_J_DQS_DN<17>"
					( Origin gPackager )
				)
				( objectStatus "M_J_DQS_DN<17>" )
			)
			( signal "@baseboard_fab2_lib.baseboard_fab2(sch_1):m_j_dqs_dp(0)"
				( attribute "CDS_PHYS_NET_NAME" "M_J_DQS_DP<0>"
					( Origin gPackager )
				)
				( attribute "PNN" "M_J_DQS_DP<0>"
					( Origin gPackager )
				)
				( objectStatus "M_J_DQS_DP<0>" )
			)
			( signal "@baseboard_fab2_lib.baseboard_fab2(sch_1):m_j_dqs_dp(1)"
				( attribute "CDS_PHYS_NET_NAME" "M_J_DQS_DP<1>"
					( Origin gPackager )
				)
				( attribute "PNN" "M_J_DQS_DP<1>"
					( Origin gPackager )
				)
				( objectStatus "M_J_DQS_DP<1>" )
			)
			( signal "@baseboard_fab2_lib.baseboard_fab2(sch_1):m_j_dqs_dp(2)"
				( attribute "CDS_PHYS_NET_NAME" "M_J_DQS_DP<2>"
					( Origin gPackager )
				)
				( attribute "PNN" "M_J_DQS_DP<2>"
					( Origin gPackager )
				)
				( objectStatus "M_J_DQS_DP<2>" )
			)
			( signal "@baseboard_fab2_lib.baseboard_fab2(sch_1):m_j_dqs_dp(3)"
				( attribute "CDS_PHYS_NET_NAME" "M_J_DQS_DP<3>"
					( Origin gPackager )
				)
				( attribute "PNN" "M_J_DQS_DP<3>"
					( Origin gPackager )
				)
				( objectStatus "M_J_DQS_DP<3>" )
			)
			( signal "@baseboard_fab2_lib.baseboard_fab2(sch_1):m_j_dqs_dp(4)"
				( attribute "CDS_PHYS_NET_NAME" "M_J_DQS_DP<4>"
					( Origin gPackager )
				)
				( attribute "PNN" "M_J_DQS_DP<4>"
					( Origin gPackager )
				)
				( objectStatus "M_J_DQS_DP<4>" )
			)
			( signal "@baseboard_fab2_lib.baseboard_fab2(sch_1):m_j_dqs_dp(5)"
				( attribute "CDS_PHYS_NET_NAME" "M_J_DQS_DP<5>"
					( Origin gPackager )
				)
				( attribute "PNN" "M_J_DQS_DP<5>"
					( Origin gPackager )
				)
				( objectStatus "M_J_DQS_DP<5>" )
			)
			( signal "@baseboard_fab2_lib.baseboard_fab2(sch_1):m_j_dqs_dp(6)"
				( attribute "CDS_PHYS_NET_NAME" "M_J_DQS_DP<6>"
					( Origin gPackager )
				)
				( attribute "PNN" "M_J_DQS_DP<6>"
					( Origin gPackager )
				)
				( objectStatus "M_J_DQS_DP<6>" )
			)
			( signal "@baseboard_fab2_lib.baseboard_fab2(sch_1):m_j_dqs_dp(7)"
				( attribute "CDS_PHYS_NET_NAME" "M_J_DQS_DP<7>"
					( Origin gPackager )
				)
				( attribute "PNN" "M_J_DQS_DP<7>"
					( Origin gPackager )
				)
				( objectStatus "M_J_DQS_DP<7>" )
			)
			( signal "@baseboard_fab2_lib.baseboard_fab2(sch_1):m_j_dqs_dp(8)"
				( attribute "CDS_PHYS_NET_NAME" "M_J_DQS_DP<8>"
					( Origin gPackager )
				)
				( attribute "PNN" "M_J_DQS_DP<8>"
					( Origin gPackager )
				)
				( objectStatus "M_J_DQS_DP<8>" )
			)
			( signal "@baseboard_fab2_lib.baseboard_fab2(sch_1):m_j_dqs_dp(9)"
				( attribute "CDS_PHYS_NET_NAME" "M_J_DQS_DP<9>"
					( Origin gPackager )
				)
				( attribute "PNN" "M_J_DQS_DP<9>"
					( Origin gPackager )
				)
				( objectStatus "M_J_DQS_DP<9>" )
			)
			( signal "@baseboard_fab2_lib.baseboard_fab2(sch_1):m_j_dqs_dp(10)"
				( attribute "CDS_PHYS_NET_NAME" "M_J_DQS_DP<10>"
					( Origin gPackager )
				)
				( attribute "PNN" "M_J_DQS_DP<10>"
					( Origin gPackager )
				)
				( objectStatus "M_J_DQS_DP<10>" )
			)
			( signal "@baseboard_fab2_lib.baseboard_fab2(sch_1):m_j_dqs_dp(11)"
				( attribute "CDS_PHYS_NET_NAME" "M_J_DQS_DP<11>"
					( Origin gPackager )
				)
				( attribute "PNN" "M_J_DQS_DP<11>"
					( Origin gPackager )
				)
				( objectStatus "M_J_DQS_DP<11>" )
			)
			( signal "@baseboard_fab2_lib.baseboard_fab2(sch_1):m_j_dqs_dp(12)"
				( attribute "CDS_PHYS_NET_NAME" "M_J_DQS_DP<12>"
					( Origin gPackager )
				)
				( attribute "PNN" "M_J_DQS_DP<12>"
					( Origin gPackager )
				)
				( objectStatus "M_J_DQS_DP<12>" )
			)
			( signal "@baseboard_fab2_lib.baseboard_fab2(sch_1):m_j_dqs_dp(13)"
				( attribute "CDS_PHYS_NET_NAME" "M_J_DQS_DP<13>"
					( Origin gPackager )
				)
				( attribute "PNN" "M_J_DQS_DP<13>"
					( Origin gPackager )
				)
				( objectStatus "M_J_DQS_DP<13>" )
			)
			( signal "@baseboard_fab2_lib.baseboard_fab2(sch_1):m_j_dqs_dp(14)"
				( attribute "CDS_PHYS_NET_NAME" "M_J_DQS_DP<14>"
					( Origin gPackager )
				)
				( attribute "PNN" "M_J_DQS_DP<14>"
					( Origin gPackager )
				)
				( objectStatus "M_J_DQS_DP<14>" )
			)
			( signal "@baseboard_fab2_lib.baseboard_fab2(sch_1):m_j_dqs_dp(15)"
				( attribute "CDS_PHYS_NET_NAME" "M_J_DQS_DP<15>"
					( Origin gPackager )
				)
				( attribute "PNN" "M_J_DQS_DP<15>"
					( Origin gPackager )
				)
				( objectStatus "M_J_DQS_DP<15>" )
			)
			( signal "@baseboard_fab2_lib.baseboard_fab2(sch_1):m_j_dqs_dp(16)"
				( attribute "CDS_PHYS_NET_NAME" "M_J_DQS_DP<16>"
					( Origin gPackager )
				)
				( attribute "PNN" "M_J_DQS_DP<16>"
					( Origin gPackager )
				)
				( objectStatus "M_J_DQS_DP<16>" )
			)
			( signal "@baseboard_fab2_lib.baseboard_fab2(sch_1):m_j_dqs_dp(17)"
				( attribute "CDS_PHYS_NET_NAME" "M_J_DQS_DP<17>"
					( Origin gPackager )
				)
				( attribute "PNN" "M_J_DQS_DP<17>"
					( Origin gPackager )
				)
				( objectStatus "M_J_DQS_DP<17>" )
			)
			( signal "@baseboard_fab2_lib.baseboard_fab2(sch_1):m_j_ecc(0)"
				( attribute "CDS_PHYS_NET_NAME" "M_J_ECC<0>"
					( Origin gPackager )
				)
				( attribute "PNN" "M_J_ECC<0>"
					( Origin gPackager )
				)
				( objectStatus "M_J_ECC<0>" )
			)
			( signal "@baseboard_fab2_lib.baseboard_fab2(sch_1):m_j_ecc(1)"
				( attribute "CDS_PHYS_NET_NAME" "M_J_ECC<1>"
					( Origin gPackager )
				)
				( attribute "PNN" "M_J_ECC<1>"
					( Origin gPackager )
				)
				( objectStatus "M_J_ECC<1>" )
			)
			( signal "@baseboard_fab2_lib.baseboard_fab2(sch_1):m_j_ecc(2)"
				( attribute "CDS_PHYS_NET_NAME" "M_J_ECC<2>"
					( Origin gPackager )
				)
				( attribute "PNN" "M_J_ECC<2>"
					( Origin gPackager )
				)
				( objectStatus "M_J_ECC<2>" )
			)
			( signal "@baseboard_fab2_lib.baseboard_fab2(sch_1):m_j_ecc(3)"
				( attribute "CDS_PHYS_NET_NAME" "M_J_ECC<3>"
					( Origin gPackager )
				)
				( attribute "PNN" "M_J_ECC<3>"
					( Origin gPackager )
				)
				( objectStatus "M_J_ECC<3>" )
			)
			( signal "@baseboard_fab2_lib.baseboard_fab2(sch_1):m_j_ecc(4)"
				( attribute "CDS_PHYS_NET_NAME" "M_J_ECC<4>"
					( Origin gPackager )
				)
				( attribute "PNN" "M_J_ECC<4>"
					( Origin gPackager )
				)
				( objectStatus "M_J_ECC<4>" )
			)
			( signal "@baseboard_fab2_lib.baseboard_fab2(sch_1):m_j_ecc(5)"
				( attribute "CDS_PHYS_NET_NAME" "M_J_ECC<5>"
					( Origin gPackager )
				)
				( attribute "PNN" "M_J_ECC<5>"
					( Origin gPackager )
				)
				( objectStatus "M_J_ECC<5>" )
			)
			( signal "@baseboard_fab2_lib.baseboard_fab2(sch_1):m_j_ecc(6)"
				( attribute "CDS_PHYS_NET_NAME" "M_J_ECC<6>"
					( Origin gPackager )
				)
				( attribute "PNN" "M_J_ECC<6>"
					( Origin gPackager )
				)
				( objectStatus "M_J_ECC<6>" )
			)
			( signal "@baseboard_fab2_lib.baseboard_fab2(sch_1):m_j_ecc(7)"
				( attribute "CDS_PHYS_NET_NAME" "M_J_ECC<7>"
					( Origin gPackager )
				)
				( attribute "PNN" "M_J_ECC<7>"
					( Origin gPackager )
				)
				( objectStatus "M_J_ECC<7>" )
			)
			( signal "@baseboard_fab2_lib.baseboard_fab2(sch_1):m_j_ma(0)"
				( attribute "CDS_PHYS_NET_NAME" "M_J_MA<0>"
					( Origin gPackager )
				)
				( attribute "PNN" "M_J_MA<0>"
					( Origin gPackager )
				)
				( objectStatus "M_J_MA<0>" )
			)
			( signal "@baseboard_fab2_lib.baseboard_fab2(sch_1):m_j_ma(1)"
				( attribute "CDS_PHYS_NET_NAME" "M_J_MA<1>"
					( Origin gPackager )
				)
				( attribute "PNN" "M_J_MA<1>"
					( Origin gPackager )
				)
				( objectStatus "M_J_MA<1>" )
			)
			( signal "@baseboard_fab2_lib.baseboard_fab2(sch_1):m_j_ma(2)"
				( attribute "CDS_PHYS_NET_NAME" "M_J_MA<2>"
					( Origin gPackager )
				)
				( attribute "PNN" "M_J_MA<2>"
					( Origin gPackager )
				)
				( objectStatus "M_J_MA<2>" )
			)
			( signal "@baseboard_fab2_lib.baseboard_fab2(sch_1):m_j_ma(3)"
				( attribute "CDS_PHYS_NET_NAME" "M_J_MA<3>"
					( Origin gPackager )
				)
				( attribute "PNN" "M_J_MA<3>"
					( Origin gPackager )
				)
				( objectStatus "M_J_MA<3>" )
			)
			( signal "@baseboard_fab2_lib.baseboard_fab2(sch_1):m_j_ma(4)"
				( attribute "CDS_PHYS_NET_NAME" "M_J_MA<4>"
					( Origin gPackager )
				)
				( attribute "PNN" "M_J_MA<4>"
					( Origin gPackager )
				)
				( objectStatus "M_J_MA<4>" )
			)
			( signal "@baseboard_fab2_lib.baseboard_fab2(sch_1):m_j_ma(5)"
				( attribute "CDS_PHYS_NET_NAME" "M_J_MA<5>"
					( Origin gPackager )
				)
				( attribute "PNN" "M_J_MA<5>"
					( Origin gPackager )
				)
				( objectStatus "M_J_MA<5>" )
			)
			( signal "@baseboard_fab2_lib.baseboard_fab2(sch_1):m_j_ma(6)"
				( attribute "CDS_PHYS_NET_NAME" "M_J_MA<6>"
					( Origin gPackager )
				)
				( attribute "PNN" "M_J_MA<6>"
					( Origin gPackager )
				)
				( objectStatus "M_J_MA<6>" )
			)
			( signal "@baseboard_fab2_lib.baseboard_fab2(sch_1):m_j_ma(7)"
				( attribute "CDS_PHYS_NET_NAME" "M_J_MA<7>"
					( Origin gPackager )
				)
				( attribute "PNN" "M_J_MA<7>"
					( Origin gPackager )
				)
				( objectStatus "M_J_MA<7>" )
			)
			( signal "@baseboard_fab2_lib.baseboard_fab2(sch_1):m_j_ma(8)"
				( attribute "CDS_PHYS_NET_NAME" "M_J_MA<8>"
					( Origin gPackager )
				)
				( attribute "PNN" "M_J_MA<8>"
					( Origin gPackager )
				)
				( objectStatus "M_J_MA<8>" )
			)
			( signal "@baseboard_fab2_lib.baseboard_fab2(sch_1):m_j_ma(9)"
				( attribute "CDS_PHYS_NET_NAME" "M_J_MA<9>"
					( Origin gPackager )
				)
				( attribute "PNN" "M_J_MA<9>"
					( Origin gPackager )
				)
				( objectStatus "M_J_MA<9>" )
			)
			( signal "@baseboard_fab2_lib.baseboard_fab2(sch_1):m_j_ma(10)"
				( attribute "CDS_PHYS_NET_NAME" "M_J_MA<10>"
					( Origin gPackager )
				)
				( attribute "PNN" "M_J_MA<10>"
					( Origin gPackager )
				)
				( objectStatus "M_J_MA<10>" )
			)
			( signal "@baseboard_fab2_lib.baseboard_fab2(sch_1):m_j_ma(11)"
				( attribute "CDS_PHYS_NET_NAME" "M_J_MA<11>"
					( Origin gPackager )
				)
				( attribute "PNN" "M_J_MA<11>"
					( Origin gPackager )
				)
				( objectStatus "M_J_MA<11>" )
			)
			( signal "@baseboard_fab2_lib.baseboard_fab2(sch_1):m_j_ma(12)"
				( attribute "CDS_PHYS_NET_NAME" "M_J_MA<12>"
					( Origin gPackager )
				)
				( attribute "PNN" "M_J_MA<12>"
					( Origin gPackager )
				)
				( objectStatus "M_J_MA<12>" )
			)
			( signal "@baseboard_fab2_lib.baseboard_fab2(sch_1):m_j_ma(13)"
				( attribute "CDS_PHYS_NET_NAME" "M_J_MA<13>"
					( Origin gPackager )
				)
				( attribute "PNN" "M_J_MA<13>"
					( Origin gPackager )
				)
				( objectStatus "M_J_MA<13>" )
			)
			( signal "@baseboard_fab2_lib.baseboard_fab2(sch_1):m_j_ma(14)"
				( attribute "CDS_PHYS_NET_NAME" "M_J_MA<14>"
					( Origin gPackager )
				)
				( attribute "PNN" "M_J_MA<14>"
					( Origin gPackager )
				)
				( objectStatus "M_J_MA<14>" )
			)
			( signal "@baseboard_fab2_lib.baseboard_fab2(sch_1):m_j_ma(15)"
				( attribute "CDS_PHYS_NET_NAME" "M_J_MA<15>"
					( Origin gPackager )
				)
				( attribute "PNN" "M_J_MA<15>"
					( Origin gPackager )
				)
				( objectStatus "M_J_MA<15>" )
			)
			( signal "@baseboard_fab2_lib.baseboard_fab2(sch_1):m_j_ma(16)"
				( attribute "CDS_PHYS_NET_NAME" "M_J_MA<16>"
					( Origin gPackager )
				)
				( attribute "PNN" "M_J_MA<16>"
					( Origin gPackager )
				)
				( objectStatus "M_J_MA<16>" )
			)
			( signal "@baseboard_fab2_lib.baseboard_fab2(sch_1):m_j_ma(17)"
				( attribute "CDS_PHYS_NET_NAME" "M_J_MA<17>"
					( Origin gPackager )
				)
				( attribute "PNN" "M_J_MA<17>"
					( Origin gPackager )
				)
				( objectStatus "M_J_MA<17>" )
			)
			( signal "@baseboard_fab2_lib.baseboard_fab2(sch_1):m_j_odt(0)"
				( attribute "CDS_PHYS_NET_NAME" "M_J_ODT<0>"
					( Origin gPackager )
				)
				( attribute "PNN" "M_J_ODT<0>"
					( Origin gPackager )
				)
				( objectStatus "M_J_ODT<0>" )
			)
			( signal "@baseboard_fab2_lib.baseboard_fab2(sch_1):m_j_odt(1)"
				( attribute "CDS_PHYS_NET_NAME" "M_J_ODT<1>"
					( Origin gPackager )
				)
				( attribute "PNN" "M_J_ODT<1>"
					( Origin gPackager )
				)
				( objectStatus "M_J_ODT<1>" )
			)
			( signal "@baseboard_fab2_lib.baseboard_fab2(sch_1):m_j_odt(2)"
				( attribute "CDS_PHYS_NET_NAME" "M_J_ODT<2>"
					( Origin gPackager )
				)
				( attribute "PNN" "M_J_ODT<2>"
					( Origin gPackager )
				)
				( objectStatus "M_J_ODT<2>" )
			)
			( signal "@baseboard_fab2_lib.baseboard_fab2(sch_1):m_j_odt(3)"
				( attribute "CDS_PHYS_NET_NAME" "M_J_ODT<3>"
					( Origin gPackager )
				)
				( attribute "PNN" "M_J_ODT<3>"
					( Origin gPackager )
				)
				( objectStatus "M_J_ODT<3>" )
			)
			( signal "@baseboard_fab2_lib.baseboard_fab2(sch_1):m_j_par"
				( attribute "CDS_PHYS_NET_NAME" "M_J_PAR"
					( Origin gPackager )
				)
				( objectStatus "M_J_PAR" )
			)
			( signal "@baseboard_fab2_lib.baseboard_fab2(sch_1):m_k_act_n"
				( attribute "CDS_PHYS_NET_NAME" "M_K_ACT_N"
					( Origin gPackager )
				)
				( objectStatus "M_K_ACT_N" )
			)
			( signal "@baseboard_fab2_lib.baseboard_fab2(sch_1):m_k_alert_n"
				( attribute "CDS_PHYS_NET_NAME" "M_K_ALERT_N"
					( Origin gPackager )
				)
				( objectStatus "M_K_ALERT_N" )
			)
			( signal "@baseboard_fab2_lib.baseboard_fab2(sch_1):m_k_ba(0)"
				( attribute "CDS_PHYS_NET_NAME" "M_K_BA<0>"
					( Origin gPackager )
				)
				( attribute "PNN" "M_K_BA<0>"
					( Origin gPackager )
				)
				( objectStatus "M_K_BA<0>" )
			)
			( signal "@baseboard_fab2_lib.baseboard_fab2(sch_1):m_k_ba(1)"
				( attribute "CDS_PHYS_NET_NAME" "M_K_BA<1>"
					( Origin gPackager )
				)
				( attribute "PNN" "M_K_BA<1>"
					( Origin gPackager )
				)
				( objectStatus "M_K_BA<1>" )
			)
			( signal "@baseboard_fab2_lib.baseboard_fab2(sch_1):m_k_bg(0)"
				( attribute "CDS_PHYS_NET_NAME" "M_K_BG<0>"
					( Origin gPackager )
				)
				( attribute "PNN" "M_K_BG<0>"
					( Origin gPackager )
				)
				( objectStatus "M_K_BG<0>" )
			)
			( signal "@baseboard_fab2_lib.baseboard_fab2(sch_1):m_k_bg(1)"
				( attribute "CDS_PHYS_NET_NAME" "M_K_BG<1>"
					( Origin gPackager )
				)
				( attribute "PNN" "M_K_BG<1>"
					( Origin gPackager )
				)
				( objectStatus "M_K_BG<1>" )
			)
			( signal "@baseboard_fab2_lib.baseboard_fab2(sch_1):m_k_c(2)"
				( attribute "CDS_PHYS_NET_NAME" "M_K_C<2>"
					( Origin gPackager )
				)
				( attribute "PNN" "M_K_C<2>"
					( Origin gPackager )
				)
				( objectStatus "M_K_C<2>" )
			)
			( signal "@baseboard_fab2_lib.baseboard_fab2(sch_1):m_k_cke(0)"
				( attribute "CDS_PHYS_NET_NAME" "M_K_CKE<0>"
					( Origin gPackager )
				)
				( attribute "PNN" "M_K_CKE<0>"
					( Origin gPackager )
				)
				( objectStatus "M_K_CKE<0>" )
			)
			( signal "@baseboard_fab2_lib.baseboard_fab2(sch_1):m_k_cke(1)"
				( attribute "CDS_PHYS_NET_NAME" "M_K_CKE<1>"
					( Origin gPackager )
				)
				( attribute "PNN" "M_K_CKE<1>"
					( Origin gPackager )
				)
				( objectStatus "M_K_CKE<1>" )
			)
			( signal "@baseboard_fab2_lib.baseboard_fab2(sch_1):m_k_cke(2)"
				( attribute "CDS_PHYS_NET_NAME" "M_K_CKE<2>"
					( Origin gPackager )
				)
				( attribute "PNN" "M_K_CKE<2>"
					( Origin gPackager )
				)
				( objectStatus "M_K_CKE<2>" )
			)
			( signal "@baseboard_fab2_lib.baseboard_fab2(sch_1):m_k_cke(3)"
				( attribute "CDS_PHYS_NET_NAME" "M_K_CKE<3>"
					( Origin gPackager )
				)
				( attribute "PNN" "M_K_CKE<3>"
					( Origin gPackager )
				)
				( objectStatus "M_K_CKE<3>" )
			)
			( signal "@baseboard_fab2_lib.baseboard_fab2(sch_1):m_k_clk_dn(0)"
				( attribute "CDS_PHYS_NET_NAME" "M_K_CLK_DN<0>"
					( Origin gPackager )
				)
				( attribute "PNN" "M_K_CLK_DN<0>"
					( Origin gPackager )
				)
				( objectStatus "M_K_CLK_DN<0>" )
			)
			( signal "@baseboard_fab2_lib.baseboard_fab2(sch_1):m_k_clk_dn(1)"
				( attribute "CDS_PHYS_NET_NAME" "M_K_CLK_DN<1>"
					( Origin gPackager )
				)
				( attribute "PNN" "M_K_CLK_DN<1>"
					( Origin gPackager )
				)
				( objectStatus "M_K_CLK_DN<1>" )
			)
			( signal "@baseboard_fab2_lib.baseboard_fab2(sch_1):m_k_clk_dn(2)"
				( attribute "CDS_PHYS_NET_NAME" "M_K_CLK_DN<2>"
					( Origin gPackager )
				)
				( attribute "PNN" "M_K_CLK_DN<2>"
					( Origin gPackager )
				)
				( objectStatus "M_K_CLK_DN<2>" )
			)
			( signal "@baseboard_fab2_lib.baseboard_fab2(sch_1):m_k_clk_dn(3)"
				( attribute "CDS_PHYS_NET_NAME" "M_K_CLK_DN<3>"
					( Origin gPackager )
				)
				( attribute "PNN" "M_K_CLK_DN<3>"
					( Origin gPackager )
				)
				( objectStatus "M_K_CLK_DN<3>" )
			)
			( signal "@baseboard_fab2_lib.baseboard_fab2(sch_1):m_k_clk_dp(0)"
				( attribute "CDS_PHYS_NET_NAME" "M_K_CLK_DP<0>"
					( Origin gPackager )
				)
				( attribute "PNN" "M_K_CLK_DP<0>"
					( Origin gPackager )
				)
				( objectStatus "M_K_CLK_DP<0>" )
			)
			( signal "@baseboard_fab2_lib.baseboard_fab2(sch_1):m_k_clk_dp(1)"
				( attribute "CDS_PHYS_NET_NAME" "M_K_CLK_DP<1>"
					( Origin gPackager )
				)
				( attribute "PNN" "M_K_CLK_DP<1>"
					( Origin gPackager )
				)
				( objectStatus "M_K_CLK_DP<1>" )
			)
			( signal "@baseboard_fab2_lib.baseboard_fab2(sch_1):m_k_clk_dp(2)"
				( attribute "CDS_PHYS_NET_NAME" "M_K_CLK_DP<2>"
					( Origin gPackager )
				)
				( attribute "PNN" "M_K_CLK_DP<2>"
					( Origin gPackager )
				)
				( objectStatus "M_K_CLK_DP<2>" )
			)
			( signal "@baseboard_fab2_lib.baseboard_fab2(sch_1):m_k_clk_dp(3)"
				( attribute "CDS_PHYS_NET_NAME" "M_K_CLK_DP<3>"
					( Origin gPackager )
				)
				( attribute "PNN" "M_K_CLK_DP<3>"
					( Origin gPackager )
				)
				( objectStatus "M_K_CLK_DP<3>" )
			)
			( signal "@baseboard_fab2_lib.baseboard_fab2(sch_1):m_k_cs_n(0)"
				( attribute "CDS_PHYS_NET_NAME" "M_K_CS_N<0>"
					( Origin gPackager )
				)
				( attribute "PNN" "M_K_CS_N<0>"
					( Origin gPackager )
				)
				( objectStatus "M_K_CS_N<0>" )
			)
			( signal "@baseboard_fab2_lib.baseboard_fab2(sch_1):m_k_cs_n(1)"
				( attribute "CDS_PHYS_NET_NAME" "M_K_CS_N<1>"
					( Origin gPackager )
				)
				( attribute "PNN" "M_K_CS_N<1>"
					( Origin gPackager )
				)
				( objectStatus "M_K_CS_N<1>" )
			)
			( signal "@baseboard_fab2_lib.baseboard_fab2(sch_1):m_k_cs_n(2)"
				( attribute "CDS_PHYS_NET_NAME" "M_K_CS_N<2>"
					( Origin gPackager )
				)
				( attribute "PNN" "M_K_CS_N<2>"
					( Origin gPackager )
				)
				( objectStatus "M_K_CS_N<2>" )
			)
			( signal "@baseboard_fab2_lib.baseboard_fab2(sch_1):m_k_cs_n(3)"
				( attribute "CDS_PHYS_NET_NAME" "M_K_CS_N<3>"
					( Origin gPackager )
				)
				( attribute "PNN" "M_K_CS_N<3>"
					( Origin gPackager )
				)
				( objectStatus "M_K_CS_N<3>" )
			)
			( signal "@baseboard_fab2_lib.baseboard_fab2(sch_1):m_k_cs_n(4)"
				( attribute "CDS_PHYS_NET_NAME" "M_K_CS_N<4>"
					( Origin gPackager )
				)
				( attribute "PNN" "M_K_CS_N<4>"
					( Origin gPackager )
				)
				( objectStatus "M_K_CS_N<4>" )
			)
			( signal "@baseboard_fab2_lib.baseboard_fab2(sch_1):m_k_cs_n(5)"
				( attribute "CDS_PHYS_NET_NAME" "M_K_CS_N<5>"
					( Origin gPackager )
				)
				( attribute "PNN" "M_K_CS_N<5>"
					( Origin gPackager )
				)
				( objectStatus "M_K_CS_N<5>" )
			)
			( signal "@baseboard_fab2_lib.baseboard_fab2(sch_1):m_k_cs_n(6)"
				( attribute "CDS_PHYS_NET_NAME" "M_K_CS_N<6>"
					( Origin gPackager )
				)
				( attribute "PNN" "M_K_CS_N<6>"
					( Origin gPackager )
				)
				( objectStatus "M_K_CS_N<6>" )
			)
			( signal "@baseboard_fab2_lib.baseboard_fab2(sch_1):m_k_cs_n(7)"
				( attribute "CDS_PHYS_NET_NAME" "M_K_CS_N<7>"
					( Origin gPackager )
				)
				( attribute "PNN" "M_K_CS_N<7>"
					( Origin gPackager )
				)
				( objectStatus "M_K_CS_N<7>" )
			)
			( signal "@baseboard_fab2_lib.baseboard_fab2(sch_1):m_k_dq(0)"
				( attribute "CDS_PHYS_NET_NAME" "M_K_DQ<0>"
					( Origin gPackager )
				)
				( attribute "PNN" "M_K_DQ<0>"
					( Origin gPackager )
				)
				( objectStatus "M_K_DQ<0>" )
			)
			( signal "@baseboard_fab2_lib.baseboard_fab2(sch_1):m_k_dq(1)"
				( attribute "CDS_PHYS_NET_NAME" "M_K_DQ<1>"
					( Origin gPackager )
				)
				( attribute "PNN" "M_K_DQ<1>"
					( Origin gPackager )
				)
				( objectStatus "M_K_DQ<1>" )
			)
			( signal "@baseboard_fab2_lib.baseboard_fab2(sch_1):m_k_dq(2)"
				( attribute "CDS_PHYS_NET_NAME" "M_K_DQ<2>"
					( Origin gPackager )
				)
				( attribute "PNN" "M_K_DQ<2>"
					( Origin gPackager )
				)
				( objectStatus "M_K_DQ<2>" )
			)
			( signal "@baseboard_fab2_lib.baseboard_fab2(sch_1):m_k_dq(3)"
				( attribute "CDS_PHYS_NET_NAME" "M_K_DQ<3>"
					( Origin gPackager )
				)
				( attribute "PNN" "M_K_DQ<3>"
					( Origin gPackager )
				)
				( objectStatus "M_K_DQ<3>" )
			)
			( signal "@baseboard_fab2_lib.baseboard_fab2(sch_1):m_k_dq(4)"
				( attribute "CDS_PHYS_NET_NAME" "M_K_DQ<4>"
					( Origin gPackager )
				)
				( attribute "PNN" "M_K_DQ<4>"
					( Origin gPackager )
				)
				( objectStatus "M_K_DQ<4>" )
			)
			( signal "@baseboard_fab2_lib.baseboard_fab2(sch_1):m_k_dq(5)"
				( attribute "CDS_PHYS_NET_NAME" "M_K_DQ<5>"
					( Origin gPackager )
				)
				( attribute "PNN" "M_K_DQ<5>"
					( Origin gPackager )
				)
				( objectStatus "M_K_DQ<5>" )
			)
			( signal "@baseboard_fab2_lib.baseboard_fab2(sch_1):m_k_dq(6)"
				( attribute "CDS_PHYS_NET_NAME" "M_K_DQ<6>"
					( Origin gPackager )
				)
				( attribute "PNN" "M_K_DQ<6>"
					( Origin gPackager )
				)
				( objectStatus "M_K_DQ<6>" )
			)
			( signal "@baseboard_fab2_lib.baseboard_fab2(sch_1):m_k_dq(7)"
				( attribute "CDS_PHYS_NET_NAME" "M_K_DQ<7>"
					( Origin gPackager )
				)
				( attribute "PNN" "M_K_DQ<7>"
					( Origin gPackager )
				)
				( objectStatus "M_K_DQ<7>" )
			)
			( signal "@baseboard_fab2_lib.baseboard_fab2(sch_1):m_k_dq(8)"
				( attribute "CDS_PHYS_NET_NAME" "M_K_DQ<8>"
					( Origin gPackager )
				)
				( attribute "PNN" "M_K_DQ<8>"
					( Origin gPackager )
				)
				( objectStatus "M_K_DQ<8>" )
			)
			( signal "@baseboard_fab2_lib.baseboard_fab2(sch_1):m_k_dq(9)"
				( attribute "CDS_PHYS_NET_NAME" "M_K_DQ<9>"
					( Origin gPackager )
				)
				( attribute "PNN" "M_K_DQ<9>"
					( Origin gPackager )
				)
				( objectStatus "M_K_DQ<9>" )
			)
			( signal "@baseboard_fab2_lib.baseboard_fab2(sch_1):m_k_dq(10)"
				( attribute "CDS_PHYS_NET_NAME" "M_K_DQ<10>"
					( Origin gPackager )
				)
				( attribute "PNN" "M_K_DQ<10>"
					( Origin gPackager )
				)
				( objectStatus "M_K_DQ<10>" )
			)
			( signal "@baseboard_fab2_lib.baseboard_fab2(sch_1):m_k_dq(11)"
				( attribute "CDS_PHYS_NET_NAME" "M_K_DQ<11>"
					( Origin gPackager )
				)
				( attribute "PNN" "M_K_DQ<11>"
					( Origin gPackager )
				)
				( objectStatus "M_K_DQ<11>" )
			)
			( signal "@baseboard_fab2_lib.baseboard_fab2(sch_1):m_k_dq(12)"
				( attribute "CDS_PHYS_NET_NAME" "M_K_DQ<12>"
					( Origin gPackager )
				)
				( attribute "PNN" "M_K_DQ<12>"
					( Origin gPackager )
				)
				( objectStatus "M_K_DQ<12>" )
			)
			( signal "@baseboard_fab2_lib.baseboard_fab2(sch_1):m_k_dq(13)"
				( attribute "CDS_PHYS_NET_NAME" "M_K_DQ<13>"
					( Origin gPackager )
				)
				( attribute "PNN" "M_K_DQ<13>"
					( Origin gPackager )
				)
				( objectStatus "M_K_DQ<13>" )
			)
			( signal "@baseboard_fab2_lib.baseboard_fab2(sch_1):m_k_dq(14)"
				( attribute "CDS_PHYS_NET_NAME" "M_K_DQ<14>"
					( Origin gPackager )
				)
				( attribute "PNN" "M_K_DQ<14>"
					( Origin gPackager )
				)
				( objectStatus "M_K_DQ<14>" )
			)
			( signal "@baseboard_fab2_lib.baseboard_fab2(sch_1):m_k_dq(15)"
				( attribute "CDS_PHYS_NET_NAME" "M_K_DQ<15>"
					( Origin gPackager )
				)
				( attribute "PNN" "M_K_DQ<15>"
					( Origin gPackager )
				)
				( objectStatus "M_K_DQ<15>" )
			)
			( signal "@baseboard_fab2_lib.baseboard_fab2(sch_1):m_k_dq(16)"
				( attribute "CDS_PHYS_NET_NAME" "M_K_DQ<16>"
					( Origin gPackager )
				)
				( attribute "PNN" "M_K_DQ<16>"
					( Origin gPackager )
				)
				( objectStatus "M_K_DQ<16>" )
			)
			( signal "@baseboard_fab2_lib.baseboard_fab2(sch_1):m_k_dq(17)"
				( attribute "CDS_PHYS_NET_NAME" "M_K_DQ<17>"
					( Origin gPackager )
				)
				( attribute "PNN" "M_K_DQ<17>"
					( Origin gPackager )
				)
				( objectStatus "M_K_DQ<17>" )
			)
			( signal "@baseboard_fab2_lib.baseboard_fab2(sch_1):m_k_dq(18)"
				( attribute "CDS_PHYS_NET_NAME" "M_K_DQ<18>"
					( Origin gPackager )
				)
				( attribute "PNN" "M_K_DQ<18>"
					( Origin gPackager )
				)
				( objectStatus "M_K_DQ<18>" )
			)
			( signal "@baseboard_fab2_lib.baseboard_fab2(sch_1):m_k_dq(19)"
				( attribute "CDS_PHYS_NET_NAME" "M_K_DQ<19>"
					( Origin gPackager )
				)
				( attribute "PNN" "M_K_DQ<19>"
					( Origin gPackager )
				)
				( objectStatus "M_K_DQ<19>" )
			)
			( signal "@baseboard_fab2_lib.baseboard_fab2(sch_1):m_k_dq(20)"
				( attribute "CDS_PHYS_NET_NAME" "M_K_DQ<20>"
					( Origin gPackager )
				)
				( attribute "PNN" "M_K_DQ<20>"
					( Origin gPackager )
				)
				( objectStatus "M_K_DQ<20>" )
			)
			( signal "@baseboard_fab2_lib.baseboard_fab2(sch_1):m_k_dq(21)"
				( attribute "CDS_PHYS_NET_NAME" "M_K_DQ<21>"
					( Origin gPackager )
				)
				( attribute "PNN" "M_K_DQ<21>"
					( Origin gPackager )
				)
				( objectStatus "M_K_DQ<21>" )
			)
			( signal "@baseboard_fab2_lib.baseboard_fab2(sch_1):m_k_dq(22)"
				( attribute "CDS_PHYS_NET_NAME" "M_K_DQ<22>"
					( Origin gPackager )
				)
				( attribute "PNN" "M_K_DQ<22>"
					( Origin gPackager )
				)
				( objectStatus "M_K_DQ<22>" )
			)
			( signal "@baseboard_fab2_lib.baseboard_fab2(sch_1):m_k_dq(23)"
				( attribute "CDS_PHYS_NET_NAME" "M_K_DQ<23>"
					( Origin gPackager )
				)
				( attribute "PNN" "M_K_DQ<23>"
					( Origin gPackager )
				)
				( objectStatus "M_K_DQ<23>" )
			)
			( signal "@baseboard_fab2_lib.baseboard_fab2(sch_1):m_k_dq(24)"
				( attribute "CDS_PHYS_NET_NAME" "M_K_DQ<24>"
					( Origin gPackager )
				)
				( attribute "PNN" "M_K_DQ<24>"
					( Origin gPackager )
				)
				( objectStatus "M_K_DQ<24>" )
			)
			( signal "@baseboard_fab2_lib.baseboard_fab2(sch_1):m_k_dq(25)"
				( attribute "CDS_PHYS_NET_NAME" "M_K_DQ<25>"
					( Origin gPackager )
				)
				( attribute "PNN" "M_K_DQ<25>"
					( Origin gPackager )
				)
				( objectStatus "M_K_DQ<25>" )
			)
			( signal "@baseboard_fab2_lib.baseboard_fab2(sch_1):m_k_dq(26)"
				( attribute "CDS_PHYS_NET_NAME" "M_K_DQ<26>"
					( Origin gPackager )
				)
				( attribute "PNN" "M_K_DQ<26>"
					( Origin gPackager )
				)
				( objectStatus "M_K_DQ<26>" )
			)
			( signal "@baseboard_fab2_lib.baseboard_fab2(sch_1):m_k_dq(27)"
				( attribute "CDS_PHYS_NET_NAME" "M_K_DQ<27>"
					( Origin gPackager )
				)
				( attribute "PNN" "M_K_DQ<27>"
					( Origin gPackager )
				)
				( objectStatus "M_K_DQ<27>" )
			)
			( signal "@baseboard_fab2_lib.baseboard_fab2(sch_1):m_k_dq(28)"
				( attribute "CDS_PHYS_NET_NAME" "M_K_DQ<28>"
					( Origin gPackager )
				)
				( attribute "PNN" "M_K_DQ<28>"
					( Origin gPackager )
				)
				( objectStatus "M_K_DQ<28>" )
			)
			( signal "@baseboard_fab2_lib.baseboard_fab2(sch_1):m_k_dq(29)"
				( attribute "CDS_PHYS_NET_NAME" "M_K_DQ<29>"
					( Origin gPackager )
				)
				( attribute "PNN" "M_K_DQ<29>"
					( Origin gPackager )
				)
				( objectStatus "M_K_DQ<29>" )
			)
			( signal "@baseboard_fab2_lib.baseboard_fab2(sch_1):m_k_dq(30)"
				( attribute "CDS_PHYS_NET_NAME" "M_K_DQ<30>"
					( Origin gPackager )
				)
				( attribute "PNN" "M_K_DQ<30>"
					( Origin gPackager )
				)
				( objectStatus "M_K_DQ<30>" )
			)
			( signal "@baseboard_fab2_lib.baseboard_fab2(sch_1):m_k_dq(31)"
				( attribute "CDS_PHYS_NET_NAME" "M_K_DQ<31>"
					( Origin gPackager )
				)
				( attribute "PNN" "M_K_DQ<31>"
					( Origin gPackager )
				)
				( objectStatus "M_K_DQ<31>" )
			)
			( signal "@baseboard_fab2_lib.baseboard_fab2(sch_1):m_k_dq(32)"
				( attribute "CDS_PHYS_NET_NAME" "M_K_DQ<32>"
					( Origin gPackager )
				)
				( attribute "PNN" "M_K_DQ<32>"
					( Origin gPackager )
				)
				( objectStatus "M_K_DQ<32>" )
			)
			( signal "@baseboard_fab2_lib.baseboard_fab2(sch_1):m_k_dq(33)"
				( attribute "CDS_PHYS_NET_NAME" "M_K_DQ<33>"
					( Origin gPackager )
				)
				( attribute "PNN" "M_K_DQ<33>"
					( Origin gPackager )
				)
				( objectStatus "M_K_DQ<33>" )
			)
			( signal "@baseboard_fab2_lib.baseboard_fab2(sch_1):m_k_dq(34)"
				( attribute "CDS_PHYS_NET_NAME" "M_K_DQ<34>"
					( Origin gPackager )
				)
				( attribute "PNN" "M_K_DQ<34>"
					( Origin gPackager )
				)
				( objectStatus "M_K_DQ<34>" )
			)
			( signal "@baseboard_fab2_lib.baseboard_fab2(sch_1):m_k_dq(35)"
				( attribute "CDS_PHYS_NET_NAME" "M_K_DQ<35>"
					( Origin gPackager )
				)
				( attribute "PNN" "M_K_DQ<35>"
					( Origin gPackager )
				)
				( objectStatus "M_K_DQ<35>" )
			)
			( signal "@baseboard_fab2_lib.baseboard_fab2(sch_1):m_k_dq(36)"
				( attribute "CDS_PHYS_NET_NAME" "M_K_DQ<36>"
					( Origin gPackager )
				)
				( attribute "PNN" "M_K_DQ<36>"
					( Origin gPackager )
				)
				( objectStatus "M_K_DQ<36>" )
			)
			( signal "@baseboard_fab2_lib.baseboard_fab2(sch_1):m_k_dq(37)"
				( attribute "CDS_PHYS_NET_NAME" "M_K_DQ<37>"
					( Origin gPackager )
				)
				( attribute "PNN" "M_K_DQ<37>"
					( Origin gPackager )
				)
				( objectStatus "M_K_DQ<37>" )
			)
			( signal "@baseboard_fab2_lib.baseboard_fab2(sch_1):m_k_dq(38)"
				( attribute "CDS_PHYS_NET_NAME" "M_K_DQ<38>"
					( Origin gPackager )
				)
				( attribute "PNN" "M_K_DQ<38>"
					( Origin gPackager )
				)
				( objectStatus "M_K_DQ<38>" )
			)
			( signal "@baseboard_fab2_lib.baseboard_fab2(sch_1):m_k_dq(39)"
				( attribute "CDS_PHYS_NET_NAME" "M_K_DQ<39>"
					( Origin gPackager )
				)
				( attribute "PNN" "M_K_DQ<39>"
					( Origin gPackager )
				)
				( objectStatus "M_K_DQ<39>" )
			)
			( signal "@baseboard_fab2_lib.baseboard_fab2(sch_1):m_k_dq(40)"
				( attribute "CDS_PHYS_NET_NAME" "M_K_DQ<40>"
					( Origin gPackager )
				)
				( attribute "PNN" "M_K_DQ<40>"
					( Origin gPackager )
				)
				( objectStatus "M_K_DQ<40>" )
			)
			( signal "@baseboard_fab2_lib.baseboard_fab2(sch_1):m_k_dq(41)"
				( attribute "CDS_PHYS_NET_NAME" "M_K_DQ<41>"
					( Origin gPackager )
				)
				( attribute "PNN" "M_K_DQ<41>"
					( Origin gPackager )
				)
				( objectStatus "M_K_DQ<41>" )
			)
			( signal "@baseboard_fab2_lib.baseboard_fab2(sch_1):m_k_dq(42)"
				( attribute "CDS_PHYS_NET_NAME" "M_K_DQ<42>"
					( Origin gPackager )
				)
				( attribute "PNN" "M_K_DQ<42>"
					( Origin gPackager )
				)
				( objectStatus "M_K_DQ<42>" )
			)
			( signal "@baseboard_fab2_lib.baseboard_fab2(sch_1):m_k_dq(43)"
				( attribute "CDS_PHYS_NET_NAME" "M_K_DQ<43>"
					( Origin gPackager )
				)
				( attribute "PNN" "M_K_DQ<43>"
					( Origin gPackager )
				)
				( objectStatus "M_K_DQ<43>" )
			)
			( signal "@baseboard_fab2_lib.baseboard_fab2(sch_1):m_k_dq(44)"
				( attribute "CDS_PHYS_NET_NAME" "M_K_DQ<44>"
					( Origin gPackager )
				)
				( attribute "PNN" "M_K_DQ<44>"
					( Origin gPackager )
				)
				( objectStatus "M_K_DQ<44>" )
			)
			( signal "@baseboard_fab2_lib.baseboard_fab2(sch_1):m_k_dq(45)"
				( attribute "CDS_PHYS_NET_NAME" "M_K_DQ<45>"
					( Origin gPackager )
				)
				( attribute "PNN" "M_K_DQ<45>"
					( Origin gPackager )
				)
				( objectStatus "M_K_DQ<45>" )
			)
			( signal "@baseboard_fab2_lib.baseboard_fab2(sch_1):m_k_dq(46)"
				( attribute "CDS_PHYS_NET_NAME" "M_K_DQ<46>"
					( Origin gPackager )
				)
				( attribute "PNN" "M_K_DQ<46>"
					( Origin gPackager )
				)
				( objectStatus "M_K_DQ<46>" )
			)
			( signal "@baseboard_fab2_lib.baseboard_fab2(sch_1):m_k_dq(47)"
				( attribute "CDS_PHYS_NET_NAME" "M_K_DQ<47>"
					( Origin gPackager )
				)
				( attribute "PNN" "M_K_DQ<47>"
					( Origin gPackager )
				)
				( objectStatus "M_K_DQ<47>" )
			)
			( signal "@baseboard_fab2_lib.baseboard_fab2(sch_1):m_k_dq(48)"
				( attribute "CDS_PHYS_NET_NAME" "M_K_DQ<48>"
					( Origin gPackager )
				)
				( attribute "PNN" "M_K_DQ<48>"
					( Origin gPackager )
				)
				( objectStatus "M_K_DQ<48>" )
			)
			( signal "@baseboard_fab2_lib.baseboard_fab2(sch_1):m_k_dq(49)"
				( attribute "CDS_PHYS_NET_NAME" "M_K_DQ<49>"
					( Origin gPackager )
				)
				( attribute "PNN" "M_K_DQ<49>"
					( Origin gPackager )
				)
				( objectStatus "M_K_DQ<49>" )
			)
			( signal "@baseboard_fab2_lib.baseboard_fab2(sch_1):m_k_dq(50)"
				( attribute "CDS_PHYS_NET_NAME" "M_K_DQ<50>"
					( Origin gPackager )
				)
				( attribute "PNN" "M_K_DQ<50>"
					( Origin gPackager )
				)
				( objectStatus "M_K_DQ<50>" )
			)
			( signal "@baseboard_fab2_lib.baseboard_fab2(sch_1):m_k_dq(51)"
				( attribute "CDS_PHYS_NET_NAME" "M_K_DQ<51>"
					( Origin gPackager )
				)
				( attribute "PNN" "M_K_DQ<51>"
					( Origin gPackager )
				)
				( objectStatus "M_K_DQ<51>" )
			)
			( signal "@baseboard_fab2_lib.baseboard_fab2(sch_1):m_k_dq(52)"
				( attribute "CDS_PHYS_NET_NAME" "M_K_DQ<52>"
					( Origin gPackager )
				)
				( attribute "PNN" "M_K_DQ<52>"
					( Origin gPackager )
				)
				( objectStatus "M_K_DQ<52>" )
			)
			( signal "@baseboard_fab2_lib.baseboard_fab2(sch_1):m_k_dq(53)"
				( attribute "CDS_PHYS_NET_NAME" "M_K_DQ<53>"
					( Origin gPackager )
				)
				( attribute "PNN" "M_K_DQ<53>"
					( Origin gPackager )
				)
				( objectStatus "M_K_DQ<53>" )
			)
			( signal "@baseboard_fab2_lib.baseboard_fab2(sch_1):m_k_dq(54)"
				( attribute "CDS_PHYS_NET_NAME" "M_K_DQ<54>"
					( Origin gPackager )
				)
				( attribute "PNN" "M_K_DQ<54>"
					( Origin gPackager )
				)
				( objectStatus "M_K_DQ<54>" )
			)
			( signal "@baseboard_fab2_lib.baseboard_fab2(sch_1):m_k_dq(55)"
				( attribute "CDS_PHYS_NET_NAME" "M_K_DQ<55>"
					( Origin gPackager )
				)
				( attribute "PNN" "M_K_DQ<55>"
					( Origin gPackager )
				)
				( objectStatus "M_K_DQ<55>" )
			)
			( signal "@baseboard_fab2_lib.baseboard_fab2(sch_1):m_k_dq(56)"
				( attribute "CDS_PHYS_NET_NAME" "M_K_DQ<56>"
					( Origin gPackager )
				)
				( attribute "PNN" "M_K_DQ<56>"
					( Origin gPackager )
				)
				( objectStatus "M_K_DQ<56>" )
			)
			( signal "@baseboard_fab2_lib.baseboard_fab2(sch_1):m_k_dq(57)"
				( attribute "CDS_PHYS_NET_NAME" "M_K_DQ<57>"
					( Origin gPackager )
				)
				( attribute "PNN" "M_K_DQ<57>"
					( Origin gPackager )
				)
				( objectStatus "M_K_DQ<57>" )
			)
			( signal "@baseboard_fab2_lib.baseboard_fab2(sch_1):m_k_dq(58)"
				( attribute "CDS_PHYS_NET_NAME" "M_K_DQ<58>"
					( Origin gPackager )
				)
				( attribute "PNN" "M_K_DQ<58>"
					( Origin gPackager )
				)
				( objectStatus "M_K_DQ<58>" )
			)
			( signal "@baseboard_fab2_lib.baseboard_fab2(sch_1):m_k_dq(59)"
				( attribute "CDS_PHYS_NET_NAME" "M_K_DQ<59>"
					( Origin gPackager )
				)
				( attribute "PNN" "M_K_DQ<59>"
					( Origin gPackager )
				)
				( objectStatus "M_K_DQ<59>" )
			)
			( signal "@baseboard_fab2_lib.baseboard_fab2(sch_1):m_k_dq(60)"
				( attribute "CDS_PHYS_NET_NAME" "M_K_DQ<60>"
					( Origin gPackager )
				)
				( attribute "PNN" "M_K_DQ<60>"
					( Origin gPackager )
				)
				( objectStatus "M_K_DQ<60>" )
			)
			( signal "@baseboard_fab2_lib.baseboard_fab2(sch_1):m_k_dq(61)"
				( attribute "CDS_PHYS_NET_NAME" "M_K_DQ<61>"
					( Origin gPackager )
				)
				( attribute "PNN" "M_K_DQ<61>"
					( Origin gPackager )
				)
				( objectStatus "M_K_DQ<61>" )
			)
			( signal "@baseboard_fab2_lib.baseboard_fab2(sch_1):m_k_dq(62)"
				( attribute "CDS_PHYS_NET_NAME" "M_K_DQ<62>"
					( Origin gPackager )
				)
				( attribute "PNN" "M_K_DQ<62>"
					( Origin gPackager )
				)
				( objectStatus "M_K_DQ<62>" )
			)
			( signal "@baseboard_fab2_lib.baseboard_fab2(sch_1):m_k_dq(63)"
				( attribute "CDS_PHYS_NET_NAME" "M_K_DQ<63>"
					( Origin gPackager )
				)
				( attribute "PNN" "M_K_DQ<63>"
					( Origin gPackager )
				)
				( objectStatus "M_K_DQ<63>" )
			)
			( signal "@baseboard_fab2_lib.baseboard_fab2(sch_1):m_k_dqs_dn(0)"
				( attribute "CDS_PHYS_NET_NAME" "M_K_DQS_DN<0>"
					( Origin gPackager )
				)
				( attribute "PNN" "M_K_DQS_DN<0>"
					( Origin gPackager )
				)
				( objectStatus "M_K_DQS_DN<0>" )
			)
			( signal "@baseboard_fab2_lib.baseboard_fab2(sch_1):m_k_dqs_dn(1)"
				( attribute "CDS_PHYS_NET_NAME" "M_K_DQS_DN<1>"
					( Origin gPackager )
				)
				( attribute "PNN" "M_K_DQS_DN<1>"
					( Origin gPackager )
				)
				( objectStatus "M_K_DQS_DN<1>" )
			)
			( signal "@baseboard_fab2_lib.baseboard_fab2(sch_1):m_k_dqs_dn(2)"
				( attribute "CDS_PHYS_NET_NAME" "M_K_DQS_DN<2>"
					( Origin gPackager )
				)
				( attribute "PNN" "M_K_DQS_DN<2>"
					( Origin gPackager )
				)
				( objectStatus "M_K_DQS_DN<2>" )
			)
			( signal "@baseboard_fab2_lib.baseboard_fab2(sch_1):m_k_dqs_dn(3)"
				( attribute "CDS_PHYS_NET_NAME" "M_K_DQS_DN<3>"
					( Origin gPackager )
				)
				( attribute "PNN" "M_K_DQS_DN<3>"
					( Origin gPackager )
				)
				( objectStatus "M_K_DQS_DN<3>" )
			)
			( signal "@baseboard_fab2_lib.baseboard_fab2(sch_1):m_k_dqs_dn(4)"
				( attribute "CDS_PHYS_NET_NAME" "M_K_DQS_DN<4>"
					( Origin gPackager )
				)
				( attribute "PNN" "M_K_DQS_DN<4>"
					( Origin gPackager )
				)
				( objectStatus "M_K_DQS_DN<4>" )
			)
			( signal "@baseboard_fab2_lib.baseboard_fab2(sch_1):m_k_dqs_dn(5)"
				( attribute "CDS_PHYS_NET_NAME" "M_K_DQS_DN<5>"
					( Origin gPackager )
				)
				( attribute "PNN" "M_K_DQS_DN<5>"
					( Origin gPackager )
				)
				( objectStatus "M_K_DQS_DN<5>" )
			)
			( signal "@baseboard_fab2_lib.baseboard_fab2(sch_1):m_k_dqs_dn(6)"
				( attribute "CDS_PHYS_NET_NAME" "M_K_DQS_DN<6>"
					( Origin gPackager )
				)
				( attribute "PNN" "M_K_DQS_DN<6>"
					( Origin gPackager )
				)
				( objectStatus "M_K_DQS_DN<6>" )
			)
			( signal "@baseboard_fab2_lib.baseboard_fab2(sch_1):m_k_dqs_dn(7)"
				( attribute "CDS_PHYS_NET_NAME" "M_K_DQS_DN<7>"
					( Origin gPackager )
				)
				( attribute "PNN" "M_K_DQS_DN<7>"
					( Origin gPackager )
				)
				( objectStatus "M_K_DQS_DN<7>" )
			)
			( signal "@baseboard_fab2_lib.baseboard_fab2(sch_1):m_k_dqs_dn(8)"
				( attribute "CDS_PHYS_NET_NAME" "M_K_DQS_DN<8>"
					( Origin gPackager )
				)
				( attribute "PNN" "M_K_DQS_DN<8>"
					( Origin gPackager )
				)
				( objectStatus "M_K_DQS_DN<8>" )
			)
			( signal "@baseboard_fab2_lib.baseboard_fab2(sch_1):m_k_dqs_dn(9)"
				( attribute "CDS_PHYS_NET_NAME" "M_K_DQS_DN<9>"
					( Origin gPackager )
				)
				( attribute "PNN" "M_K_DQS_DN<9>"
					( Origin gPackager )
				)
				( objectStatus "M_K_DQS_DN<9>" )
			)
			( signal "@baseboard_fab2_lib.baseboard_fab2(sch_1):m_k_dqs_dn(10)"
				( attribute "CDS_PHYS_NET_NAME" "M_K_DQS_DN<10>"
					( Origin gPackager )
				)
				( attribute "PNN" "M_K_DQS_DN<10>"
					( Origin gPackager )
				)
				( objectStatus "M_K_DQS_DN<10>" )
			)
			( signal "@baseboard_fab2_lib.baseboard_fab2(sch_1):m_k_dqs_dn(11)"
				( attribute "CDS_PHYS_NET_NAME" "M_K_DQS_DN<11>"
					( Origin gPackager )
				)
				( attribute "PNN" "M_K_DQS_DN<11>"
					( Origin gPackager )
				)
				( objectStatus "M_K_DQS_DN<11>" )
			)
			( signal "@baseboard_fab2_lib.baseboard_fab2(sch_1):m_k_dqs_dn(12)"
				( attribute "CDS_PHYS_NET_NAME" "M_K_DQS_DN<12>"
					( Origin gPackager )
				)
				( attribute "PNN" "M_K_DQS_DN<12>"
					( Origin gPackager )
				)
				( objectStatus "M_K_DQS_DN<12>" )
			)
			( signal "@baseboard_fab2_lib.baseboard_fab2(sch_1):m_k_dqs_dn(13)"
				( attribute "CDS_PHYS_NET_NAME" "M_K_DQS_DN<13>"
					( Origin gPackager )
				)
				( attribute "PNN" "M_K_DQS_DN<13>"
					( Origin gPackager )
				)
				( objectStatus "M_K_DQS_DN<13>" )
			)
			( signal "@baseboard_fab2_lib.baseboard_fab2(sch_1):m_k_dqs_dn(14)"
				( attribute "CDS_PHYS_NET_NAME" "M_K_DQS_DN<14>"
					( Origin gPackager )
				)
				( attribute "PNN" "M_K_DQS_DN<14>"
					( Origin gPackager )
				)
				( objectStatus "M_K_DQS_DN<14>" )
			)
			( signal "@baseboard_fab2_lib.baseboard_fab2(sch_1):m_k_dqs_dn(15)"
				( attribute "CDS_PHYS_NET_NAME" "M_K_DQS_DN<15>"
					( Origin gPackager )
				)
				( attribute "PNN" "M_K_DQS_DN<15>"
					( Origin gPackager )
				)
				( objectStatus "M_K_DQS_DN<15>" )
			)
			( signal "@baseboard_fab2_lib.baseboard_fab2(sch_1):m_k_dqs_dn(16)"
				( attribute "CDS_PHYS_NET_NAME" "M_K_DQS_DN<16>"
					( Origin gPackager )
				)
				( attribute "PNN" "M_K_DQS_DN<16>"
					( Origin gPackager )
				)
				( objectStatus "M_K_DQS_DN<16>" )
			)
			( signal "@baseboard_fab2_lib.baseboard_fab2(sch_1):m_k_dqs_dn(17)"
				( attribute "CDS_PHYS_NET_NAME" "M_K_DQS_DN<17>"
					( Origin gPackager )
				)
				( attribute "PNN" "M_K_DQS_DN<17>"
					( Origin gPackager )
				)
				( objectStatus "M_K_DQS_DN<17>" )
			)
			( signal "@baseboard_fab2_lib.baseboard_fab2(sch_1):m_k_dqs_dp(0)"
				( attribute "CDS_PHYS_NET_NAME" "M_K_DQS_DP<0>"
					( Origin gPackager )
				)
				( attribute "PNN" "M_K_DQS_DP<0>"
					( Origin gPackager )
				)
				( objectStatus "M_K_DQS_DP<0>" )
			)
			( signal "@baseboard_fab2_lib.baseboard_fab2(sch_1):m_k_dqs_dp(1)"
				( attribute "CDS_PHYS_NET_NAME" "M_K_DQS_DP<1>"
					( Origin gPackager )
				)
				( attribute "PNN" "M_K_DQS_DP<1>"
					( Origin gPackager )
				)
				( objectStatus "M_K_DQS_DP<1>" )
			)
			( signal "@baseboard_fab2_lib.baseboard_fab2(sch_1):m_k_dqs_dp(2)"
				( attribute "CDS_PHYS_NET_NAME" "M_K_DQS_DP<2>"
					( Origin gPackager )
				)
				( attribute "PNN" "M_K_DQS_DP<2>"
					( Origin gPackager )
				)
				( objectStatus "M_K_DQS_DP<2>" )
			)
			( signal "@baseboard_fab2_lib.baseboard_fab2(sch_1):m_k_dqs_dp(3)"
				( attribute "CDS_PHYS_NET_NAME" "M_K_DQS_DP<3>"
					( Origin gPackager )
				)
				( attribute "PNN" "M_K_DQS_DP<3>"
					( Origin gPackager )
				)
				( objectStatus "M_K_DQS_DP<3>" )
			)
			( signal "@baseboard_fab2_lib.baseboard_fab2(sch_1):m_k_dqs_dp(4)"
				( attribute "CDS_PHYS_NET_NAME" "M_K_DQS_DP<4>"
					( Origin gPackager )
				)
				( attribute "PNN" "M_K_DQS_DP<4>"
					( Origin gPackager )
				)
				( objectStatus "M_K_DQS_DP<4>" )
			)
			( signal "@baseboard_fab2_lib.baseboard_fab2(sch_1):m_k_dqs_dp(5)"
				( attribute "CDS_PHYS_NET_NAME" "M_K_DQS_DP<5>"
					( Origin gPackager )
				)
				( attribute "PNN" "M_K_DQS_DP<5>"
					( Origin gPackager )
				)
				( objectStatus "M_K_DQS_DP<5>" )
			)
			( signal "@baseboard_fab2_lib.baseboard_fab2(sch_1):m_k_dqs_dp(6)"
				( attribute "CDS_PHYS_NET_NAME" "M_K_DQS_DP<6>"
					( Origin gPackager )
				)
				( attribute "PNN" "M_K_DQS_DP<6>"
					( Origin gPackager )
				)
				( objectStatus "M_K_DQS_DP<6>" )
			)
			( signal "@baseboard_fab2_lib.baseboard_fab2(sch_1):m_k_dqs_dp(7)"
				( attribute "CDS_PHYS_NET_NAME" "M_K_DQS_DP<7>"
					( Origin gPackager )
				)
				( attribute "PNN" "M_K_DQS_DP<7>"
					( Origin gPackager )
				)
				( objectStatus "M_K_DQS_DP<7>" )
			)
			( signal "@baseboard_fab2_lib.baseboard_fab2(sch_1):m_k_dqs_dp(8)"
				( attribute "CDS_PHYS_NET_NAME" "M_K_DQS_DP<8>"
					( Origin gPackager )
				)
				( attribute "PNN" "M_K_DQS_DP<8>"
					( Origin gPackager )
				)
				( objectStatus "M_K_DQS_DP<8>" )
			)
			( signal "@baseboard_fab2_lib.baseboard_fab2(sch_1):m_k_dqs_dp(9)"
				( attribute "CDS_PHYS_NET_NAME" "M_K_DQS_DP<9>"
					( Origin gPackager )
				)
				( attribute "PNN" "M_K_DQS_DP<9>"
					( Origin gPackager )
				)
				( objectStatus "M_K_DQS_DP<9>" )
			)
			( signal "@baseboard_fab2_lib.baseboard_fab2(sch_1):m_k_dqs_dp(10)"
				( attribute "CDS_PHYS_NET_NAME" "M_K_DQS_DP<10>"
					( Origin gPackager )
				)
				( attribute "PNN" "M_K_DQS_DP<10>"
					( Origin gPackager )
				)
				( objectStatus "M_K_DQS_DP<10>" )
			)
			( signal "@baseboard_fab2_lib.baseboard_fab2(sch_1):m_k_dqs_dp(11)"
				( attribute "CDS_PHYS_NET_NAME" "M_K_DQS_DP<11>"
					( Origin gPackager )
				)
				( attribute "PNN" "M_K_DQS_DP<11>"
					( Origin gPackager )
				)
				( objectStatus "M_K_DQS_DP<11>" )
			)
			( signal "@baseboard_fab2_lib.baseboard_fab2(sch_1):m_k_dqs_dp(12)"
				( attribute "CDS_PHYS_NET_NAME" "M_K_DQS_DP<12>"
					( Origin gPackager )
				)
				( attribute "PNN" "M_K_DQS_DP<12>"
					( Origin gPackager )
				)
				( objectStatus "M_K_DQS_DP<12>" )
			)
			( signal "@baseboard_fab2_lib.baseboard_fab2(sch_1):m_k_dqs_dp(13)"
				( attribute "CDS_PHYS_NET_NAME" "M_K_DQS_DP<13>"
					( Origin gPackager )
				)
				( attribute "PNN" "M_K_DQS_DP<13>"
					( Origin gPackager )
				)
				( objectStatus "M_K_DQS_DP<13>" )
			)
			( signal "@baseboard_fab2_lib.baseboard_fab2(sch_1):m_k_dqs_dp(14)"
				( attribute "CDS_PHYS_NET_NAME" "M_K_DQS_DP<14>"
					( Origin gPackager )
				)
				( attribute "PNN" "M_K_DQS_DP<14>"
					( Origin gPackager )
				)
				( objectStatus "M_K_DQS_DP<14>" )
			)
			( signal "@baseboard_fab2_lib.baseboard_fab2(sch_1):m_k_dqs_dp(15)"
				( attribute "CDS_PHYS_NET_NAME" "M_K_DQS_DP<15>"
					( Origin gPackager )
				)
				( attribute "PNN" "M_K_DQS_DP<15>"
					( Origin gPackager )
				)
				( objectStatus "M_K_DQS_DP<15>" )
			)
			( signal "@baseboard_fab2_lib.baseboard_fab2(sch_1):m_k_dqs_dp(16)"
				( attribute "CDS_PHYS_NET_NAME" "M_K_DQS_DP<16>"
					( Origin gPackager )
				)
				( attribute "PNN" "M_K_DQS_DP<16>"
					( Origin gPackager )
				)
				( objectStatus "M_K_DQS_DP<16>" )
			)
			( signal "@baseboard_fab2_lib.baseboard_fab2(sch_1):m_k_dqs_dp(17)"
				( attribute "CDS_PHYS_NET_NAME" "M_K_DQS_DP<17>"
					( Origin gPackager )
				)
				( attribute "PNN" "M_K_DQS_DP<17>"
					( Origin gPackager )
				)
				( objectStatus "M_K_DQS_DP<17>" )
			)
			( signal "@baseboard_fab2_lib.baseboard_fab2(sch_1):m_k_ecc(0)"
				( attribute "CDS_PHYS_NET_NAME" "M_K_ECC<0>"
					( Origin gPackager )
				)
				( attribute "PNN" "M_K_ECC<0>"
					( Origin gPackager )
				)
				( objectStatus "M_K_ECC<0>" )
			)
			( signal "@baseboard_fab2_lib.baseboard_fab2(sch_1):m_k_ecc(1)"
				( attribute "CDS_PHYS_NET_NAME" "M_K_ECC<1>"
					( Origin gPackager )
				)
				( attribute "PNN" "M_K_ECC<1>"
					( Origin gPackager )
				)
				( objectStatus "M_K_ECC<1>" )
			)
			( signal "@baseboard_fab2_lib.baseboard_fab2(sch_1):m_k_ecc(2)"
				( attribute "CDS_PHYS_NET_NAME" "M_K_ECC<2>"
					( Origin gPackager )
				)
				( attribute "PNN" "M_K_ECC<2>"
					( Origin gPackager )
				)
				( objectStatus "M_K_ECC<2>" )
			)
			( signal "@baseboard_fab2_lib.baseboard_fab2(sch_1):m_k_ecc(3)"
				( attribute "CDS_PHYS_NET_NAME" "M_K_ECC<3>"
					( Origin gPackager )
				)
				( attribute "PNN" "M_K_ECC<3>"
					( Origin gPackager )
				)
				( objectStatus "M_K_ECC<3>" )
			)
			( signal "@baseboard_fab2_lib.baseboard_fab2(sch_1):m_k_ecc(4)"
				( attribute "CDS_PHYS_NET_NAME" "M_K_ECC<4>"
					( Origin gPackager )
				)
				( attribute "PNN" "M_K_ECC<4>"
					( Origin gPackager )
				)
				( objectStatus "M_K_ECC<4>" )
			)
			( signal "@baseboard_fab2_lib.baseboard_fab2(sch_1):m_k_ecc(5)"
				( attribute "CDS_PHYS_NET_NAME" "M_K_ECC<5>"
					( Origin gPackager )
				)
				( attribute "PNN" "M_K_ECC<5>"
					( Origin gPackager )
				)
				( objectStatus "M_K_ECC<5>" )
			)
			( signal "@baseboard_fab2_lib.baseboard_fab2(sch_1):m_k_ecc(6)"
				( attribute "CDS_PHYS_NET_NAME" "M_K_ECC<6>"
					( Origin gPackager )
				)
				( attribute "PNN" "M_K_ECC<6>"
					( Origin gPackager )
				)
				( objectStatus "M_K_ECC<6>" )
			)
			( signal "@baseboard_fab2_lib.baseboard_fab2(sch_1):m_k_ecc(7)"
				( attribute "CDS_PHYS_NET_NAME" "M_K_ECC<7>"
					( Origin gPackager )
				)
				( attribute "PNN" "M_K_ECC<7>"
					( Origin gPackager )
				)
				( objectStatus "M_K_ECC<7>" )
			)
			( signal "@baseboard_fab2_lib.baseboard_fab2(sch_1):m_k_ma(0)"
				( attribute "CDS_PHYS_NET_NAME" "M_K_MA<0>"
					( Origin gPackager )
				)
				( attribute "PNN" "M_K_MA<0>"
					( Origin gPackager )
				)
				( objectStatus "M_K_MA<0>" )
			)
			( signal "@baseboard_fab2_lib.baseboard_fab2(sch_1):m_k_ma(1)"
				( attribute "CDS_PHYS_NET_NAME" "M_K_MA<1>"
					( Origin gPackager )
				)
				( attribute "PNN" "M_K_MA<1>"
					( Origin gPackager )
				)
				( objectStatus "M_K_MA<1>" )
			)
			( signal "@baseboard_fab2_lib.baseboard_fab2(sch_1):m_k_ma(2)"
				( attribute "CDS_PHYS_NET_NAME" "M_K_MA<2>"
					( Origin gPackager )
				)
				( attribute "PNN" "M_K_MA<2>"
					( Origin gPackager )
				)
				( objectStatus "M_K_MA<2>" )
			)
			( signal "@baseboard_fab2_lib.baseboard_fab2(sch_1):m_k_ma(3)"
				( attribute "CDS_PHYS_NET_NAME" "M_K_MA<3>"
					( Origin gPackager )
				)
				( attribute "PNN" "M_K_MA<3>"
					( Origin gPackager )
				)
				( objectStatus "M_K_MA<3>" )
			)
			( signal "@baseboard_fab2_lib.baseboard_fab2(sch_1):m_k_ma(4)"
				( attribute "CDS_PHYS_NET_NAME" "M_K_MA<4>"
					( Origin gPackager )
				)
				( attribute "PNN" "M_K_MA<4>"
					( Origin gPackager )
				)
				( objectStatus "M_K_MA<4>" )
			)
			( signal "@baseboard_fab2_lib.baseboard_fab2(sch_1):m_k_ma(5)"
				( attribute "CDS_PHYS_NET_NAME" "M_K_MA<5>"
					( Origin gPackager )
				)
				( attribute "PNN" "M_K_MA<5>"
					( Origin gPackager )
				)
				( objectStatus "M_K_MA<5>" )
			)
			( signal "@baseboard_fab2_lib.baseboard_fab2(sch_1):m_k_ma(6)"
				( attribute "CDS_PHYS_NET_NAME" "M_K_MA<6>"
					( Origin gPackager )
				)
				( attribute "PNN" "M_K_MA<6>"
					( Origin gPackager )
				)
				( objectStatus "M_K_MA<6>" )
			)
			( signal "@baseboard_fab2_lib.baseboard_fab2(sch_1):m_k_ma(7)"
				( attribute "CDS_PHYS_NET_NAME" "M_K_MA<7>"
					( Origin gPackager )
				)
				( attribute "PNN" "M_K_MA<7>"
					( Origin gPackager )
				)
				( objectStatus "M_K_MA<7>" )
			)
			( signal "@baseboard_fab2_lib.baseboard_fab2(sch_1):m_k_ma(8)"
				( attribute "CDS_PHYS_NET_NAME" "M_K_MA<8>"
					( Origin gPackager )
				)
				( attribute "PNN" "M_K_MA<8>"
					( Origin gPackager )
				)
				( objectStatus "M_K_MA<8>" )
			)
			( signal "@baseboard_fab2_lib.baseboard_fab2(sch_1):m_k_ma(9)"
				( attribute "CDS_PHYS_NET_NAME" "M_K_MA<9>"
					( Origin gPackager )
				)
				( attribute "PNN" "M_K_MA<9>"
					( Origin gPackager )
				)
				( objectStatus "M_K_MA<9>" )
			)
			( signal "@baseboard_fab2_lib.baseboard_fab2(sch_1):m_k_ma(10)"
				( attribute "CDS_PHYS_NET_NAME" "M_K_MA<10>"
					( Origin gPackager )
				)
				( attribute "PNN" "M_K_MA<10>"
					( Origin gPackager )
				)
				( objectStatus "M_K_MA<10>" )
			)
			( signal "@baseboard_fab2_lib.baseboard_fab2(sch_1):m_k_ma(11)"
				( attribute "CDS_PHYS_NET_NAME" "M_K_MA<11>"
					( Origin gPackager )
				)
				( attribute "PNN" "M_K_MA<11>"
					( Origin gPackager )
				)
				( objectStatus "M_K_MA<11>" )
			)
			( signal "@baseboard_fab2_lib.baseboard_fab2(sch_1):m_k_ma(12)"
				( attribute "CDS_PHYS_NET_NAME" "M_K_MA<12>"
					( Origin gPackager )
				)
				( attribute "PNN" "M_K_MA<12>"
					( Origin gPackager )
				)
				( objectStatus "M_K_MA<12>" )
			)
			( signal "@baseboard_fab2_lib.baseboard_fab2(sch_1):m_k_ma(13)"
				( attribute "CDS_PHYS_NET_NAME" "M_K_MA<13>"
					( Origin gPackager )
				)
				( attribute "PNN" "M_K_MA<13>"
					( Origin gPackager )
				)
				( objectStatus "M_K_MA<13>" )
			)
			( signal "@baseboard_fab2_lib.baseboard_fab2(sch_1):m_k_ma(14)"
				( attribute "CDS_PHYS_NET_NAME" "M_K_MA<14>"
					( Origin gPackager )
				)
				( attribute "PNN" "M_K_MA<14>"
					( Origin gPackager )
				)
				( objectStatus "M_K_MA<14>" )
			)
			( signal "@baseboard_fab2_lib.baseboard_fab2(sch_1):m_k_ma(15)"
				( attribute "CDS_PHYS_NET_NAME" "M_K_MA<15>"
					( Origin gPackager )
				)
				( attribute "PNN" "M_K_MA<15>"
					( Origin gPackager )
				)
				( objectStatus "M_K_MA<15>" )
			)
			( signal "@baseboard_fab2_lib.baseboard_fab2(sch_1):m_k_ma(16)"
				( attribute "CDS_PHYS_NET_NAME" "M_K_MA<16>"
					( Origin gPackager )
				)
				( attribute "PNN" "M_K_MA<16>"
					( Origin gPackager )
				)
				( objectStatus "M_K_MA<16>" )
			)
			( signal "@baseboard_fab2_lib.baseboard_fab2(sch_1):m_k_ma(17)"
				( attribute "CDS_PHYS_NET_NAME" "M_K_MA<17>"
					( Origin gPackager )
				)
				( attribute "PNN" "M_K_MA<17>"
					( Origin gPackager )
				)
				( objectStatus "M_K_MA<17>" )
			)
			( signal "@baseboard_fab2_lib.baseboard_fab2(sch_1):m_k_odt(0)"
				( attribute "CDS_PHYS_NET_NAME" "M_K_ODT<0>"
					( Origin gPackager )
				)
				( attribute "PNN" "M_K_ODT<0>"
					( Origin gPackager )
				)
				( objectStatus "M_K_ODT<0>" )
			)
			( signal "@baseboard_fab2_lib.baseboard_fab2(sch_1):m_k_odt(1)"
				( attribute "CDS_PHYS_NET_NAME" "M_K_ODT<1>"
					( Origin gPackager )
				)
				( attribute "PNN" "M_K_ODT<1>"
					( Origin gPackager )
				)
				( objectStatus "M_K_ODT<1>" )
			)
			( signal "@baseboard_fab2_lib.baseboard_fab2(sch_1):m_k_odt(2)"
				( attribute "CDS_PHYS_NET_NAME" "M_K_ODT<2>"
					( Origin gPackager )
				)
				( attribute "PNN" "M_K_ODT<2>"
					( Origin gPackager )
				)
				( objectStatus "M_K_ODT<2>" )
			)
			( signal "@baseboard_fab2_lib.baseboard_fab2(sch_1):m_k_odt(3)"
				( attribute "CDS_PHYS_NET_NAME" "M_K_ODT<3>"
					( Origin gPackager )
				)
				( attribute "PNN" "M_K_ODT<3>"
					( Origin gPackager )
				)
				( objectStatus "M_K_ODT<3>" )
			)
			( signal "@baseboard_fab2_lib.baseboard_fab2(sch_1):m_k_par"
				( attribute "CDS_PHYS_NET_NAME" "M_K_PAR"
					( Origin gPackager )
				)
				( objectStatus "M_K_PAR" )
			)
			( signal "@baseboard_fab2_lib.baseboard_fab2(sch_1):m_l_act_n"
				( attribute "CDS_PHYS_NET_NAME" "M_L_ACT_N"
					( Origin gPackager )
				)
				( objectStatus "M_L_ACT_N" )
			)
			( signal "@baseboard_fab2_lib.baseboard_fab2(sch_1):m_l_alert_n"
				( attribute "CDS_PHYS_NET_NAME" "M_L_ALERT_N"
					( Origin gPackager )
				)
				( objectStatus "M_L_ALERT_N" )
			)
			( signal "@baseboard_fab2_lib.baseboard_fab2(sch_1):m_l_ba(0)"
				( attribute "CDS_PHYS_NET_NAME" "M_L_BA<0>"
					( Origin gPackager )
				)
				( attribute "PNN" "M_L_BA<0>"
					( Origin gPackager )
				)
				( objectStatus "M_L_BA<0>" )
			)
			( signal "@baseboard_fab2_lib.baseboard_fab2(sch_1):m_l_ba(1)"
				( attribute "CDS_PHYS_NET_NAME" "M_L_BA<1>"
					( Origin gPackager )
				)
				( attribute "PNN" "M_L_BA<1>"
					( Origin gPackager )
				)
				( objectStatus "M_L_BA<1>" )
			)
			( signal "@baseboard_fab2_lib.baseboard_fab2(sch_1):m_l_bg(0)"
				( attribute "CDS_PHYS_NET_NAME" "M_L_BG<0>"
					( Origin gPackager )
				)
				( attribute "PNN" "M_L_BG<0>"
					( Origin gPackager )
				)
				( objectStatus "M_L_BG<0>" )
			)
			( signal "@baseboard_fab2_lib.baseboard_fab2(sch_1):m_l_bg(1)"
				( attribute "CDS_PHYS_NET_NAME" "M_L_BG<1>"
					( Origin gPackager )
				)
				( attribute "PNN" "M_L_BG<1>"
					( Origin gPackager )
				)
				( objectStatus "M_L_BG<1>" )
			)
			( signal "@baseboard_fab2_lib.baseboard_fab2(sch_1):m_l_c(2)"
				( attribute "CDS_PHYS_NET_NAME" "M_L_C<2>"
					( Origin gPackager )
				)
				( attribute "PNN" "M_L_C<2>"
					( Origin gPackager )
				)
				( objectStatus "M_L_C<2>" )
			)
			( signal "@baseboard_fab2_lib.baseboard_fab2(sch_1):m_l_cke(0)"
				( attribute "CDS_PHYS_NET_NAME" "M_L_CKE<0>"
					( Origin gPackager )
				)
				( attribute "PNN" "M_L_CKE<0>"
					( Origin gPackager )
				)
				( objectStatus "M_L_CKE<0>" )
			)
			( signal "@baseboard_fab2_lib.baseboard_fab2(sch_1):m_l_cke(1)"
				( attribute "CDS_PHYS_NET_NAME" "M_L_CKE<1>"
					( Origin gPackager )
				)
				( attribute "PNN" "M_L_CKE<1>"
					( Origin gPackager )
				)
				( objectStatus "M_L_CKE<1>" )
			)
			( signal "@baseboard_fab2_lib.baseboard_fab2(sch_1):m_l_cke(2)"
				( attribute "CDS_PHYS_NET_NAME" "M_L_CKE<2>"
					( Origin gPackager )
				)
				( attribute "PNN" "M_L_CKE<2>"
					( Origin gPackager )
				)
				( objectStatus "M_L_CKE<2>" )
			)
			( signal "@baseboard_fab2_lib.baseboard_fab2(sch_1):m_l_cke(3)"
				( attribute "CDS_PHYS_NET_NAME" "M_L_CKE<3>"
					( Origin gPackager )
				)
				( attribute "PNN" "M_L_CKE<3>"
					( Origin gPackager )
				)
				( objectStatus "M_L_CKE<3>" )
			)
			( signal "@baseboard_fab2_lib.baseboard_fab2(sch_1):m_l_clk_dn(0)"
				( attribute "CDS_PHYS_NET_NAME" "M_L_CLK_DN<0>"
					( Origin gPackager )
				)
				( attribute "PNN" "M_L_CLK_DN<0>"
					( Origin gPackager )
				)
				( objectStatus "M_L_CLK_DN<0>" )
			)
			( signal "@baseboard_fab2_lib.baseboard_fab2(sch_1):m_l_clk_dn(1)"
				( attribute "CDS_PHYS_NET_NAME" "M_L_CLK_DN<1>"
					( Origin gPackager )
				)
				( attribute "PNN" "M_L_CLK_DN<1>"
					( Origin gPackager )
				)
				( objectStatus "M_L_CLK_DN<1>" )
			)
			( signal "@baseboard_fab2_lib.baseboard_fab2(sch_1):m_l_clk_dn(2)"
				( attribute "CDS_PHYS_NET_NAME" "M_L_CLK_DN<2>"
					( Origin gPackager )
				)
				( attribute "PNN" "M_L_CLK_DN<2>"
					( Origin gPackager )
				)
				( objectStatus "M_L_CLK_DN<2>" )
			)
			( signal "@baseboard_fab2_lib.baseboard_fab2(sch_1):m_l_clk_dn(3)"
				( attribute "CDS_PHYS_NET_NAME" "M_L_CLK_DN<3>"
					( Origin gPackager )
				)
				( attribute "PNN" "M_L_CLK_DN<3>"
					( Origin gPackager )
				)
				( objectStatus "M_L_CLK_DN<3>" )
			)
			( signal "@baseboard_fab2_lib.baseboard_fab2(sch_1):m_l_clk_dp(0)"
				( attribute "CDS_PHYS_NET_NAME" "M_L_CLK_DP<0>"
					( Origin gPackager )
				)
				( attribute "PNN" "M_L_CLK_DP<0>"
					( Origin gPackager )
				)
				( objectStatus "M_L_CLK_DP<0>" )
			)
			( signal "@baseboard_fab2_lib.baseboard_fab2(sch_1):m_l_clk_dp(1)"
				( attribute "CDS_PHYS_NET_NAME" "M_L_CLK_DP<1>"
					( Origin gPackager )
				)
				( attribute "PNN" "M_L_CLK_DP<1>"
					( Origin gPackager )
				)
				( objectStatus "M_L_CLK_DP<1>" )
			)
			( signal "@baseboard_fab2_lib.baseboard_fab2(sch_1):m_l_clk_dp(2)"
				( attribute "CDS_PHYS_NET_NAME" "M_L_CLK_DP<2>"
					( Origin gPackager )
				)
				( attribute "PNN" "M_L_CLK_DP<2>"
					( Origin gPackager )
				)
				( objectStatus "M_L_CLK_DP<2>" )
			)
			( signal "@baseboard_fab2_lib.baseboard_fab2(sch_1):m_l_clk_dp(3)"
				( attribute "CDS_PHYS_NET_NAME" "M_L_CLK_DP<3>"
					( Origin gPackager )
				)
				( attribute "PNN" "M_L_CLK_DP<3>"
					( Origin gPackager )
				)
				( objectStatus "M_L_CLK_DP<3>" )
			)
			( signal "@baseboard_fab2_lib.baseboard_fab2(sch_1):m_l_cs_n(0)"
				( attribute "CDS_PHYS_NET_NAME" "M_L_CS_N<0>"
					( Origin gPackager )
				)
				( attribute "PNN" "M_L_CS_N<0>"
					( Origin gPackager )
				)
				( objectStatus "M_L_CS_N<0>" )
			)
			( signal "@baseboard_fab2_lib.baseboard_fab2(sch_1):m_l_cs_n(1)"
				( attribute "CDS_PHYS_NET_NAME" "M_L_CS_N<1>"
					( Origin gPackager )
				)
				( attribute "PNN" "M_L_CS_N<1>"
					( Origin gPackager )
				)
				( objectStatus "M_L_CS_N<1>" )
			)
			( signal "@baseboard_fab2_lib.baseboard_fab2(sch_1):m_l_cs_n(2)"
				( attribute "CDS_PHYS_NET_NAME" "M_L_CS_N<2>"
					( Origin gPackager )
				)
				( attribute "PNN" "M_L_CS_N<2>"
					( Origin gPackager )
				)
				( objectStatus "M_L_CS_N<2>" )
			)
			( signal "@baseboard_fab2_lib.baseboard_fab2(sch_1):m_l_cs_n(3)"
				( attribute "CDS_PHYS_NET_NAME" "M_L_CS_N<3>"
					( Origin gPackager )
				)
				( attribute "PNN" "M_L_CS_N<3>"
					( Origin gPackager )
				)
				( objectStatus "M_L_CS_N<3>" )
			)
			( signal "@baseboard_fab2_lib.baseboard_fab2(sch_1):m_l_cs_n(4)"
				( attribute "CDS_PHYS_NET_NAME" "M_L_CS_N<4>"
					( Origin gPackager )
				)
				( attribute "PNN" "M_L_CS_N<4>"
					( Origin gPackager )
				)
				( objectStatus "M_L_CS_N<4>" )
			)
			( signal "@baseboard_fab2_lib.baseboard_fab2(sch_1):m_l_cs_n(5)"
				( attribute "CDS_PHYS_NET_NAME" "M_L_CS_N<5>"
					( Origin gPackager )
				)
				( attribute "PNN" "M_L_CS_N<5>"
					( Origin gPackager )
				)
				( objectStatus "M_L_CS_N<5>" )
			)
			( signal "@baseboard_fab2_lib.baseboard_fab2(sch_1):m_l_cs_n(6)"
				( attribute "CDS_PHYS_NET_NAME" "M_L_CS_N<6>"
					( Origin gPackager )
				)
				( attribute "PNN" "M_L_CS_N<6>"
					( Origin gPackager )
				)
				( objectStatus "M_L_CS_N<6>" )
			)
			( signal "@baseboard_fab2_lib.baseboard_fab2(sch_1):m_l_cs_n(7)"
				( attribute "CDS_PHYS_NET_NAME" "M_L_CS_N<7>"
					( Origin gPackager )
				)
				( attribute "PNN" "M_L_CS_N<7>"
					( Origin gPackager )
				)
				( objectStatus "M_L_CS_N<7>" )
			)
			( signal "@baseboard_fab2_lib.baseboard_fab2(sch_1):m_l_dq(0)"
				( attribute "CDS_PHYS_NET_NAME" "M_L_DQ<0>"
					( Origin gPackager )
				)
				( attribute "PNN" "M_L_DQ<0>"
					( Origin gPackager )
				)
				( objectStatus "M_L_DQ<0>" )
			)
			( signal "@baseboard_fab2_lib.baseboard_fab2(sch_1):m_l_dq(1)"
				( attribute "CDS_PHYS_NET_NAME" "M_L_DQ<1>"
					( Origin gPackager )
				)
				( attribute "PNN" "M_L_DQ<1>"
					( Origin gPackager )
				)
				( objectStatus "M_L_DQ<1>" )
			)
			( signal "@baseboard_fab2_lib.baseboard_fab2(sch_1):m_l_dq(2)"
				( attribute "CDS_PHYS_NET_NAME" "M_L_DQ<2>"
					( Origin gPackager )
				)
				( attribute "PNN" "M_L_DQ<2>"
					( Origin gPackager )
				)
				( objectStatus "M_L_DQ<2>" )
			)
			( signal "@baseboard_fab2_lib.baseboard_fab2(sch_1):m_l_dq(3)"
				( attribute "CDS_PHYS_NET_NAME" "M_L_DQ<3>"
					( Origin gPackager )
				)
				( attribute "PNN" "M_L_DQ<3>"
					( Origin gPackager )
				)
				( objectStatus "M_L_DQ<3>" )
			)
			( signal "@baseboard_fab2_lib.baseboard_fab2(sch_1):m_l_dq(4)"
				( attribute "CDS_PHYS_NET_NAME" "M_L_DQ<4>"
					( Origin gPackager )
				)
				( attribute "PNN" "M_L_DQ<4>"
					( Origin gPackager )
				)
				( objectStatus "M_L_DQ<4>" )
			)
			( signal "@baseboard_fab2_lib.baseboard_fab2(sch_1):m_l_dq(5)"
				( attribute "CDS_PHYS_NET_NAME" "M_L_DQ<5>"
					( Origin gPackager )
				)
				( attribute "PNN" "M_L_DQ<5>"
					( Origin gPackager )
				)
				( objectStatus "M_L_DQ<5>" )
			)
			( signal "@baseboard_fab2_lib.baseboard_fab2(sch_1):m_l_dq(6)"
				( attribute "CDS_PHYS_NET_NAME" "M_L_DQ<6>"
					( Origin gPackager )
				)
				( attribute "PNN" "M_L_DQ<6>"
					( Origin gPackager )
				)
				( objectStatus "M_L_DQ<6>" )
			)
			( signal "@baseboard_fab2_lib.baseboard_fab2(sch_1):m_l_dq(7)"
				( attribute "CDS_PHYS_NET_NAME" "M_L_DQ<7>"
					( Origin gPackager )
				)
				( attribute "PNN" "M_L_DQ<7>"
					( Origin gPackager )
				)
				( objectStatus "M_L_DQ<7>" )
			)
			( signal "@baseboard_fab2_lib.baseboard_fab2(sch_1):m_l_dq(8)"
				( attribute "CDS_PHYS_NET_NAME" "M_L_DQ<8>"
					( Origin gPackager )
				)
				( attribute "PNN" "M_L_DQ<8>"
					( Origin gPackager )
				)
				( objectStatus "M_L_DQ<8>" )
			)
			( signal "@baseboard_fab2_lib.baseboard_fab2(sch_1):m_l_dq(9)"
				( attribute "CDS_PHYS_NET_NAME" "M_L_DQ<9>"
					( Origin gPackager )
				)
				( attribute "PNN" "M_L_DQ<9>"
					( Origin gPackager )
				)
				( objectStatus "M_L_DQ<9>" )
			)
			( signal "@baseboard_fab2_lib.baseboard_fab2(sch_1):m_l_dq(10)"
				( attribute "CDS_PHYS_NET_NAME" "M_L_DQ<10>"
					( Origin gPackager )
				)
				( attribute "PNN" "M_L_DQ<10>"
					( Origin gPackager )
				)
				( objectStatus "M_L_DQ<10>" )
			)
			( signal "@baseboard_fab2_lib.baseboard_fab2(sch_1):m_l_dq(11)"
				( attribute "CDS_PHYS_NET_NAME" "M_L_DQ<11>"
					( Origin gPackager )
				)
				( attribute "PNN" "M_L_DQ<11>"
					( Origin gPackager )
				)
				( objectStatus "M_L_DQ<11>" )
			)
			( signal "@baseboard_fab2_lib.baseboard_fab2(sch_1):m_l_dq(12)"
				( attribute "CDS_PHYS_NET_NAME" "M_L_DQ<12>"
					( Origin gPackager )
				)
				( attribute "PNN" "M_L_DQ<12>"
					( Origin gPackager )
				)
				( objectStatus "M_L_DQ<12>" )
			)
			( signal "@baseboard_fab2_lib.baseboard_fab2(sch_1):m_l_dq(13)"
				( attribute "CDS_PHYS_NET_NAME" "M_L_DQ<13>"
					( Origin gPackager )
				)
				( attribute "PNN" "M_L_DQ<13>"
					( Origin gPackager )
				)
				( objectStatus "M_L_DQ<13>" )
			)
			( signal "@baseboard_fab2_lib.baseboard_fab2(sch_1):m_l_dq(14)"
				( attribute "CDS_PHYS_NET_NAME" "M_L_DQ<14>"
					( Origin gPackager )
				)
				( attribute "PNN" "M_L_DQ<14>"
					( Origin gPackager )
				)
				( objectStatus "M_L_DQ<14>" )
			)
			( signal "@baseboard_fab2_lib.baseboard_fab2(sch_1):m_l_dq(15)"
				( attribute "CDS_PHYS_NET_NAME" "M_L_DQ<15>"
					( Origin gPackager )
				)
				( attribute "PNN" "M_L_DQ<15>"
					( Origin gPackager )
				)
				( objectStatus "M_L_DQ<15>" )
			)
			( signal "@baseboard_fab2_lib.baseboard_fab2(sch_1):m_l_dq(16)"
				( attribute "CDS_PHYS_NET_NAME" "M_L_DQ<16>"
					( Origin gPackager )
				)
				( attribute "PNN" "M_L_DQ<16>"
					( Origin gPackager )
				)
				( objectStatus "M_L_DQ<16>" )
			)
			( signal "@baseboard_fab2_lib.baseboard_fab2(sch_1):m_l_dq(17)"
				( attribute "CDS_PHYS_NET_NAME" "M_L_DQ<17>"
					( Origin gPackager )
				)
				( attribute "PNN" "M_L_DQ<17>"
					( Origin gPackager )
				)
				( objectStatus "M_L_DQ<17>" )
			)
			( signal "@baseboard_fab2_lib.baseboard_fab2(sch_1):m_l_dq(18)"
				( attribute "CDS_PHYS_NET_NAME" "M_L_DQ<18>"
					( Origin gPackager )
				)
				( attribute "PNN" "M_L_DQ<18>"
					( Origin gPackager )
				)
				( objectStatus "M_L_DQ<18>" )
			)
			( signal "@baseboard_fab2_lib.baseboard_fab2(sch_1):m_l_dq(19)"
				( attribute "CDS_PHYS_NET_NAME" "M_L_DQ<19>"
					( Origin gPackager )
				)
				( attribute "PNN" "M_L_DQ<19>"
					( Origin gPackager )
				)
				( objectStatus "M_L_DQ<19>" )
			)
			( signal "@baseboard_fab2_lib.baseboard_fab2(sch_1):m_l_dq(20)"
				( attribute "CDS_PHYS_NET_NAME" "M_L_DQ<20>"
					( Origin gPackager )
				)
				( attribute "PNN" "M_L_DQ<20>"
					( Origin gPackager )
				)
				( objectStatus "M_L_DQ<20>" )
			)
			( signal "@baseboard_fab2_lib.baseboard_fab2(sch_1):m_l_dq(21)"
				( attribute "CDS_PHYS_NET_NAME" "M_L_DQ<21>"
					( Origin gPackager )
				)
				( attribute "PNN" "M_L_DQ<21>"
					( Origin gPackager )
				)
				( objectStatus "M_L_DQ<21>" )
			)
			( signal "@baseboard_fab2_lib.baseboard_fab2(sch_1):m_l_dq(22)"
				( attribute "CDS_PHYS_NET_NAME" "M_L_DQ<22>"
					( Origin gPackager )
				)
				( attribute "PNN" "M_L_DQ<22>"
					( Origin gPackager )
				)
				( objectStatus "M_L_DQ<22>" )
			)
			( signal "@baseboard_fab2_lib.baseboard_fab2(sch_1):m_l_dq(23)"
				( attribute "CDS_PHYS_NET_NAME" "M_L_DQ<23>"
					( Origin gPackager )
				)
				( attribute "PNN" "M_L_DQ<23>"
					( Origin gPackager )
				)
				( objectStatus "M_L_DQ<23>" )
			)
			( signal "@baseboard_fab2_lib.baseboard_fab2(sch_1):m_l_dq(24)"
				( attribute "CDS_PHYS_NET_NAME" "M_L_DQ<24>"
					( Origin gPackager )
				)
				( attribute "PNN" "M_L_DQ<24>"
					( Origin gPackager )
				)
				( objectStatus "M_L_DQ<24>" )
			)
			( signal "@baseboard_fab2_lib.baseboard_fab2(sch_1):m_l_dq(25)"
				( attribute "CDS_PHYS_NET_NAME" "M_L_DQ<25>"
					( Origin gPackager )
				)
				( attribute "PNN" "M_L_DQ<25>"
					( Origin gPackager )
				)
				( objectStatus "M_L_DQ<25>" )
			)
			( signal "@baseboard_fab2_lib.baseboard_fab2(sch_1):m_l_dq(26)"
				( attribute "CDS_PHYS_NET_NAME" "M_L_DQ<26>"
					( Origin gPackager )
				)
				( attribute "PNN" "M_L_DQ<26>"
					( Origin gPackager )
				)
				( objectStatus "M_L_DQ<26>" )
			)
			( signal "@baseboard_fab2_lib.baseboard_fab2(sch_1):m_l_dq(27)"
				( attribute "CDS_PHYS_NET_NAME" "M_L_DQ<27>"
					( Origin gPackager )
				)
				( attribute "PNN" "M_L_DQ<27>"
					( Origin gPackager )
				)
				( objectStatus "M_L_DQ<27>" )
			)
			( signal "@baseboard_fab2_lib.baseboard_fab2(sch_1):m_l_dq(28)"
				( attribute "CDS_PHYS_NET_NAME" "M_L_DQ<28>"
					( Origin gPackager )
				)
				( attribute "PNN" "M_L_DQ<28>"
					( Origin gPackager )
				)
				( objectStatus "M_L_DQ<28>" )
			)
			( signal "@baseboard_fab2_lib.baseboard_fab2(sch_1):m_l_dq(29)"
				( attribute "CDS_PHYS_NET_NAME" "M_L_DQ<29>"
					( Origin gPackager )
				)
				( attribute "PNN" "M_L_DQ<29>"
					( Origin gPackager )
				)
				( objectStatus "M_L_DQ<29>" )
			)
			( signal "@baseboard_fab2_lib.baseboard_fab2(sch_1):m_l_dq(30)"
				( attribute "CDS_PHYS_NET_NAME" "M_L_DQ<30>"
					( Origin gPackager )
				)
				( attribute "PNN" "M_L_DQ<30>"
					( Origin gPackager )
				)
				( objectStatus "M_L_DQ<30>" )
			)
			( signal "@baseboard_fab2_lib.baseboard_fab2(sch_1):m_l_dq(31)"
				( attribute "CDS_PHYS_NET_NAME" "M_L_DQ<31>"
					( Origin gPackager )
				)
				( attribute "PNN" "M_L_DQ<31>"
					( Origin gPackager )
				)
				( objectStatus "M_L_DQ<31>" )
			)
			( signal "@baseboard_fab2_lib.baseboard_fab2(sch_1):m_l_dq(32)"
				( attribute "CDS_PHYS_NET_NAME" "M_L_DQ<32>"
					( Origin gPackager )
				)
				( attribute "PNN" "M_L_DQ<32>"
					( Origin gPackager )
				)
				( objectStatus "M_L_DQ<32>" )
			)
			( signal "@baseboard_fab2_lib.baseboard_fab2(sch_1):m_l_dq(33)"
				( attribute "CDS_PHYS_NET_NAME" "M_L_DQ<33>"
					( Origin gPackager )
				)
				( attribute "PNN" "M_L_DQ<33>"
					( Origin gPackager )
				)
				( objectStatus "M_L_DQ<33>" )
			)
			( signal "@baseboard_fab2_lib.baseboard_fab2(sch_1):m_l_dq(34)"
				( attribute "CDS_PHYS_NET_NAME" "M_L_DQ<34>"
					( Origin gPackager )
				)
				( attribute "PNN" "M_L_DQ<34>"
					( Origin gPackager )
				)
				( objectStatus "M_L_DQ<34>" )
			)
			( signal "@baseboard_fab2_lib.baseboard_fab2(sch_1):m_l_dq(35)"
				( attribute "CDS_PHYS_NET_NAME" "M_L_DQ<35>"
					( Origin gPackager )
				)
				( attribute "PNN" "M_L_DQ<35>"
					( Origin gPackager )
				)
				( objectStatus "M_L_DQ<35>" )
			)
			( signal "@baseboard_fab2_lib.baseboard_fab2(sch_1):m_l_dq(36)"
				( attribute "CDS_PHYS_NET_NAME" "M_L_DQ<36>"
					( Origin gPackager )
				)
				( attribute "PNN" "M_L_DQ<36>"
					( Origin gPackager )
				)
				( objectStatus "M_L_DQ<36>" )
			)
			( signal "@baseboard_fab2_lib.baseboard_fab2(sch_1):m_l_dq(37)"
				( attribute "CDS_PHYS_NET_NAME" "M_L_DQ<37>"
					( Origin gPackager )
				)
				( attribute "PNN" "M_L_DQ<37>"
					( Origin gPackager )
				)
				( objectStatus "M_L_DQ<37>" )
			)
			( signal "@baseboard_fab2_lib.baseboard_fab2(sch_1):m_l_dq(38)"
				( attribute "CDS_PHYS_NET_NAME" "M_L_DQ<38>"
					( Origin gPackager )
				)
				( attribute "PNN" "M_L_DQ<38>"
					( Origin gPackager )
				)
				( objectStatus "M_L_DQ<38>" )
			)
			( signal "@baseboard_fab2_lib.baseboard_fab2(sch_1):m_l_dq(39)"
				( attribute "CDS_PHYS_NET_NAME" "M_L_DQ<39>"
					( Origin gPackager )
				)
				( attribute "PNN" "M_L_DQ<39>"
					( Origin gPackager )
				)
				( objectStatus "M_L_DQ<39>" )
			)
			( signal "@baseboard_fab2_lib.baseboard_fab2(sch_1):m_l_dq(40)"
				( attribute "CDS_PHYS_NET_NAME" "M_L_DQ<40>"
					( Origin gPackager )
				)
				( attribute "PNN" "M_L_DQ<40>"
					( Origin gPackager )
				)
				( objectStatus "M_L_DQ<40>" )
			)
			( signal "@baseboard_fab2_lib.baseboard_fab2(sch_1):m_l_dq(41)"
				( attribute "CDS_PHYS_NET_NAME" "M_L_DQ<41>"
					( Origin gPackager )
				)
				( attribute "PNN" "M_L_DQ<41>"
					( Origin gPackager )
				)
				( objectStatus "M_L_DQ<41>" )
			)
			( signal "@baseboard_fab2_lib.baseboard_fab2(sch_1):m_l_dq(42)"
				( attribute "CDS_PHYS_NET_NAME" "M_L_DQ<42>"
					( Origin gPackager )
				)
				( attribute "PNN" "M_L_DQ<42>"
					( Origin gPackager )
				)
				( objectStatus "M_L_DQ<42>" )
			)
			( signal "@baseboard_fab2_lib.baseboard_fab2(sch_1):m_l_dq(43)"
				( attribute "CDS_PHYS_NET_NAME" "M_L_DQ<43>"
					( Origin gPackager )
				)
				( attribute "PNN" "M_L_DQ<43>"
					( Origin gPackager )
				)
				( objectStatus "M_L_DQ<43>" )
			)
			( signal "@baseboard_fab2_lib.baseboard_fab2(sch_1):m_l_dq(44)"
				( attribute "CDS_PHYS_NET_NAME" "M_L_DQ<44>"
					( Origin gPackager )
				)
				( attribute "PNN" "M_L_DQ<44>"
					( Origin gPackager )
				)
				( objectStatus "M_L_DQ<44>" )
			)
			( signal "@baseboard_fab2_lib.baseboard_fab2(sch_1):m_l_dq(45)"
				( attribute "CDS_PHYS_NET_NAME" "M_L_DQ<45>"
					( Origin gPackager )
				)
				( attribute "PNN" "M_L_DQ<45>"
					( Origin gPackager )
				)
				( objectStatus "M_L_DQ<45>" )
			)
			( signal "@baseboard_fab2_lib.baseboard_fab2(sch_1):m_l_dq(46)"
				( attribute "CDS_PHYS_NET_NAME" "M_L_DQ<46>"
					( Origin gPackager )
				)
				( attribute "PNN" "M_L_DQ<46>"
					( Origin gPackager )
				)
				( objectStatus "M_L_DQ<46>" )
			)
			( signal "@baseboard_fab2_lib.baseboard_fab2(sch_1):m_l_dq(47)"
				( attribute "CDS_PHYS_NET_NAME" "M_L_DQ<47>"
					( Origin gPackager )
				)
				( attribute "PNN" "M_L_DQ<47>"
					( Origin gPackager )
				)
				( objectStatus "M_L_DQ<47>" )
			)
			( signal "@baseboard_fab2_lib.baseboard_fab2(sch_1):m_l_dq(48)"
				( attribute "CDS_PHYS_NET_NAME" "M_L_DQ<48>"
					( Origin gPackager )
				)
				( attribute "PNN" "M_L_DQ<48>"
					( Origin gPackager )
				)
				( objectStatus "M_L_DQ<48>" )
			)
			( signal "@baseboard_fab2_lib.baseboard_fab2(sch_1):m_l_dq(49)"
				( attribute "CDS_PHYS_NET_NAME" "M_L_DQ<49>"
					( Origin gPackager )
				)
				( attribute "PNN" "M_L_DQ<49>"
					( Origin gPackager )
				)
				( objectStatus "M_L_DQ<49>" )
			)
			( signal "@baseboard_fab2_lib.baseboard_fab2(sch_1):m_l_dq(50)"
				( attribute "CDS_PHYS_NET_NAME" "M_L_DQ<50>"
					( Origin gPackager )
				)
				( attribute "PNN" "M_L_DQ<50>"
					( Origin gPackager )
				)
				( objectStatus "M_L_DQ<50>" )
			)
			( signal "@baseboard_fab2_lib.baseboard_fab2(sch_1):m_l_dq(51)"
				( attribute "CDS_PHYS_NET_NAME" "M_L_DQ<51>"
					( Origin gPackager )
				)
				( attribute "PNN" "M_L_DQ<51>"
					( Origin gPackager )
				)
				( objectStatus "M_L_DQ<51>" )
			)
			( signal "@baseboard_fab2_lib.baseboard_fab2(sch_1):m_l_dq(52)"
				( attribute "CDS_PHYS_NET_NAME" "M_L_DQ<52>"
					( Origin gPackager )
				)
				( attribute "PNN" "M_L_DQ<52>"
					( Origin gPackager )
				)
				( objectStatus "M_L_DQ<52>" )
			)
			( signal "@baseboard_fab2_lib.baseboard_fab2(sch_1):m_l_dq(53)"
				( attribute "CDS_PHYS_NET_NAME" "M_L_DQ<53>"
					( Origin gPackager )
				)
				( attribute "PNN" "M_L_DQ<53>"
					( Origin gPackager )
				)
				( objectStatus "M_L_DQ<53>" )
			)
			( signal "@baseboard_fab2_lib.baseboard_fab2(sch_1):m_l_dq(54)"
				( attribute "CDS_PHYS_NET_NAME" "M_L_DQ<54>"
					( Origin gPackager )
				)
				( attribute "PNN" "M_L_DQ<54>"
					( Origin gPackager )
				)
				( objectStatus "M_L_DQ<54>" )
			)
			( signal "@baseboard_fab2_lib.baseboard_fab2(sch_1):m_l_dq(55)"
				( attribute "CDS_PHYS_NET_NAME" "M_L_DQ<55>"
					( Origin gPackager )
				)
				( attribute "PNN" "M_L_DQ<55>"
					( Origin gPackager )
				)
				( objectStatus "M_L_DQ<55>" )
			)
			( signal "@baseboard_fab2_lib.baseboard_fab2(sch_1):m_l_dq(56)"
				( attribute "CDS_PHYS_NET_NAME" "M_L_DQ<56>"
					( Origin gPackager )
				)
				( attribute "PNN" "M_L_DQ<56>"
					( Origin gPackager )
				)
				( objectStatus "M_L_DQ<56>" )
			)
			( signal "@baseboard_fab2_lib.baseboard_fab2(sch_1):m_l_dq(57)"
				( attribute "CDS_PHYS_NET_NAME" "M_L_DQ<57>"
					( Origin gPackager )
				)
				( attribute "PNN" "M_L_DQ<57>"
					( Origin gPackager )
				)
				( objectStatus "M_L_DQ<57>" )
			)
			( signal "@baseboard_fab2_lib.baseboard_fab2(sch_1):m_l_dq(58)"
				( attribute "CDS_PHYS_NET_NAME" "M_L_DQ<58>"
					( Origin gPackager )
				)
				( attribute "PNN" "M_L_DQ<58>"
					( Origin gPackager )
				)
				( objectStatus "M_L_DQ<58>" )
			)
			( signal "@baseboard_fab2_lib.baseboard_fab2(sch_1):m_l_dq(59)"
				( attribute "CDS_PHYS_NET_NAME" "M_L_DQ<59>"
					( Origin gPackager )
				)
				( attribute "PNN" "M_L_DQ<59>"
					( Origin gPackager )
				)
				( objectStatus "M_L_DQ<59>" )
			)
			( signal "@baseboard_fab2_lib.baseboard_fab2(sch_1):m_l_dq(60)"
				( attribute "CDS_PHYS_NET_NAME" "M_L_DQ<60>"
					( Origin gPackager )
				)
				( attribute "PNN" "M_L_DQ<60>"
					( Origin gPackager )
				)
				( objectStatus "M_L_DQ<60>" )
			)
			( signal "@baseboard_fab2_lib.baseboard_fab2(sch_1):m_l_dq(61)"
				( attribute "CDS_PHYS_NET_NAME" "M_L_DQ<61>"
					( Origin gPackager )
				)
				( attribute "PNN" "M_L_DQ<61>"
					( Origin gPackager )
				)
				( objectStatus "M_L_DQ<61>" )
			)
			( signal "@baseboard_fab2_lib.baseboard_fab2(sch_1):m_l_dq(62)"
				( attribute "CDS_PHYS_NET_NAME" "M_L_DQ<62>"
					( Origin gPackager )
				)
				( attribute "PNN" "M_L_DQ<62>"
					( Origin gPackager )
				)
				( objectStatus "M_L_DQ<62>" )
			)
			( signal "@baseboard_fab2_lib.baseboard_fab2(sch_1):m_l_dq(63)"
				( attribute "CDS_PHYS_NET_NAME" "M_L_DQ<63>"
					( Origin gPackager )
				)
				( attribute "PNN" "M_L_DQ<63>"
					( Origin gPackager )
				)
				( objectStatus "M_L_DQ<63>" )
			)
			( signal "@baseboard_fab2_lib.baseboard_fab2(sch_1):m_l_dqs_dn(0)"
				( attribute "CDS_PHYS_NET_NAME" "M_L_DQS_DN<0>"
					( Origin gPackager )
				)
				( attribute "PNN" "M_L_DQS_DN<0>"
					( Origin gPackager )
				)
				( objectStatus "M_L_DQS_DN<0>" )
			)
			( signal "@baseboard_fab2_lib.baseboard_fab2(sch_1):m_l_dqs_dn(1)"
				( attribute "CDS_PHYS_NET_NAME" "M_L_DQS_DN<1>"
					( Origin gPackager )
				)
				( attribute "PNN" "M_L_DQS_DN<1>"
					( Origin gPackager )
				)
				( objectStatus "M_L_DQS_DN<1>" )
			)
			( signal "@baseboard_fab2_lib.baseboard_fab2(sch_1):m_l_dqs_dn(2)"
				( attribute "CDS_PHYS_NET_NAME" "M_L_DQS_DN<2>"
					( Origin gPackager )
				)
				( attribute "PNN" "M_L_DQS_DN<2>"
					( Origin gPackager )
				)
				( objectStatus "M_L_DQS_DN<2>" )
			)
			( signal "@baseboard_fab2_lib.baseboard_fab2(sch_1):m_l_dqs_dn(3)"
				( attribute "CDS_PHYS_NET_NAME" "M_L_DQS_DN<3>"
					( Origin gPackager )
				)
				( attribute "PNN" "M_L_DQS_DN<3>"
					( Origin gPackager )
				)
				( objectStatus "M_L_DQS_DN<3>" )
			)
			( signal "@baseboard_fab2_lib.baseboard_fab2(sch_1):m_l_dqs_dn(4)"
				( attribute "CDS_PHYS_NET_NAME" "M_L_DQS_DN<4>"
					( Origin gPackager )
				)
				( attribute "PNN" "M_L_DQS_DN<4>"
					( Origin gPackager )
				)
				( objectStatus "M_L_DQS_DN<4>" )
			)
			( signal "@baseboard_fab2_lib.baseboard_fab2(sch_1):m_l_dqs_dn(5)"
				( attribute "CDS_PHYS_NET_NAME" "M_L_DQS_DN<5>"
					( Origin gPackager )
				)
				( attribute "PNN" "M_L_DQS_DN<5>"
					( Origin gPackager )
				)
				( objectStatus "M_L_DQS_DN<5>" )
			)
			( signal "@baseboard_fab2_lib.baseboard_fab2(sch_1):m_l_dqs_dn(6)"
				( attribute "CDS_PHYS_NET_NAME" "M_L_DQS_DN<6>"
					( Origin gPackager )
				)
				( attribute "PNN" "M_L_DQS_DN<6>"
					( Origin gPackager )
				)
				( objectStatus "M_L_DQS_DN<6>" )
			)
			( signal "@baseboard_fab2_lib.baseboard_fab2(sch_1):m_l_dqs_dn(7)"
				( attribute "CDS_PHYS_NET_NAME" "M_L_DQS_DN<7>"
					( Origin gPackager )
				)
				( attribute "PNN" "M_L_DQS_DN<7>"
					( Origin gPackager )
				)
				( objectStatus "M_L_DQS_DN<7>" )
			)
			( signal "@baseboard_fab2_lib.baseboard_fab2(sch_1):m_l_dqs_dn(8)"
				( attribute "CDS_PHYS_NET_NAME" "M_L_DQS_DN<8>"
					( Origin gPackager )
				)
				( attribute "PNN" "M_L_DQS_DN<8>"
					( Origin gPackager )
				)
				( objectStatus "M_L_DQS_DN<8>" )
			)
			( signal "@baseboard_fab2_lib.baseboard_fab2(sch_1):m_l_dqs_dn(9)"
				( attribute "CDS_PHYS_NET_NAME" "M_L_DQS_DN<9>"
					( Origin gPackager )
				)
				( attribute "PNN" "M_L_DQS_DN<9>"
					( Origin gPackager )
				)
				( objectStatus "M_L_DQS_DN<9>" )
			)
			( signal "@baseboard_fab2_lib.baseboard_fab2(sch_1):m_l_dqs_dn(10)"
				( attribute "CDS_PHYS_NET_NAME" "M_L_DQS_DN<10>"
					( Origin gPackager )
				)
				( attribute "PNN" "M_L_DQS_DN<10>"
					( Origin gPackager )
				)
				( objectStatus "M_L_DQS_DN<10>" )
			)
			( signal "@baseboard_fab2_lib.baseboard_fab2(sch_1):m_l_dqs_dn(11)"
				( attribute "CDS_PHYS_NET_NAME" "M_L_DQS_DN<11>"
					( Origin gPackager )
				)
				( attribute "PNN" "M_L_DQS_DN<11>"
					( Origin gPackager )
				)
				( objectStatus "M_L_DQS_DN<11>" )
			)
			( signal "@baseboard_fab2_lib.baseboard_fab2(sch_1):m_l_dqs_dn(12)"
				( attribute "CDS_PHYS_NET_NAME" "M_L_DQS_DN<12>"
					( Origin gPackager )
				)
				( attribute "PNN" "M_L_DQS_DN<12>"
					( Origin gPackager )
				)
				( objectStatus "M_L_DQS_DN<12>" )
			)
			( signal "@baseboard_fab2_lib.baseboard_fab2(sch_1):m_l_dqs_dn(13)"
				( attribute "CDS_PHYS_NET_NAME" "M_L_DQS_DN<13>"
					( Origin gPackager )
				)
				( attribute "PNN" "M_L_DQS_DN<13>"
					( Origin gPackager )
				)
				( objectStatus "M_L_DQS_DN<13>" )
			)
			( signal "@baseboard_fab2_lib.baseboard_fab2(sch_1):m_l_dqs_dn(14)"
				( attribute "CDS_PHYS_NET_NAME" "M_L_DQS_DN<14>"
					( Origin gPackager )
				)
				( attribute "PNN" "M_L_DQS_DN<14>"
					( Origin gPackager )
				)
				( objectStatus "M_L_DQS_DN<14>" )
			)
			( signal "@baseboard_fab2_lib.baseboard_fab2(sch_1):m_l_dqs_dn(15)"
				( attribute "CDS_PHYS_NET_NAME" "M_L_DQS_DN<15>"
					( Origin gPackager )
				)
				( attribute "PNN" "M_L_DQS_DN<15>"
					( Origin gPackager )
				)
				( objectStatus "M_L_DQS_DN<15>" )
			)
			( signal "@baseboard_fab2_lib.baseboard_fab2(sch_1):m_l_dqs_dn(16)"
				( attribute "CDS_PHYS_NET_NAME" "M_L_DQS_DN<16>"
					( Origin gPackager )
				)
				( attribute "PNN" "M_L_DQS_DN<16>"
					( Origin gPackager )
				)
				( objectStatus "M_L_DQS_DN<16>" )
			)
			( signal "@baseboard_fab2_lib.baseboard_fab2(sch_1):m_l_dqs_dn(17)"
				( attribute "CDS_PHYS_NET_NAME" "M_L_DQS_DN<17>"
					( Origin gPackager )
				)
				( attribute "PNN" "M_L_DQS_DN<17>"
					( Origin gPackager )
				)
				( objectStatus "M_L_DQS_DN<17>" )
			)
			( signal "@baseboard_fab2_lib.baseboard_fab2(sch_1):m_l_dqs_dp(0)"
				( attribute "CDS_PHYS_NET_NAME" "M_L_DQS_DP<0>"
					( Origin gPackager )
				)
				( attribute "PNN" "M_L_DQS_DP<0>"
					( Origin gPackager )
				)
				( objectStatus "M_L_DQS_DP<0>" )
			)
			( signal "@baseboard_fab2_lib.baseboard_fab2(sch_1):m_l_dqs_dp(1)"
				( attribute "CDS_PHYS_NET_NAME" "M_L_DQS_DP<1>"
					( Origin gPackager )
				)
				( attribute "PNN" "M_L_DQS_DP<1>"
					( Origin gPackager )
				)
				( objectStatus "M_L_DQS_DP<1>" )
			)
			( signal "@baseboard_fab2_lib.baseboard_fab2(sch_1):m_l_dqs_dp(2)"
				( attribute "CDS_PHYS_NET_NAME" "M_L_DQS_DP<2>"
					( Origin gPackager )
				)
				( attribute "PNN" "M_L_DQS_DP<2>"
					( Origin gPackager )
				)
				( objectStatus "M_L_DQS_DP<2>" )
			)
			( signal "@baseboard_fab2_lib.baseboard_fab2(sch_1):m_l_dqs_dp(3)"
				( attribute "CDS_PHYS_NET_NAME" "M_L_DQS_DP<3>"
					( Origin gPackager )
				)
				( attribute "PNN" "M_L_DQS_DP<3>"
					( Origin gPackager )
				)
				( objectStatus "M_L_DQS_DP<3>" )
			)
			( signal "@baseboard_fab2_lib.baseboard_fab2(sch_1):m_l_dqs_dp(4)"
				( attribute "CDS_PHYS_NET_NAME" "M_L_DQS_DP<4>"
					( Origin gPackager )
				)
				( attribute "PNN" "M_L_DQS_DP<4>"
					( Origin gPackager )
				)
				( objectStatus "M_L_DQS_DP<4>" )
			)
			( signal "@baseboard_fab2_lib.baseboard_fab2(sch_1):m_l_dqs_dp(5)"
				( attribute "CDS_PHYS_NET_NAME" "M_L_DQS_DP<5>"
					( Origin gPackager )
				)
				( attribute "PNN" "M_L_DQS_DP<5>"
					( Origin gPackager )
				)
				( objectStatus "M_L_DQS_DP<5>" )
			)
			( signal "@baseboard_fab2_lib.baseboard_fab2(sch_1):m_l_dqs_dp(6)"
				( attribute "CDS_PHYS_NET_NAME" "M_L_DQS_DP<6>"
					( Origin gPackager )
				)
				( attribute "PNN" "M_L_DQS_DP<6>"
					( Origin gPackager )
				)
				( objectStatus "M_L_DQS_DP<6>" )
			)
			( signal "@baseboard_fab2_lib.baseboard_fab2(sch_1):m_l_dqs_dp(7)"
				( attribute "CDS_PHYS_NET_NAME" "M_L_DQS_DP<7>"
					( Origin gPackager )
				)
				( attribute "PNN" "M_L_DQS_DP<7>"
					( Origin gPackager )
				)
				( objectStatus "M_L_DQS_DP<7>" )
			)
			( signal "@baseboard_fab2_lib.baseboard_fab2(sch_1):m_l_dqs_dp(8)"
				( attribute "CDS_PHYS_NET_NAME" "M_L_DQS_DP<8>"
					( Origin gPackager )
				)
				( attribute "PNN" "M_L_DQS_DP<8>"
					( Origin gPackager )
				)
				( objectStatus "M_L_DQS_DP<8>" )
			)
			( signal "@baseboard_fab2_lib.baseboard_fab2(sch_1):m_l_dqs_dp(9)"
				( attribute "CDS_PHYS_NET_NAME" "M_L_DQS_DP<9>"
					( Origin gPackager )
				)
				( attribute "PNN" "M_L_DQS_DP<9>"
					( Origin gPackager )
				)
				( objectStatus "M_L_DQS_DP<9>" )
			)
			( signal "@baseboard_fab2_lib.baseboard_fab2(sch_1):m_l_dqs_dp(10)"
				( attribute "CDS_PHYS_NET_NAME" "M_L_DQS_DP<10>"
					( Origin gPackager )
				)
				( attribute "PNN" "M_L_DQS_DP<10>"
					( Origin gPackager )
				)
				( objectStatus "M_L_DQS_DP<10>" )
			)
			( signal "@baseboard_fab2_lib.baseboard_fab2(sch_1):m_l_dqs_dp(11)"
				( attribute "CDS_PHYS_NET_NAME" "M_L_DQS_DP<11>"
					( Origin gPackager )
				)
				( attribute "PNN" "M_L_DQS_DP<11>"
					( Origin gPackager )
				)
				( objectStatus "M_L_DQS_DP<11>" )
			)
			( signal "@baseboard_fab2_lib.baseboard_fab2(sch_1):m_l_dqs_dp(12)"
				( attribute "CDS_PHYS_NET_NAME" "M_L_DQS_DP<12>"
					( Origin gPackager )
				)
				( attribute "PNN" "M_L_DQS_DP<12>"
					( Origin gPackager )
				)
				( objectStatus "M_L_DQS_DP<12>" )
			)
			( signal "@baseboard_fab2_lib.baseboard_fab2(sch_1):m_l_dqs_dp(13)"
				( attribute "CDS_PHYS_NET_NAME" "M_L_DQS_DP<13>"
					( Origin gPackager )
				)
				( attribute "PNN" "M_L_DQS_DP<13>"
					( Origin gPackager )
				)
				( objectStatus "M_L_DQS_DP<13>" )
			)
			( signal "@baseboard_fab2_lib.baseboard_fab2(sch_1):m_l_dqs_dp(14)"
				( attribute "CDS_PHYS_NET_NAME" "M_L_DQS_DP<14>"
					( Origin gPackager )
				)
				( attribute "PNN" "M_L_DQS_DP<14>"
					( Origin gPackager )
				)
				( objectStatus "M_L_DQS_DP<14>" )
			)
			( signal "@baseboard_fab2_lib.baseboard_fab2(sch_1):m_l_dqs_dp(15)"
				( attribute "CDS_PHYS_NET_NAME" "M_L_DQS_DP<15>"
					( Origin gPackager )
				)
				( attribute "PNN" "M_L_DQS_DP<15>"
					( Origin gPackager )
				)
				( objectStatus "M_L_DQS_DP<15>" )
			)
			( signal "@baseboard_fab2_lib.baseboard_fab2(sch_1):m_l_dqs_dp(16)"
				( attribute "CDS_PHYS_NET_NAME" "M_L_DQS_DP<16>"
					( Origin gPackager )
				)
				( attribute "PNN" "M_L_DQS_DP<16>"
					( Origin gPackager )
				)
				( objectStatus "M_L_DQS_DP<16>" )
			)
			( signal "@baseboard_fab2_lib.baseboard_fab2(sch_1):m_l_dqs_dp(17)"
				( attribute "CDS_PHYS_NET_NAME" "M_L_DQS_DP<17>"
					( Origin gPackager )
				)
				( attribute "PNN" "M_L_DQS_DP<17>"
					( Origin gPackager )
				)
				( objectStatus "M_L_DQS_DP<17>" )
			)
			( signal "@baseboard_fab2_lib.baseboard_fab2(sch_1):m_l_ecc(0)"
				( attribute "CDS_PHYS_NET_NAME" "M_L_ECC<0>"
					( Origin gPackager )
				)
				( attribute "PNN" "M_L_ECC<0>"
					( Origin gPackager )
				)
				( objectStatus "M_L_ECC<0>" )
			)
			( signal "@baseboard_fab2_lib.baseboard_fab2(sch_1):m_l_ecc(1)"
				( attribute "CDS_PHYS_NET_NAME" "M_L_ECC<1>"
					( Origin gPackager )
				)
				( attribute "PNN" "M_L_ECC<1>"
					( Origin gPackager )
				)
				( objectStatus "M_L_ECC<1>" )
			)
			( signal "@baseboard_fab2_lib.baseboard_fab2(sch_1):m_l_ecc(2)"
				( attribute "CDS_PHYS_NET_NAME" "M_L_ECC<2>"
					( Origin gPackager )
				)
				( attribute "PNN" "M_L_ECC<2>"
					( Origin gPackager )
				)
				( objectStatus "M_L_ECC<2>" )
			)
			( signal "@baseboard_fab2_lib.baseboard_fab2(sch_1):m_l_ecc(3)"
				( attribute "CDS_PHYS_NET_NAME" "M_L_ECC<3>"
					( Origin gPackager )
				)
				( attribute "PNN" "M_L_ECC<3>"
					( Origin gPackager )
				)
				( objectStatus "M_L_ECC<3>" )
			)
			( signal "@baseboard_fab2_lib.baseboard_fab2(sch_1):m_l_ecc(4)"
				( attribute "CDS_PHYS_NET_NAME" "M_L_ECC<4>"
					( Origin gPackager )
				)
				( attribute "PNN" "M_L_ECC<4>"
					( Origin gPackager )
				)
				( objectStatus "M_L_ECC<4>" )
			)
			( signal "@baseboard_fab2_lib.baseboard_fab2(sch_1):m_l_ecc(5)"
				( attribute "CDS_PHYS_NET_NAME" "M_L_ECC<5>"
					( Origin gPackager )
				)
				( attribute "PNN" "M_L_ECC<5>"
					( Origin gPackager )
				)
				( objectStatus "M_L_ECC<5>" )
			)
			( signal "@baseboard_fab2_lib.baseboard_fab2(sch_1):m_l_ecc(6)"
				( attribute "CDS_PHYS_NET_NAME" "M_L_ECC<6>"
					( Origin gPackager )
				)
				( attribute "PNN" "M_L_ECC<6>"
					( Origin gPackager )
				)
				( objectStatus "M_L_ECC<6>" )
			)
			( signal "@baseboard_fab2_lib.baseboard_fab2(sch_1):m_l_ecc(7)"
				( attribute "CDS_PHYS_NET_NAME" "M_L_ECC<7>"
					( Origin gPackager )
				)
				( attribute "PNN" "M_L_ECC<7>"
					( Origin gPackager )
				)
				( objectStatus "M_L_ECC<7>" )
			)
			( signal "@baseboard_fab2_lib.baseboard_fab2(sch_1):m_l_ma(0)"
				( attribute "CDS_PHYS_NET_NAME" "M_L_MA<0>"
					( Origin gPackager )
				)
				( attribute "PNN" "M_L_MA<0>"
					( Origin gPackager )
				)
				( objectStatus "M_L_MA<0>" )
			)
			( signal "@baseboard_fab2_lib.baseboard_fab2(sch_1):m_l_ma(1)"
				( attribute "CDS_PHYS_NET_NAME" "M_L_MA<1>"
					( Origin gPackager )
				)
				( attribute "PNN" "M_L_MA<1>"
					( Origin gPackager )
				)
				( objectStatus "M_L_MA<1>" )
			)
			( signal "@baseboard_fab2_lib.baseboard_fab2(sch_1):m_l_ma(2)"
				( attribute "CDS_PHYS_NET_NAME" "M_L_MA<2>"
					( Origin gPackager )
				)
				( attribute "PNN" "M_L_MA<2>"
					( Origin gPackager )
				)
				( objectStatus "M_L_MA<2>" )
			)
			( signal "@baseboard_fab2_lib.baseboard_fab2(sch_1):m_l_ma(3)"
				( attribute "CDS_PHYS_NET_NAME" "M_L_MA<3>"
					( Origin gPackager )
				)
				( attribute "PNN" "M_L_MA<3>"
					( Origin gPackager )
				)
				( objectStatus "M_L_MA<3>" )
			)
			( signal "@baseboard_fab2_lib.baseboard_fab2(sch_1):m_l_ma(4)"
				( attribute "CDS_PHYS_NET_NAME" "M_L_MA<4>"
					( Origin gPackager )
				)
				( attribute "PNN" "M_L_MA<4>"
					( Origin gPackager )
				)
				( objectStatus "M_L_MA<4>" )
			)
			( signal "@baseboard_fab2_lib.baseboard_fab2(sch_1):m_l_ma(5)"
				( attribute "CDS_PHYS_NET_NAME" "M_L_MA<5>"
					( Origin gPackager )
				)
				( attribute "PNN" "M_L_MA<5>"
					( Origin gPackager )
				)
				( objectStatus "M_L_MA<5>" )
			)
			( signal "@baseboard_fab2_lib.baseboard_fab2(sch_1):m_l_ma(6)"
				( attribute "CDS_PHYS_NET_NAME" "M_L_MA<6>"
					( Origin gPackager )
				)
				( attribute "PNN" "M_L_MA<6>"
					( Origin gPackager )
				)
				( objectStatus "M_L_MA<6>" )
			)
			( signal "@baseboard_fab2_lib.baseboard_fab2(sch_1):m_l_ma(7)"
				( attribute "CDS_PHYS_NET_NAME" "M_L_MA<7>"
					( Origin gPackager )
				)
				( attribute "PNN" "M_L_MA<7>"
					( Origin gPackager )
				)
				( objectStatus "M_L_MA<7>" )
			)
			( signal "@baseboard_fab2_lib.baseboard_fab2(sch_1):m_l_ma(8)"
				( attribute "CDS_PHYS_NET_NAME" "M_L_MA<8>"
					( Origin gPackager )
				)
				( attribute "PNN" "M_L_MA<8>"
					( Origin gPackager )
				)
				( objectStatus "M_L_MA<8>" )
			)
			( signal "@baseboard_fab2_lib.baseboard_fab2(sch_1):m_l_ma(9)"
				( attribute "CDS_PHYS_NET_NAME" "M_L_MA<9>"
					( Origin gPackager )
				)
				( attribute "PNN" "M_L_MA<9>"
					( Origin gPackager )
				)
				( objectStatus "M_L_MA<9>" )
			)
			( signal "@baseboard_fab2_lib.baseboard_fab2(sch_1):m_l_ma(10)"
				( attribute "CDS_PHYS_NET_NAME" "M_L_MA<10>"
					( Origin gPackager )
				)
				( attribute "PNN" "M_L_MA<10>"
					( Origin gPackager )
				)
				( objectStatus "M_L_MA<10>" )
			)
			( signal "@baseboard_fab2_lib.baseboard_fab2(sch_1):m_l_ma(11)"
				( attribute "CDS_PHYS_NET_NAME" "M_L_MA<11>"
					( Origin gPackager )
				)
				( attribute "PNN" "M_L_MA<11>"
					( Origin gPackager )
				)
				( objectStatus "M_L_MA<11>" )
			)
			( signal "@baseboard_fab2_lib.baseboard_fab2(sch_1):m_l_ma(12)"
				( attribute "CDS_PHYS_NET_NAME" "M_L_MA<12>"
					( Origin gPackager )
				)
				( attribute "PNN" "M_L_MA<12>"
					( Origin gPackager )
				)
				( objectStatus "M_L_MA<12>" )
			)
			( signal "@baseboard_fab2_lib.baseboard_fab2(sch_1):m_l_ma(13)"
				( attribute "CDS_PHYS_NET_NAME" "M_L_MA<13>"
					( Origin gPackager )
				)
				( attribute "PNN" "M_L_MA<13>"
					( Origin gPackager )
				)
				( objectStatus "M_L_MA<13>" )
			)
			( signal "@baseboard_fab2_lib.baseboard_fab2(sch_1):m_l_ma(14)"
				( attribute "CDS_PHYS_NET_NAME" "M_L_MA<14>"
					( Origin gPackager )
				)
				( attribute "PNN" "M_L_MA<14>"
					( Origin gPackager )
				)
				( objectStatus "M_L_MA<14>" )
			)
			( signal "@baseboard_fab2_lib.baseboard_fab2(sch_1):m_l_ma(15)"
				( attribute "CDS_PHYS_NET_NAME" "M_L_MA<15>"
					( Origin gPackager )
				)
				( attribute "PNN" "M_L_MA<15>"
					( Origin gPackager )
				)
				( objectStatus "M_L_MA<15>" )
			)
			( signal "@baseboard_fab2_lib.baseboard_fab2(sch_1):m_l_ma(16)"
				( attribute "CDS_PHYS_NET_NAME" "M_L_MA<16>"
					( Origin gPackager )
				)
				( attribute "PNN" "M_L_MA<16>"
					( Origin gPackager )
				)
				( objectStatus "M_L_MA<16>" )
			)
			( signal "@baseboard_fab2_lib.baseboard_fab2(sch_1):m_l_ma(17)"
				( attribute "CDS_PHYS_NET_NAME" "M_L_MA<17>"
					( Origin gPackager )
				)
				( attribute "PNN" "M_L_MA<17>"
					( Origin gPackager )
				)
				( objectStatus "M_L_MA<17>" )
			)
			( signal "@baseboard_fab2_lib.baseboard_fab2(sch_1):m_l_odt(0)"
				( attribute "CDS_PHYS_NET_NAME" "M_L_ODT<0>"
					( Origin gPackager )
				)
				( attribute "PNN" "M_L_ODT<0>"
					( Origin gPackager )
				)
				( objectStatus "M_L_ODT<0>" )
			)
			( signal "@baseboard_fab2_lib.baseboard_fab2(sch_1):m_l_odt(1)"
				( attribute "CDS_PHYS_NET_NAME" "M_L_ODT<1>"
					( Origin gPackager )
				)
				( attribute "PNN" "M_L_ODT<1>"
					( Origin gPackager )
				)
				( objectStatus "M_L_ODT<1>" )
			)
			( signal "@baseboard_fab2_lib.baseboard_fab2(sch_1):m_l_odt(2)"
				( attribute "CDS_PHYS_NET_NAME" "M_L_ODT<2>"
					( Origin gPackager )
				)
				( attribute "PNN" "M_L_ODT<2>"
					( Origin gPackager )
				)
				( objectStatus "M_L_ODT<2>" )
			)
			( signal "@baseboard_fab2_lib.baseboard_fab2(sch_1):m_l_odt(3)"
				( attribute "CDS_PHYS_NET_NAME" "M_L_ODT<3>"
					( Origin gPackager )
				)
				( attribute "PNN" "M_L_ODT<3>"
					( Origin gPackager )
				)
				( objectStatus "M_L_ODT<3>" )
			)
			( signal "@baseboard_fab2_lib.baseboard_fab2(sch_1):m_l_par"
				( attribute "CDS_PHYS_NET_NAME" "M_L_PAR"
					( Origin gPackager )
				)
				( objectStatus "M_L_PAR" )
			)
			( signal "@baseboard_fab2_lib.baseboard_fab2(sch_1):m_m_act_n"
				( attribute "CDS_PHYS_NET_NAME" "M_M_ACT_N"
					( Origin gPackager )
				)
				( objectStatus "M_M_ACT_N" )
			)
			( signal "@baseboard_fab2_lib.baseboard_fab2(sch_1):m_m_alert_n"
				( attribute "CDS_PHYS_NET_NAME" "M_M_ALERT_N"
					( Origin gPackager )
				)
				( objectStatus "M_M_ALERT_N" )
			)
			( signal "@baseboard_fab2_lib.baseboard_fab2(sch_1):m_m_ba(0)"
				( attribute "CDS_PHYS_NET_NAME" "M_M_BA<0>"
					( Origin gPackager )
				)
				( attribute "PNN" "M_M_BA<0>"
					( Origin gPackager )
				)
				( objectStatus "M_M_BA<0>" )
			)
			( signal "@baseboard_fab2_lib.baseboard_fab2(sch_1):m_m_ba(1)"
				( attribute "CDS_PHYS_NET_NAME" "M_M_BA<1>"
					( Origin gPackager )
				)
				( attribute "PNN" "M_M_BA<1>"
					( Origin gPackager )
				)
				( objectStatus "M_M_BA<1>" )
			)
			( signal "@baseboard_fab2_lib.baseboard_fab2(sch_1):m_m_bg(0)"
				( attribute "CDS_PHYS_NET_NAME" "M_M_BG<0>"
					( Origin gPackager )
				)
				( attribute "PNN" "M_M_BG<0>"
					( Origin gPackager )
				)
				( objectStatus "M_M_BG<0>" )
			)
			( signal "@baseboard_fab2_lib.baseboard_fab2(sch_1):m_m_bg(1)"
				( attribute "CDS_PHYS_NET_NAME" "M_M_BG<1>"
					( Origin gPackager )
				)
				( attribute "PNN" "M_M_BG<1>"
					( Origin gPackager )
				)
				( objectStatus "M_M_BG<1>" )
			)
			( signal "@baseboard_fab2_lib.baseboard_fab2(sch_1):m_m_c(2)"
				( attribute "CDS_PHYS_NET_NAME" "M_M_C<2>"
					( Origin gPackager )
				)
				( attribute "PNN" "M_M_C<2>"
					( Origin gPackager )
				)
				( objectStatus "M_M_C<2>" )
			)
			( signal "@baseboard_fab2_lib.baseboard_fab2(sch_1):m_m_cke(0)"
				( attribute "CDS_PHYS_NET_NAME" "M_M_CKE<0>"
					( Origin gPackager )
				)
				( attribute "PNN" "M_M_CKE<0>"
					( Origin gPackager )
				)
				( objectStatus "M_M_CKE<0>" )
			)
			( signal "@baseboard_fab2_lib.baseboard_fab2(sch_1):m_m_cke(1)"
				( attribute "CDS_PHYS_NET_NAME" "M_M_CKE<1>"
					( Origin gPackager )
				)
				( attribute "PNN" "M_M_CKE<1>"
					( Origin gPackager )
				)
				( objectStatus "M_M_CKE<1>" )
			)
			( signal "@baseboard_fab2_lib.baseboard_fab2(sch_1):m_m_cke(2)"
				( attribute "CDS_PHYS_NET_NAME" "M_M_CKE<2>"
					( Origin gPackager )
				)
				( attribute "PNN" "M_M_CKE<2>"
					( Origin gPackager )
				)
				( objectStatus "M_M_CKE<2>" )
			)
			( signal "@baseboard_fab2_lib.baseboard_fab2(sch_1):m_m_cke(3)"
				( attribute "CDS_PHYS_NET_NAME" "M_M_CKE<3>"
					( Origin gPackager )
				)
				( attribute "PNN" "M_M_CKE<3>"
					( Origin gPackager )
				)
				( objectStatus "M_M_CKE<3>" )
			)
			( signal "@baseboard_fab2_lib.baseboard_fab2(sch_1):m_m_clk_dn(0)"
				( attribute "CDS_PHYS_NET_NAME" "M_M_CLK_DN<0>"
					( Origin gPackager )
				)
				( attribute "PNN" "M_M_CLK_DN<0>"
					( Origin gPackager )
				)
				( objectStatus "M_M_CLK_DN<0>" )
			)
			( signal "@baseboard_fab2_lib.baseboard_fab2(sch_1):m_m_clk_dn(1)"
				( attribute "CDS_PHYS_NET_NAME" "M_M_CLK_DN<1>"
					( Origin gPackager )
				)
				( attribute "PNN" "M_M_CLK_DN<1>"
					( Origin gPackager )
				)
				( objectStatus "M_M_CLK_DN<1>" )
			)
			( signal "@baseboard_fab2_lib.baseboard_fab2(sch_1):m_m_clk_dn(2)"
				( attribute "CDS_PHYS_NET_NAME" "M_M_CLK_DN<2>"
					( Origin gPackager )
				)
				( attribute "PNN" "M_M_CLK_DN<2>"
					( Origin gPackager )
				)
				( objectStatus "M_M_CLK_DN<2>" )
			)
			( signal "@baseboard_fab2_lib.baseboard_fab2(sch_1):m_m_clk_dn(3)"
				( attribute "CDS_PHYS_NET_NAME" "M_M_CLK_DN<3>"
					( Origin gPackager )
				)
				( attribute "PNN" "M_M_CLK_DN<3>"
					( Origin gPackager )
				)
				( objectStatus "M_M_CLK_DN<3>" )
			)
			( signal "@baseboard_fab2_lib.baseboard_fab2(sch_1):m_m_clk_dp(0)"
				( attribute "CDS_PHYS_NET_NAME" "M_M_CLK_DP<0>"
					( Origin gPackager )
				)
				( attribute "PNN" "M_M_CLK_DP<0>"
					( Origin gPackager )
				)
				( objectStatus "M_M_CLK_DP<0>" )
			)
			( signal "@baseboard_fab2_lib.baseboard_fab2(sch_1):m_m_clk_dp(1)"
				( attribute "CDS_PHYS_NET_NAME" "M_M_CLK_DP<1>"
					( Origin gPackager )
				)
				( attribute "PNN" "M_M_CLK_DP<1>"
					( Origin gPackager )
				)
				( objectStatus "M_M_CLK_DP<1>" )
			)
			( signal "@baseboard_fab2_lib.baseboard_fab2(sch_1):m_m_clk_dp(2)"
				( attribute "CDS_PHYS_NET_NAME" "M_M_CLK_DP<2>"
					( Origin gPackager )
				)
				( attribute "PNN" "M_M_CLK_DP<2>"
					( Origin gPackager )
				)
				( objectStatus "M_M_CLK_DP<2>" )
			)
			( signal "@baseboard_fab2_lib.baseboard_fab2(sch_1):m_m_clk_dp(3)"
				( attribute "CDS_PHYS_NET_NAME" "M_M_CLK_DP<3>"
					( Origin gPackager )
				)
				( attribute "PNN" "M_M_CLK_DP<3>"
					( Origin gPackager )
				)
				( objectStatus "M_M_CLK_DP<3>" )
			)
			( signal "@baseboard_fab2_lib.baseboard_fab2(sch_1):m_m_cs_n(0)"
				( attribute "CDS_PHYS_NET_NAME" "M_M_CS_N<0>"
					( Origin gPackager )
				)
				( attribute "PNN" "M_M_CS_N<0>"
					( Origin gPackager )
				)
				( objectStatus "M_M_CS_N<0>" )
			)
			( signal "@baseboard_fab2_lib.baseboard_fab2(sch_1):m_m_cs_n(1)"
				( attribute "CDS_PHYS_NET_NAME" "M_M_CS_N<1>"
					( Origin gPackager )
				)
				( attribute "PNN" "M_M_CS_N<1>"
					( Origin gPackager )
				)
				( objectStatus "M_M_CS_N<1>" )
			)
			( signal "@baseboard_fab2_lib.baseboard_fab2(sch_1):m_m_cs_n(2)"
				( attribute "CDS_PHYS_NET_NAME" "M_M_CS_N<2>"
					( Origin gPackager )
				)
				( attribute "PNN" "M_M_CS_N<2>"
					( Origin gPackager )
				)
				( objectStatus "M_M_CS_N<2>" )
			)
			( signal "@baseboard_fab2_lib.baseboard_fab2(sch_1):m_m_cs_n(3)"
				( attribute "CDS_PHYS_NET_NAME" "M_M_CS_N<3>"
					( Origin gPackager )
				)
				( attribute "PNN" "M_M_CS_N<3>"
					( Origin gPackager )
				)
				( objectStatus "M_M_CS_N<3>" )
			)
			( signal "@baseboard_fab2_lib.baseboard_fab2(sch_1):m_m_cs_n(4)"
				( attribute "CDS_PHYS_NET_NAME" "M_M_CS_N<4>"
					( Origin gPackager )
				)
				( attribute "PNN" "M_M_CS_N<4>"
					( Origin gPackager )
				)
				( objectStatus "M_M_CS_N<4>" )
			)
			( signal "@baseboard_fab2_lib.baseboard_fab2(sch_1):m_m_cs_n(5)"
				( attribute "CDS_PHYS_NET_NAME" "M_M_CS_N<5>"
					( Origin gPackager )
				)
				( attribute "PNN" "M_M_CS_N<5>"
					( Origin gPackager )
				)
				( objectStatus "M_M_CS_N<5>" )
			)
			( signal "@baseboard_fab2_lib.baseboard_fab2(sch_1):m_m_cs_n(6)"
				( attribute "CDS_PHYS_NET_NAME" "M_M_CS_N<6>"
					( Origin gPackager )
				)
				( attribute "PNN" "M_M_CS_N<6>"
					( Origin gPackager )
				)
				( objectStatus "M_M_CS_N<6>" )
			)
			( signal "@baseboard_fab2_lib.baseboard_fab2(sch_1):m_m_cs_n(7)"
				( attribute "CDS_PHYS_NET_NAME" "M_M_CS_N<7>"
					( Origin gPackager )
				)
				( attribute "PNN" "M_M_CS_N<7>"
					( Origin gPackager )
				)
				( objectStatus "M_M_CS_N<7>" )
			)
			( signal "@baseboard_fab2_lib.baseboard_fab2(sch_1):m_m_dq(0)"
				( attribute "CDS_PHYS_NET_NAME" "M_M_DQ<0>"
					( Origin gPackager )
				)
				( attribute "PNN" "M_M_DQ<0>"
					( Origin gPackager )
				)
				( objectStatus "M_M_DQ<0>" )
			)
			( signal "@baseboard_fab2_lib.baseboard_fab2(sch_1):m_m_dq(1)"
				( attribute "CDS_PHYS_NET_NAME" "M_M_DQ<1>"
					( Origin gPackager )
				)
				( attribute "PNN" "M_M_DQ<1>"
					( Origin gPackager )
				)
				( objectStatus "M_M_DQ<1>" )
			)
			( signal "@baseboard_fab2_lib.baseboard_fab2(sch_1):m_m_dq(2)"
				( attribute "CDS_PHYS_NET_NAME" "M_M_DQ<2>"
					( Origin gPackager )
				)
				( attribute "PNN" "M_M_DQ<2>"
					( Origin gPackager )
				)
				( objectStatus "M_M_DQ<2>" )
			)
			( signal "@baseboard_fab2_lib.baseboard_fab2(sch_1):m_m_dq(3)"
				( attribute "CDS_PHYS_NET_NAME" "M_M_DQ<3>"
					( Origin gPackager )
				)
				( attribute "PNN" "M_M_DQ<3>"
					( Origin gPackager )
				)
				( objectStatus "M_M_DQ<3>" )
			)
			( signal "@baseboard_fab2_lib.baseboard_fab2(sch_1):m_m_dq(4)"
				( attribute "CDS_PHYS_NET_NAME" "M_M_DQ<4>"
					( Origin gPackager )
				)
				( attribute "PNN" "M_M_DQ<4>"
					( Origin gPackager )
				)
				( objectStatus "M_M_DQ<4>" )
			)
			( signal "@baseboard_fab2_lib.baseboard_fab2(sch_1):m_m_dq(5)"
				( attribute "CDS_PHYS_NET_NAME" "M_M_DQ<5>"
					( Origin gPackager )
				)
				( attribute "PNN" "M_M_DQ<5>"
					( Origin gPackager )
				)
				( objectStatus "M_M_DQ<5>" )
			)
			( signal "@baseboard_fab2_lib.baseboard_fab2(sch_1):m_m_dq(6)"
				( attribute "CDS_PHYS_NET_NAME" "M_M_DQ<6>"
					( Origin gPackager )
				)
				( attribute "PNN" "M_M_DQ<6>"
					( Origin gPackager )
				)
				( objectStatus "M_M_DQ<6>" )
			)
			( signal "@baseboard_fab2_lib.baseboard_fab2(sch_1):m_m_dq(7)"
				( attribute "CDS_PHYS_NET_NAME" "M_M_DQ<7>"
					( Origin gPackager )
				)
				( attribute "PNN" "M_M_DQ<7>"
					( Origin gPackager )
				)
				( objectStatus "M_M_DQ<7>" )
			)
			( signal "@baseboard_fab2_lib.baseboard_fab2(sch_1):m_m_dq(8)"
				( attribute "CDS_PHYS_NET_NAME" "M_M_DQ<8>"
					( Origin gPackager )
				)
				( attribute "PNN" "M_M_DQ<8>"
					( Origin gPackager )
				)
				( objectStatus "M_M_DQ<8>" )
			)
			( signal "@baseboard_fab2_lib.baseboard_fab2(sch_1):m_m_dq(9)"
				( attribute "CDS_PHYS_NET_NAME" "M_M_DQ<9>"
					( Origin gPackager )
				)
				( attribute "PNN" "M_M_DQ<9>"
					( Origin gPackager )
				)
				( objectStatus "M_M_DQ<9>" )
			)
			( signal "@baseboard_fab2_lib.baseboard_fab2(sch_1):m_m_dq(10)"
				( attribute "CDS_PHYS_NET_NAME" "M_M_DQ<10>"
					( Origin gPackager )
				)
				( attribute "PNN" "M_M_DQ<10>"
					( Origin gPackager )
				)
				( objectStatus "M_M_DQ<10>" )
			)
			( signal "@baseboard_fab2_lib.baseboard_fab2(sch_1):m_m_dq(11)"
				( attribute "CDS_PHYS_NET_NAME" "M_M_DQ<11>"
					( Origin gPackager )
				)
				( attribute "PNN" "M_M_DQ<11>"
					( Origin gPackager )
				)
				( objectStatus "M_M_DQ<11>" )
			)
			( signal "@baseboard_fab2_lib.baseboard_fab2(sch_1):m_m_dq(12)"
				( attribute "CDS_PHYS_NET_NAME" "M_M_DQ<12>"
					( Origin gPackager )
				)
				( attribute "PNN" "M_M_DQ<12>"
					( Origin gPackager )
				)
				( objectStatus "M_M_DQ<12>" )
			)
			( signal "@baseboard_fab2_lib.baseboard_fab2(sch_1):m_m_dq(13)"
				( attribute "CDS_PHYS_NET_NAME" "M_M_DQ<13>"
					( Origin gPackager )
				)
				( attribute "PNN" "M_M_DQ<13>"
					( Origin gPackager )
				)
				( objectStatus "M_M_DQ<13>" )
			)
			( signal "@baseboard_fab2_lib.baseboard_fab2(sch_1):m_m_dq(14)"
				( attribute "CDS_PHYS_NET_NAME" "M_M_DQ<14>"
					( Origin gPackager )
				)
				( attribute "PNN" "M_M_DQ<14>"
					( Origin gPackager )
				)
				( objectStatus "M_M_DQ<14>" )
			)
			( signal "@baseboard_fab2_lib.baseboard_fab2(sch_1):m_m_dq(15)"
				( attribute "CDS_PHYS_NET_NAME" "M_M_DQ<15>"
					( Origin gPackager )
				)
				( attribute "PNN" "M_M_DQ<15>"
					( Origin gPackager )
				)
				( objectStatus "M_M_DQ<15>" )
			)
			( signal "@baseboard_fab2_lib.baseboard_fab2(sch_1):m_m_dq(16)"
				( attribute "CDS_PHYS_NET_NAME" "M_M_DQ<16>"
					( Origin gPackager )
				)
				( attribute "PNN" "M_M_DQ<16>"
					( Origin gPackager )
				)
				( objectStatus "M_M_DQ<16>" )
			)
			( signal "@baseboard_fab2_lib.baseboard_fab2(sch_1):m_m_dq(17)"
				( attribute "CDS_PHYS_NET_NAME" "M_M_DQ<17>"
					( Origin gPackager )
				)
				( attribute "PNN" "M_M_DQ<17>"
					( Origin gPackager )
				)
				( objectStatus "M_M_DQ<17>" )
			)
			( signal "@baseboard_fab2_lib.baseboard_fab2(sch_1):m_m_dq(18)"
				( attribute "CDS_PHYS_NET_NAME" "M_M_DQ<18>"
					( Origin gPackager )
				)
				( attribute "PNN" "M_M_DQ<18>"
					( Origin gPackager )
				)
				( objectStatus "M_M_DQ<18>" )
			)
			( signal "@baseboard_fab2_lib.baseboard_fab2(sch_1):m_m_dq(19)"
				( attribute "CDS_PHYS_NET_NAME" "M_M_DQ<19>"
					( Origin gPackager )
				)
				( attribute "PNN" "M_M_DQ<19>"
					( Origin gPackager )
				)
				( objectStatus "M_M_DQ<19>" )
			)
			( signal "@baseboard_fab2_lib.baseboard_fab2(sch_1):m_m_dq(20)"
				( attribute "CDS_PHYS_NET_NAME" "M_M_DQ<20>"
					( Origin gPackager )
				)
				( attribute "PNN" "M_M_DQ<20>"
					( Origin gPackager )
				)
				( objectStatus "M_M_DQ<20>" )
			)
			( signal "@baseboard_fab2_lib.baseboard_fab2(sch_1):m_m_dq(21)"
				( attribute "CDS_PHYS_NET_NAME" "M_M_DQ<21>"
					( Origin gPackager )
				)
				( attribute "PNN" "M_M_DQ<21>"
					( Origin gPackager )
				)
				( objectStatus "M_M_DQ<21>" )
			)
			( signal "@baseboard_fab2_lib.baseboard_fab2(sch_1):m_m_dq(22)"
				( attribute "CDS_PHYS_NET_NAME" "M_M_DQ<22>"
					( Origin gPackager )
				)
				( attribute "PNN" "M_M_DQ<22>"
					( Origin gPackager )
				)
				( objectStatus "M_M_DQ<22>" )
			)
			( signal "@baseboard_fab2_lib.baseboard_fab2(sch_1):m_m_dq(23)"
				( attribute "CDS_PHYS_NET_NAME" "M_M_DQ<23>"
					( Origin gPackager )
				)
				( attribute "PNN" "M_M_DQ<23>"
					( Origin gPackager )
				)
				( objectStatus "M_M_DQ<23>" )
			)
			( signal "@baseboard_fab2_lib.baseboard_fab2(sch_1):m_m_dq(24)"
				( attribute "CDS_PHYS_NET_NAME" "M_M_DQ<24>"
					( Origin gPackager )
				)
				( attribute "PNN" "M_M_DQ<24>"
					( Origin gPackager )
				)
				( objectStatus "M_M_DQ<24>" )
			)
			( signal "@baseboard_fab2_lib.baseboard_fab2(sch_1):m_m_dq(25)"
				( attribute "CDS_PHYS_NET_NAME" "M_M_DQ<25>"
					( Origin gPackager )
				)
				( attribute "PNN" "M_M_DQ<25>"
					( Origin gPackager )
				)
				( objectStatus "M_M_DQ<25>" )
			)
			( signal "@baseboard_fab2_lib.baseboard_fab2(sch_1):m_m_dq(26)"
				( attribute "CDS_PHYS_NET_NAME" "M_M_DQ<26>"
					( Origin gPackager )
				)
				( attribute "PNN" "M_M_DQ<26>"
					( Origin gPackager )
				)
				( objectStatus "M_M_DQ<26>" )
			)
			( signal "@baseboard_fab2_lib.baseboard_fab2(sch_1):m_m_dq(27)"
				( attribute "CDS_PHYS_NET_NAME" "M_M_DQ<27>"
					( Origin gPackager )
				)
				( attribute "PNN" "M_M_DQ<27>"
					( Origin gPackager )
				)
				( objectStatus "M_M_DQ<27>" )
			)
			( signal "@baseboard_fab2_lib.baseboard_fab2(sch_1):m_m_dq(28)"
				( attribute "CDS_PHYS_NET_NAME" "M_M_DQ<28>"
					( Origin gPackager )
				)
				( attribute "PNN" "M_M_DQ<28>"
					( Origin gPackager )
				)
				( objectStatus "M_M_DQ<28>" )
			)
			( signal "@baseboard_fab2_lib.baseboard_fab2(sch_1):m_m_dq(29)"
				( attribute "CDS_PHYS_NET_NAME" "M_M_DQ<29>"
					( Origin gPackager )
				)
				( attribute "PNN" "M_M_DQ<29>"
					( Origin gPackager )
				)
				( objectStatus "M_M_DQ<29>" )
			)
			( signal "@baseboard_fab2_lib.baseboard_fab2(sch_1):m_m_dq(30)"
				( attribute "CDS_PHYS_NET_NAME" "M_M_DQ<30>"
					( Origin gPackager )
				)
				( attribute "PNN" "M_M_DQ<30>"
					( Origin gPackager )
				)
				( objectStatus "M_M_DQ<30>" )
			)
			( signal "@baseboard_fab2_lib.baseboard_fab2(sch_1):m_m_dq(31)"
				( attribute "CDS_PHYS_NET_NAME" "M_M_DQ<31>"
					( Origin gPackager )
				)
				( attribute "PNN" "M_M_DQ<31>"
					( Origin gPackager )
				)
				( objectStatus "M_M_DQ<31>" )
			)
			( signal "@baseboard_fab2_lib.baseboard_fab2(sch_1):m_m_dq(32)"
				( attribute "CDS_PHYS_NET_NAME" "M_M_DQ<32>"
					( Origin gPackager )
				)
				( attribute "PNN" "M_M_DQ<32>"
					( Origin gPackager )
				)
				( objectStatus "M_M_DQ<32>" )
			)
			( signal "@baseboard_fab2_lib.baseboard_fab2(sch_1):m_m_dq(33)"
				( attribute "CDS_PHYS_NET_NAME" "M_M_DQ<33>"
					( Origin gPackager )
				)
				( attribute "PNN" "M_M_DQ<33>"
					( Origin gPackager )
				)
				( objectStatus "M_M_DQ<33>" )
			)
			( signal "@baseboard_fab2_lib.baseboard_fab2(sch_1):m_m_dq(34)"
				( attribute "CDS_PHYS_NET_NAME" "M_M_DQ<34>"
					( Origin gPackager )
				)
				( attribute "PNN" "M_M_DQ<34>"
					( Origin gPackager )
				)
				( objectStatus "M_M_DQ<34>" )
			)
			( signal "@baseboard_fab2_lib.baseboard_fab2(sch_1):m_m_dq(35)"
				( attribute "CDS_PHYS_NET_NAME" "M_M_DQ<35>"
					( Origin gPackager )
				)
				( attribute "PNN" "M_M_DQ<35>"
					( Origin gPackager )
				)
				( objectStatus "M_M_DQ<35>" )
			)
			( signal "@baseboard_fab2_lib.baseboard_fab2(sch_1):m_m_dq(36)"
				( attribute "CDS_PHYS_NET_NAME" "M_M_DQ<36>"
					( Origin gPackager )
				)
				( attribute "PNN" "M_M_DQ<36>"
					( Origin gPackager )
				)
				( objectStatus "M_M_DQ<36>" )
			)
			( signal "@baseboard_fab2_lib.baseboard_fab2(sch_1):m_m_dq(37)"
				( attribute "CDS_PHYS_NET_NAME" "M_M_DQ<37>"
					( Origin gPackager )
				)
				( attribute "PNN" "M_M_DQ<37>"
					( Origin gPackager )
				)
				( objectStatus "M_M_DQ<37>" )
			)
			( signal "@baseboard_fab2_lib.baseboard_fab2(sch_1):m_m_dq(38)"
				( attribute "CDS_PHYS_NET_NAME" "M_M_DQ<38>"
					( Origin gPackager )
				)
				( attribute "PNN" "M_M_DQ<38>"
					( Origin gPackager )
				)
				( objectStatus "M_M_DQ<38>" )
			)
			( signal "@baseboard_fab2_lib.baseboard_fab2(sch_1):m_m_dq(39)"
				( attribute "CDS_PHYS_NET_NAME" "M_M_DQ<39>"
					( Origin gPackager )
				)
				( attribute "PNN" "M_M_DQ<39>"
					( Origin gPackager )
				)
				( objectStatus "M_M_DQ<39>" )
			)
			( signal "@baseboard_fab2_lib.baseboard_fab2(sch_1):m_m_dq(40)"
				( attribute "CDS_PHYS_NET_NAME" "M_M_DQ<40>"
					( Origin gPackager )
				)
				( attribute "PNN" "M_M_DQ<40>"
					( Origin gPackager )
				)
				( objectStatus "M_M_DQ<40>" )
			)
			( signal "@baseboard_fab2_lib.baseboard_fab2(sch_1):m_m_dq(41)"
				( attribute "CDS_PHYS_NET_NAME" "M_M_DQ<41>"
					( Origin gPackager )
				)
				( attribute "PNN" "M_M_DQ<41>"
					( Origin gPackager )
				)
				( objectStatus "M_M_DQ<41>" )
			)
			( signal "@baseboard_fab2_lib.baseboard_fab2(sch_1):m_m_dq(42)"
				( attribute "CDS_PHYS_NET_NAME" "M_M_DQ<42>"
					( Origin gPackager )
				)
				( attribute "PNN" "M_M_DQ<42>"
					( Origin gPackager )
				)
				( objectStatus "M_M_DQ<42>" )
			)
			( signal "@baseboard_fab2_lib.baseboard_fab2(sch_1):m_m_dq(43)"
				( attribute "CDS_PHYS_NET_NAME" "M_M_DQ<43>"
					( Origin gPackager )
				)
				( attribute "PNN" "M_M_DQ<43>"
					( Origin gPackager )
				)
				( objectStatus "M_M_DQ<43>" )
			)
			( signal "@baseboard_fab2_lib.baseboard_fab2(sch_1):m_m_dq(44)"
				( attribute "CDS_PHYS_NET_NAME" "M_M_DQ<44>"
					( Origin gPackager )
				)
				( attribute "PNN" "M_M_DQ<44>"
					( Origin gPackager )
				)
				( objectStatus "M_M_DQ<44>" )
			)
			( signal "@baseboard_fab2_lib.baseboard_fab2(sch_1):m_m_dq(45)"
				( attribute "CDS_PHYS_NET_NAME" "M_M_DQ<45>"
					( Origin gPackager )
				)
				( attribute "PNN" "M_M_DQ<45>"
					( Origin gPackager )
				)
				( objectStatus "M_M_DQ<45>" )
			)
			( signal "@baseboard_fab2_lib.baseboard_fab2(sch_1):m_m_dq(46)"
				( attribute "CDS_PHYS_NET_NAME" "M_M_DQ<46>"
					( Origin gPackager )
				)
				( attribute "PNN" "M_M_DQ<46>"
					( Origin gPackager )
				)
				( objectStatus "M_M_DQ<46>" )
			)
			( signal "@baseboard_fab2_lib.baseboard_fab2(sch_1):m_m_dq(47)"
				( attribute "CDS_PHYS_NET_NAME" "M_M_DQ<47>"
					( Origin gPackager )
				)
				( attribute "PNN" "M_M_DQ<47>"
					( Origin gPackager )
				)
				( objectStatus "M_M_DQ<47>" )
			)
			( signal "@baseboard_fab2_lib.baseboard_fab2(sch_1):m_m_dq(48)"
				( attribute "CDS_PHYS_NET_NAME" "M_M_DQ<48>"
					( Origin gPackager )
				)
				( attribute "PNN" "M_M_DQ<48>"
					( Origin gPackager )
				)
				( objectStatus "M_M_DQ<48>" )
			)
			( signal "@baseboard_fab2_lib.baseboard_fab2(sch_1):m_m_dq(49)"
				( attribute "CDS_PHYS_NET_NAME" "M_M_DQ<49>"
					( Origin gPackager )
				)
				( attribute "PNN" "M_M_DQ<49>"
					( Origin gPackager )
				)
				( objectStatus "M_M_DQ<49>" )
			)
			( signal "@baseboard_fab2_lib.baseboard_fab2(sch_1):m_m_dq(50)"
				( attribute "CDS_PHYS_NET_NAME" "M_M_DQ<50>"
					( Origin gPackager )
				)
				( attribute "PNN" "M_M_DQ<50>"
					( Origin gPackager )
				)
				( objectStatus "M_M_DQ<50>" )
			)
			( signal "@baseboard_fab2_lib.baseboard_fab2(sch_1):m_m_dq(51)"
				( attribute "CDS_PHYS_NET_NAME" "M_M_DQ<51>"
					( Origin gPackager )
				)
				( attribute "PNN" "M_M_DQ<51>"
					( Origin gPackager )
				)
				( objectStatus "M_M_DQ<51>" )
			)
			( signal "@baseboard_fab2_lib.baseboard_fab2(sch_1):m_m_dq(52)"
				( attribute "CDS_PHYS_NET_NAME" "M_M_DQ<52>"
					( Origin gPackager )
				)
				( attribute "PNN" "M_M_DQ<52>"
					( Origin gPackager )
				)
				( objectStatus "M_M_DQ<52>" )
			)
			( signal "@baseboard_fab2_lib.baseboard_fab2(sch_1):m_m_dq(53)"
				( attribute "CDS_PHYS_NET_NAME" "M_M_DQ<53>"
					( Origin gPackager )
				)
				( attribute "PNN" "M_M_DQ<53>"
					( Origin gPackager )
				)
				( objectStatus "M_M_DQ<53>" )
			)
			( signal "@baseboard_fab2_lib.baseboard_fab2(sch_1):m_m_dq(54)"
				( attribute "CDS_PHYS_NET_NAME" "M_M_DQ<54>"
					( Origin gPackager )
				)
				( attribute "PNN" "M_M_DQ<54>"
					( Origin gPackager )
				)
				( objectStatus "M_M_DQ<54>" )
			)
			( signal "@baseboard_fab2_lib.baseboard_fab2(sch_1):m_m_dq(55)"
				( attribute "CDS_PHYS_NET_NAME" "M_M_DQ<55>"
					( Origin gPackager )
				)
				( attribute "PNN" "M_M_DQ<55>"
					( Origin gPackager )
				)
				( objectStatus "M_M_DQ<55>" )
			)
			( signal "@baseboard_fab2_lib.baseboard_fab2(sch_1):m_m_dq(56)"
				( attribute "CDS_PHYS_NET_NAME" "M_M_DQ<56>"
					( Origin gPackager )
				)
				( attribute "PNN" "M_M_DQ<56>"
					( Origin gPackager )
				)
				( objectStatus "M_M_DQ<56>" )
			)
			( signal "@baseboard_fab2_lib.baseboard_fab2(sch_1):m_m_dq(57)"
				( attribute "CDS_PHYS_NET_NAME" "M_M_DQ<57>"
					( Origin gPackager )
				)
				( attribute "PNN" "M_M_DQ<57>"
					( Origin gPackager )
				)
				( objectStatus "M_M_DQ<57>" )
			)
			( signal "@baseboard_fab2_lib.baseboard_fab2(sch_1):m_m_dq(58)"
				( attribute "CDS_PHYS_NET_NAME" "M_M_DQ<58>"
					( Origin gPackager )
				)
				( attribute "PNN" "M_M_DQ<58>"
					( Origin gPackager )
				)
				( objectStatus "M_M_DQ<58>" )
			)
			( signal "@baseboard_fab2_lib.baseboard_fab2(sch_1):m_m_dq(59)"
				( attribute "CDS_PHYS_NET_NAME" "M_M_DQ<59>"
					( Origin gPackager )
				)
				( attribute "PNN" "M_M_DQ<59>"
					( Origin gPackager )
				)
				( objectStatus "M_M_DQ<59>" )
			)
			( signal "@baseboard_fab2_lib.baseboard_fab2(sch_1):m_m_dq(60)"
				( attribute "CDS_PHYS_NET_NAME" "M_M_DQ<60>"
					( Origin gPackager )
				)
				( attribute "PNN" "M_M_DQ<60>"
					( Origin gPackager )
				)
				( objectStatus "M_M_DQ<60>" )
			)
			( signal "@baseboard_fab2_lib.baseboard_fab2(sch_1):m_m_dq(61)"
				( attribute "CDS_PHYS_NET_NAME" "M_M_DQ<61>"
					( Origin gPackager )
				)
				( attribute "PNN" "M_M_DQ<61>"
					( Origin gPackager )
				)
				( objectStatus "M_M_DQ<61>" )
			)
			( signal "@baseboard_fab2_lib.baseboard_fab2(sch_1):m_m_dq(62)"
				( attribute "CDS_PHYS_NET_NAME" "M_M_DQ<62>"
					( Origin gPackager )
				)
				( attribute "PNN" "M_M_DQ<62>"
					( Origin gPackager )
				)
				( objectStatus "M_M_DQ<62>" )
			)
			( signal "@baseboard_fab2_lib.baseboard_fab2(sch_1):m_m_dq(63)"
				( attribute "CDS_PHYS_NET_NAME" "M_M_DQ<63>"
					( Origin gPackager )
				)
				( attribute "PNN" "M_M_DQ<63>"
					( Origin gPackager )
				)
				( objectStatus "M_M_DQ<63>" )
			)
			( signal "@baseboard_fab2_lib.baseboard_fab2(sch_1):m_m_dqs_dn(0)"
				( attribute "CDS_PHYS_NET_NAME" "M_M_DQS_DN<0>"
					( Origin gPackager )
				)
				( attribute "PNN" "M_M_DQS_DN<0>"
					( Origin gPackager )
				)
				( objectStatus "M_M_DQS_DN<0>" )
			)
			( signal "@baseboard_fab2_lib.baseboard_fab2(sch_1):m_m_dqs_dn(1)"
				( attribute "CDS_PHYS_NET_NAME" "M_M_DQS_DN<1>"
					( Origin gPackager )
				)
				( attribute "PNN" "M_M_DQS_DN<1>"
					( Origin gPackager )
				)
				( objectStatus "M_M_DQS_DN<1>" )
			)
			( signal "@baseboard_fab2_lib.baseboard_fab2(sch_1):m_m_dqs_dn(2)"
				( attribute "CDS_PHYS_NET_NAME" "M_M_DQS_DN<2>"
					( Origin gPackager )
				)
				( attribute "PNN" "M_M_DQS_DN<2>"
					( Origin gPackager )
				)
				( objectStatus "M_M_DQS_DN<2>" )
			)
			( signal "@baseboard_fab2_lib.baseboard_fab2(sch_1):m_m_dqs_dn(3)"
				( attribute "CDS_PHYS_NET_NAME" "M_M_DQS_DN<3>"
					( Origin gPackager )
				)
				( attribute "PNN" "M_M_DQS_DN<3>"
					( Origin gPackager )
				)
				( objectStatus "M_M_DQS_DN<3>" )
			)
			( signal "@baseboard_fab2_lib.baseboard_fab2(sch_1):m_m_dqs_dn(4)"
				( attribute "CDS_PHYS_NET_NAME" "M_M_DQS_DN<4>"
					( Origin gPackager )
				)
				( attribute "PNN" "M_M_DQS_DN<4>"
					( Origin gPackager )
				)
				( objectStatus "M_M_DQS_DN<4>" )
			)
			( signal "@baseboard_fab2_lib.baseboard_fab2(sch_1):m_m_dqs_dn(5)"
				( attribute "CDS_PHYS_NET_NAME" "M_M_DQS_DN<5>"
					( Origin gPackager )
				)
				( attribute "PNN" "M_M_DQS_DN<5>"
					( Origin gPackager )
				)
				( objectStatus "M_M_DQS_DN<5>" )
			)
			( signal "@baseboard_fab2_lib.baseboard_fab2(sch_1):m_m_dqs_dn(6)"
				( attribute "CDS_PHYS_NET_NAME" "M_M_DQS_DN<6>"
					( Origin gPackager )
				)
				( attribute "PNN" "M_M_DQS_DN<6>"
					( Origin gPackager )
				)
				( objectStatus "M_M_DQS_DN<6>" )
			)
			( signal "@baseboard_fab2_lib.baseboard_fab2(sch_1):m_m_dqs_dn(7)"
				( attribute "CDS_PHYS_NET_NAME" "M_M_DQS_DN<7>"
					( Origin gPackager )
				)
				( attribute "PNN" "M_M_DQS_DN<7>"
					( Origin gPackager )
				)
				( objectStatus "M_M_DQS_DN<7>" )
			)
			( signal "@baseboard_fab2_lib.baseboard_fab2(sch_1):m_m_dqs_dn(8)"
				( attribute "CDS_PHYS_NET_NAME" "M_M_DQS_DN<8>"
					( Origin gPackager )
				)
				( attribute "PNN" "M_M_DQS_DN<8>"
					( Origin gPackager )
				)
				( objectStatus "M_M_DQS_DN<8>" )
			)
			( signal "@baseboard_fab2_lib.baseboard_fab2(sch_1):m_m_dqs_dn(9)"
				( attribute "CDS_PHYS_NET_NAME" "M_M_DQS_DN<9>"
					( Origin gPackager )
				)
				( attribute "PNN" "M_M_DQS_DN<9>"
					( Origin gPackager )
				)
				( objectStatus "M_M_DQS_DN<9>" )
			)
			( signal "@baseboard_fab2_lib.baseboard_fab2(sch_1):m_m_dqs_dn(10)"
				( attribute "CDS_PHYS_NET_NAME" "M_M_DQS_DN<10>"
					( Origin gPackager )
				)
				( attribute "PNN" "M_M_DQS_DN<10>"
					( Origin gPackager )
				)
				( objectStatus "M_M_DQS_DN<10>" )
			)
			( signal "@baseboard_fab2_lib.baseboard_fab2(sch_1):m_m_dqs_dn(11)"
				( attribute "CDS_PHYS_NET_NAME" "M_M_DQS_DN<11>"
					( Origin gPackager )
				)
				( attribute "PNN" "M_M_DQS_DN<11>"
					( Origin gPackager )
				)
				( objectStatus "M_M_DQS_DN<11>" )
			)
			( signal "@baseboard_fab2_lib.baseboard_fab2(sch_1):m_m_dqs_dn(12)"
				( attribute "CDS_PHYS_NET_NAME" "M_M_DQS_DN<12>"
					( Origin gPackager )
				)
				( attribute "PNN" "M_M_DQS_DN<12>"
					( Origin gPackager )
				)
				( objectStatus "M_M_DQS_DN<12>" )
			)
			( signal "@baseboard_fab2_lib.baseboard_fab2(sch_1):m_m_dqs_dn(13)"
				( attribute "CDS_PHYS_NET_NAME" "M_M_DQS_DN<13>"
					( Origin gPackager )
				)
				( attribute "PNN" "M_M_DQS_DN<13>"
					( Origin gPackager )
				)
				( objectStatus "M_M_DQS_DN<13>" )
			)
			( signal "@baseboard_fab2_lib.baseboard_fab2(sch_1):m_m_dqs_dn(14)"
				( attribute "CDS_PHYS_NET_NAME" "M_M_DQS_DN<14>"
					( Origin gPackager )
				)
				( attribute "PNN" "M_M_DQS_DN<14>"
					( Origin gPackager )
				)
				( objectStatus "M_M_DQS_DN<14>" )
			)
			( signal "@baseboard_fab2_lib.baseboard_fab2(sch_1):m_m_dqs_dn(15)"
				( attribute "CDS_PHYS_NET_NAME" "M_M_DQS_DN<15>"
					( Origin gPackager )
				)
				( attribute "PNN" "M_M_DQS_DN<15>"
					( Origin gPackager )
				)
				( objectStatus "M_M_DQS_DN<15>" )
			)
			( signal "@baseboard_fab2_lib.baseboard_fab2(sch_1):m_m_dqs_dn(16)"
				( attribute "CDS_PHYS_NET_NAME" "M_M_DQS_DN<16>"
					( Origin gPackager )
				)
				( attribute "PNN" "M_M_DQS_DN<16>"
					( Origin gPackager )
				)
				( objectStatus "M_M_DQS_DN<16>" )
			)
			( signal "@baseboard_fab2_lib.baseboard_fab2(sch_1):m_m_dqs_dn(17)"
				( attribute "CDS_PHYS_NET_NAME" "M_M_DQS_DN<17>"
					( Origin gPackager )
				)
				( attribute "PNN" "M_M_DQS_DN<17>"
					( Origin gPackager )
				)
				( objectStatus "M_M_DQS_DN<17>" )
			)
			( signal "@baseboard_fab2_lib.baseboard_fab2(sch_1):m_m_dqs_dp(0)"
				( attribute "CDS_PHYS_NET_NAME" "M_M_DQS_DP<0>"
					( Origin gPackager )
				)
				( attribute "PNN" "M_M_DQS_DP<0>"
					( Origin gPackager )
				)
				( objectStatus "M_M_DQS_DP<0>" )
			)
			( signal "@baseboard_fab2_lib.baseboard_fab2(sch_1):m_m_dqs_dp(1)"
				( attribute "CDS_PHYS_NET_NAME" "M_M_DQS_DP<1>"
					( Origin gPackager )
				)
				( attribute "PNN" "M_M_DQS_DP<1>"
					( Origin gPackager )
				)
				( objectStatus "M_M_DQS_DP<1>" )
			)
			( signal "@baseboard_fab2_lib.baseboard_fab2(sch_1):m_m_dqs_dp(2)"
				( attribute "CDS_PHYS_NET_NAME" "M_M_DQS_DP<2>"
					( Origin gPackager )
				)
				( attribute "PNN" "M_M_DQS_DP<2>"
					( Origin gPackager )
				)
				( objectStatus "M_M_DQS_DP<2>" )
			)
			( signal "@baseboard_fab2_lib.baseboard_fab2(sch_1):m_m_dqs_dp(3)"
				( attribute "CDS_PHYS_NET_NAME" "M_M_DQS_DP<3>"
					( Origin gPackager )
				)
				( attribute "PNN" "M_M_DQS_DP<3>"
					( Origin gPackager )
				)
				( objectStatus "M_M_DQS_DP<3>" )
			)
			( signal "@baseboard_fab2_lib.baseboard_fab2(sch_1):m_m_dqs_dp(4)"
				( attribute "CDS_PHYS_NET_NAME" "M_M_DQS_DP<4>"
					( Origin gPackager )
				)
				( attribute "PNN" "M_M_DQS_DP<4>"
					( Origin gPackager )
				)
				( objectStatus "M_M_DQS_DP<4>" )
			)
			( signal "@baseboard_fab2_lib.baseboard_fab2(sch_1):m_m_dqs_dp(5)"
				( attribute "CDS_PHYS_NET_NAME" "M_M_DQS_DP<5>"
					( Origin gPackager )
				)
				( attribute "PNN" "M_M_DQS_DP<5>"
					( Origin gPackager )
				)
				( objectStatus "M_M_DQS_DP<5>" )
			)
			( signal "@baseboard_fab2_lib.baseboard_fab2(sch_1):m_m_dqs_dp(6)"
				( attribute "CDS_PHYS_NET_NAME" "M_M_DQS_DP<6>"
					( Origin gPackager )
				)
				( attribute "PNN" "M_M_DQS_DP<6>"
					( Origin gPackager )
				)
				( objectStatus "M_M_DQS_DP<6>" )
			)
			( signal "@baseboard_fab2_lib.baseboard_fab2(sch_1):m_m_dqs_dp(7)"
				( attribute "CDS_PHYS_NET_NAME" "M_M_DQS_DP<7>"
					( Origin gPackager )
				)
				( attribute "PNN" "M_M_DQS_DP<7>"
					( Origin gPackager )
				)
				( objectStatus "M_M_DQS_DP<7>" )
			)
			( signal "@baseboard_fab2_lib.baseboard_fab2(sch_1):m_m_dqs_dp(8)"
				( attribute "CDS_PHYS_NET_NAME" "M_M_DQS_DP<8>"
					( Origin gPackager )
				)
				( attribute "PNN" "M_M_DQS_DP<8>"
					( Origin gPackager )
				)
				( objectStatus "M_M_DQS_DP<8>" )
			)
			( signal "@baseboard_fab2_lib.baseboard_fab2(sch_1):m_m_dqs_dp(9)"
				( attribute "CDS_PHYS_NET_NAME" "M_M_DQS_DP<9>"
					( Origin gPackager )
				)
				( attribute "PNN" "M_M_DQS_DP<9>"
					( Origin gPackager )
				)
				( objectStatus "M_M_DQS_DP<9>" )
			)
			( signal "@baseboard_fab2_lib.baseboard_fab2(sch_1):m_m_dqs_dp(10)"
				( attribute "CDS_PHYS_NET_NAME" "M_M_DQS_DP<10>"
					( Origin gPackager )
				)
				( attribute "PNN" "M_M_DQS_DP<10>"
					( Origin gPackager )
				)
				( objectStatus "M_M_DQS_DP<10>" )
			)
			( signal "@baseboard_fab2_lib.baseboard_fab2(sch_1):m_m_dqs_dp(11)"
				( attribute "CDS_PHYS_NET_NAME" "M_M_DQS_DP<11>"
					( Origin gPackager )
				)
				( attribute "PNN" "M_M_DQS_DP<11>"
					( Origin gPackager )
				)
				( objectStatus "M_M_DQS_DP<11>" )
			)
			( signal "@baseboard_fab2_lib.baseboard_fab2(sch_1):m_m_dqs_dp(12)"
				( attribute "CDS_PHYS_NET_NAME" "M_M_DQS_DP<12>"
					( Origin gPackager )
				)
				( attribute "PNN" "M_M_DQS_DP<12>"
					( Origin gPackager )
				)
				( objectStatus "M_M_DQS_DP<12>" )
			)
			( signal "@baseboard_fab2_lib.baseboard_fab2(sch_1):m_m_dqs_dp(13)"
				( attribute "CDS_PHYS_NET_NAME" "M_M_DQS_DP<13>"
					( Origin gPackager )
				)
				( attribute "PNN" "M_M_DQS_DP<13>"
					( Origin gPackager )
				)
				( objectStatus "M_M_DQS_DP<13>" )
			)
			( signal "@baseboard_fab2_lib.baseboard_fab2(sch_1):m_m_dqs_dp(14)"
				( attribute "CDS_PHYS_NET_NAME" "M_M_DQS_DP<14>"
					( Origin gPackager )
				)
				( attribute "PNN" "M_M_DQS_DP<14>"
					( Origin gPackager )
				)
				( objectStatus "M_M_DQS_DP<14>" )
			)
			( signal "@baseboard_fab2_lib.baseboard_fab2(sch_1):m_m_dqs_dp(15)"
				( attribute "CDS_PHYS_NET_NAME" "M_M_DQS_DP<15>"
					( Origin gPackager )
				)
				( attribute "PNN" "M_M_DQS_DP<15>"
					( Origin gPackager )
				)
				( objectStatus "M_M_DQS_DP<15>" )
			)
			( signal "@baseboard_fab2_lib.baseboard_fab2(sch_1):m_m_dqs_dp(16)"
				( attribute "CDS_PHYS_NET_NAME" "M_M_DQS_DP<16>"
					( Origin gPackager )
				)
				( attribute "PNN" "M_M_DQS_DP<16>"
					( Origin gPackager )
				)
				( objectStatus "M_M_DQS_DP<16>" )
			)
			( signal "@baseboard_fab2_lib.baseboard_fab2(sch_1):m_m_dqs_dp(17)"
				( attribute "CDS_PHYS_NET_NAME" "M_M_DQS_DP<17>"
					( Origin gPackager )
				)
				( attribute "PNN" "M_M_DQS_DP<17>"
					( Origin gPackager )
				)
				( objectStatus "M_M_DQS_DP<17>" )
			)
			( signal "@baseboard_fab2_lib.baseboard_fab2(sch_1):m_m_ecc(0)"
				( attribute "CDS_PHYS_NET_NAME" "M_M_ECC<0>"
					( Origin gPackager )
				)
				( attribute "PNN" "M_M_ECC<0>"
					( Origin gPackager )
				)
				( objectStatus "M_M_ECC<0>" )
			)
			( signal "@baseboard_fab2_lib.baseboard_fab2(sch_1):m_m_ecc(1)"
				( attribute "CDS_PHYS_NET_NAME" "M_M_ECC<1>"
					( Origin gPackager )
				)
				( attribute "PNN" "M_M_ECC<1>"
					( Origin gPackager )
				)
				( objectStatus "M_M_ECC<1>" )
			)
			( signal "@baseboard_fab2_lib.baseboard_fab2(sch_1):m_m_ecc(2)"
				( attribute "CDS_PHYS_NET_NAME" "M_M_ECC<2>"
					( Origin gPackager )
				)
				( attribute "PNN" "M_M_ECC<2>"
					( Origin gPackager )
				)
				( objectStatus "M_M_ECC<2>" )
			)
			( signal "@baseboard_fab2_lib.baseboard_fab2(sch_1):m_m_ecc(3)"
				( attribute "CDS_PHYS_NET_NAME" "M_M_ECC<3>"
					( Origin gPackager )
				)
				( attribute "PNN" "M_M_ECC<3>"
					( Origin gPackager )
				)
				( objectStatus "M_M_ECC<3>" )
			)
			( signal "@baseboard_fab2_lib.baseboard_fab2(sch_1):m_m_ecc(4)"
				( attribute "CDS_PHYS_NET_NAME" "M_M_ECC<4>"
					( Origin gPackager )
				)
				( attribute "PNN" "M_M_ECC<4>"
					( Origin gPackager )
				)
				( objectStatus "M_M_ECC<4>" )
			)
			( signal "@baseboard_fab2_lib.baseboard_fab2(sch_1):m_m_ecc(5)"
				( attribute "CDS_PHYS_NET_NAME" "M_M_ECC<5>"
					( Origin gPackager )
				)
				( attribute "PNN" "M_M_ECC<5>"
					( Origin gPackager )
				)
				( objectStatus "M_M_ECC<5>" )
			)
			( signal "@baseboard_fab2_lib.baseboard_fab2(sch_1):m_m_ecc(6)"
				( attribute "CDS_PHYS_NET_NAME" "M_M_ECC<6>"
					( Origin gPackager )
				)
				( attribute "PNN" "M_M_ECC<6>"
					( Origin gPackager )
				)
				( objectStatus "M_M_ECC<6>" )
			)
			( signal "@baseboard_fab2_lib.baseboard_fab2(sch_1):m_m_ecc(7)"
				( attribute "CDS_PHYS_NET_NAME" "M_M_ECC<7>"
					( Origin gPackager )
				)
				( attribute "PNN" "M_M_ECC<7>"
					( Origin gPackager )
				)
				( objectStatus "M_M_ECC<7>" )
			)
			( signal "@baseboard_fab2_lib.baseboard_fab2(sch_1):m_m_ma(0)"
				( attribute "CDS_PHYS_NET_NAME" "M_M_MA<0>"
					( Origin gPackager )
				)
				( attribute "PNN" "M_M_MA<0>"
					( Origin gPackager )
				)
				( objectStatus "M_M_MA<0>" )
			)
			( signal "@baseboard_fab2_lib.baseboard_fab2(sch_1):m_m_ma(1)"
				( attribute "CDS_PHYS_NET_NAME" "M_M_MA<1>"
					( Origin gPackager )
				)
				( attribute "PNN" "M_M_MA<1>"
					( Origin gPackager )
				)
				( objectStatus "M_M_MA<1>" )
			)
			( signal "@baseboard_fab2_lib.baseboard_fab2(sch_1):m_m_ma(2)"
				( attribute "CDS_PHYS_NET_NAME" "M_M_MA<2>"
					( Origin gPackager )
				)
				( attribute "PNN" "M_M_MA<2>"
					( Origin gPackager )
				)
				( objectStatus "M_M_MA<2>" )
			)
			( signal "@baseboard_fab2_lib.baseboard_fab2(sch_1):m_m_ma(3)"
				( attribute "CDS_PHYS_NET_NAME" "M_M_MA<3>"
					( Origin gPackager )
				)
				( attribute "PNN" "M_M_MA<3>"
					( Origin gPackager )
				)
				( objectStatus "M_M_MA<3>" )
			)
			( signal "@baseboard_fab2_lib.baseboard_fab2(sch_1):m_m_ma(4)"
				( attribute "CDS_PHYS_NET_NAME" "M_M_MA<4>"
					( Origin gPackager )
				)
				( attribute "PNN" "M_M_MA<4>"
					( Origin gPackager )
				)
				( objectStatus "M_M_MA<4>" )
			)
			( signal "@baseboard_fab2_lib.baseboard_fab2(sch_1):m_m_ma(5)"
				( attribute "CDS_PHYS_NET_NAME" "M_M_MA<5>"
					( Origin gPackager )
				)
				( attribute "PNN" "M_M_MA<5>"
					( Origin gPackager )
				)
				( objectStatus "M_M_MA<5>" )
			)
			( signal "@baseboard_fab2_lib.baseboard_fab2(sch_1):m_m_ma(6)"
				( attribute "CDS_PHYS_NET_NAME" "M_M_MA<6>"
					( Origin gPackager )
				)
				( attribute "PNN" "M_M_MA<6>"
					( Origin gPackager )
				)
				( objectStatus "M_M_MA<6>" )
			)
			( signal "@baseboard_fab2_lib.baseboard_fab2(sch_1):m_m_ma(7)"
				( attribute "CDS_PHYS_NET_NAME" "M_M_MA<7>"
					( Origin gPackager )
				)
				( attribute "PNN" "M_M_MA<7>"
					( Origin gPackager )
				)
				( objectStatus "M_M_MA<7>" )
			)
			( signal "@baseboard_fab2_lib.baseboard_fab2(sch_1):m_m_ma(8)"
				( attribute "CDS_PHYS_NET_NAME" "M_M_MA<8>"
					( Origin gPackager )
				)
				( attribute "PNN" "M_M_MA<8>"
					( Origin gPackager )
				)
				( objectStatus "M_M_MA<8>" )
			)
			( signal "@baseboard_fab2_lib.baseboard_fab2(sch_1):m_m_ma(9)"
				( attribute "CDS_PHYS_NET_NAME" "M_M_MA<9>"
					( Origin gPackager )
				)
				( attribute "PNN" "M_M_MA<9>"
					( Origin gPackager )
				)
				( objectStatus "M_M_MA<9>" )
			)
			( signal "@baseboard_fab2_lib.baseboard_fab2(sch_1):m_m_ma(10)"
				( attribute "CDS_PHYS_NET_NAME" "M_M_MA<10>"
					( Origin gPackager )
				)
				( attribute "PNN" "M_M_MA<10>"
					( Origin gPackager )
				)
				( objectStatus "M_M_MA<10>" )
			)
			( signal "@baseboard_fab2_lib.baseboard_fab2(sch_1):m_m_ma(11)"
				( attribute "CDS_PHYS_NET_NAME" "M_M_MA<11>"
					( Origin gPackager )
				)
				( attribute "PNN" "M_M_MA<11>"
					( Origin gPackager )
				)
				( objectStatus "M_M_MA<11>" )
			)
			( signal "@baseboard_fab2_lib.baseboard_fab2(sch_1):m_m_ma(12)"
				( attribute "CDS_PHYS_NET_NAME" "M_M_MA<12>"
					( Origin gPackager )
				)
				( attribute "PNN" "M_M_MA<12>"
					( Origin gPackager )
				)
				( objectStatus "M_M_MA<12>" )
			)
			( signal "@baseboard_fab2_lib.baseboard_fab2(sch_1):m_m_ma(13)"
				( attribute "CDS_PHYS_NET_NAME" "M_M_MA<13>"
					( Origin gPackager )
				)
				( attribute "PNN" "M_M_MA<13>"
					( Origin gPackager )
				)
				( objectStatus "M_M_MA<13>" )
			)
			( signal "@baseboard_fab2_lib.baseboard_fab2(sch_1):m_m_ma(14)"
				( attribute "CDS_PHYS_NET_NAME" "M_M_MA<14>"
					( Origin gPackager )
				)
				( attribute "PNN" "M_M_MA<14>"
					( Origin gPackager )
				)
				( objectStatus "M_M_MA<14>" )
			)
			( signal "@baseboard_fab2_lib.baseboard_fab2(sch_1):m_m_ma(15)"
				( attribute "CDS_PHYS_NET_NAME" "M_M_MA<15>"
					( Origin gPackager )
				)
				( attribute "PNN" "M_M_MA<15>"
					( Origin gPackager )
				)
				( objectStatus "M_M_MA<15>" )
			)
			( signal "@baseboard_fab2_lib.baseboard_fab2(sch_1):m_m_ma(16)"
				( attribute "CDS_PHYS_NET_NAME" "M_M_MA<16>"
					( Origin gPackager )
				)
				( attribute "PNN" "M_M_MA<16>"
					( Origin gPackager )
				)
				( objectStatus "M_M_MA<16>" )
			)
			( signal "@baseboard_fab2_lib.baseboard_fab2(sch_1):m_m_ma(17)"
				( attribute "CDS_PHYS_NET_NAME" "M_M_MA<17>"
					( Origin gPackager )
				)
				( attribute "PNN" "M_M_MA<17>"
					( Origin gPackager )
				)
				( objectStatus "M_M_MA<17>" )
			)
			( signal "@baseboard_fab2_lib.baseboard_fab2(sch_1):m_m_odt(0)"
				( attribute "CDS_PHYS_NET_NAME" "M_M_ODT<0>"
					( Origin gPackager )
				)
				( attribute "PNN" "M_M_ODT<0>"
					( Origin gPackager )
				)
				( objectStatus "M_M_ODT<0>" )
			)
			( signal "@baseboard_fab2_lib.baseboard_fab2(sch_1):m_m_odt(1)"
				( attribute "CDS_PHYS_NET_NAME" "M_M_ODT<1>"
					( Origin gPackager )
				)
				( attribute "PNN" "M_M_ODT<1>"
					( Origin gPackager )
				)
				( objectStatus "M_M_ODT<1>" )
			)
			( signal "@baseboard_fab2_lib.baseboard_fab2(sch_1):m_m_odt(2)"
				( attribute "CDS_PHYS_NET_NAME" "M_M_ODT<2>"
					( Origin gPackager )
				)
				( attribute "PNN" "M_M_ODT<2>"
					( Origin gPackager )
				)
				( objectStatus "M_M_ODT<2>" )
			)
			( signal "@baseboard_fab2_lib.baseboard_fab2(sch_1):m_m_odt(3)"
				( attribute "CDS_PHYS_NET_NAME" "M_M_ODT<3>"
					( Origin gPackager )
				)
				( attribute "PNN" "M_M_ODT<3>"
					( Origin gPackager )
				)
				( objectStatus "M_M_ODT<3>" )
			)
			( signal "@baseboard_fab2_lib.baseboard_fab2(sch_1):m_m_par"
				( attribute "CDS_PHYS_NET_NAME" "M_M_PAR"
					( Origin gPackager )
				)
				( objectStatus "M_M_PAR" )
			)
			( signal "@baseboard_fab2_lib.baseboard_fab2(sch_1):clk_100m_cpu1_pe_refclk_dn"
				( attribute "CDS_PHYS_NET_NAME" "CLK_100M_CPU1_PE_REFCLK_DN"
					( Origin gPackager )
				)
				( objectStatus "CLK_100M_CPU1_PE_REFCLK_DN" )
			)
			( signal "@baseboard_fab2_lib.baseboard_fab2(sch_1):clk_100m_cpu1_pe_refclk_dp"
				( attribute "CDS_PHYS_NET_NAME" "CLK_100M_CPU1_PE_REFCLK_DP"
					( Origin gPackager )
				)
				( objectStatus "CLK_100M_CPU1_PE_REFCLK_DP" )
			)
			( signal "@baseboard_fab2_lib.baseboard_fab2(sch_1):clk_156m_osc_cpu1_hfi_dn"
				( attribute "CDS_PHYS_NET_NAME" "CLK_156M_OSC_CPU1_HFI_DN"
					( Origin gPackager )
				)
				( objectStatus "CLK_156M_OSC_CPU1_HFI_DN" )
			)
			( signal "@baseboard_fab2_lib.baseboard_fab2(sch_1):clk_156m_osc_cpu1_hfi_dp"
				( attribute "CDS_PHYS_NET_NAME" "CLK_156M_OSC_CPU1_HFI_DP"
					( Origin gPackager )
				)
				( objectStatus "CLK_156M_OSC_CPU1_HFI_DP" )
			)
			( signal "@baseboard_fab2_lib.baseboard_fab2(sch_1):jtag_mcp_cpu1_tdi"
				( attribute "CDS_PHYS_NET_NAME" "JTAG_MCP_CPU1_TDI"
					( Origin gPackager )
				)
				( objectStatus "JTAG_MCP_CPU1_TDI" )
			)
			( signal "@baseboard_fab2_lib.baseboard_fab2(sch_1):jtag_mcp_cpu1_tdo"
				( attribute "CDS_PHYS_NET_NAME" "JTAG_MCP_CPU1_TDO"
					( Origin gPackager )
				)
				( objectStatus "JTAG_MCP_CPU1_TDO" )
			)
			( signal "@baseboard_fab2_lib.baseboard_fab2(sch_1):rst_cd_cpu1_por_n"
				( attribute "CDS_PHYS_NET_NAME" "RST_CD_CPU1_POR_N"
					( Origin gPackager )
				)
				( objectStatus "RST_CD_CPU1_POR_N" )
			)
			( signal "@baseboard_fab2_lib.baseboard_fab2(sch_1):tp_cd_hfi1_cpu1_i2cdat"
				( attribute "CDS_PHYS_NET_NAME" "TP_CD_HFI1_CPU1_I2CDAT"
					( Origin gPackager )
				)
				( objectStatus "TP_CD_HFI1_CPU1_I2CDAT" )
			)
			( signal "@baseboard_fab2_lib.baseboard_fab2(sch_1):tp_cd_hfi1_cpu1_i2clk"
				( attribute "CDS_PHYS_NET_NAME" "TP_CD_HFI1_CPU1_I2CLK"
					( Origin gPackager )
				)
				( objectStatus "TP_CD_HFI1_CPU1_I2CLK" )
			)
			( signal "@baseboard_fab2_lib.baseboard_fab2(sch_1):tp_cd_hfi1_cpu1_int_n"
				( attribute "CDS_PHYS_NET_NAME" "TP_CD_HFI1_CPU1_INT_N"
					( Origin gPackager )
				)
				( objectStatus "TP_CD_HFI1_CPU1_INT_N" )
			)
			( signal "@baseboard_fab2_lib.baseboard_fab2(sch_1):tp_cd_hfi1_cpu1_led_n"
				( attribute "CDS_PHYS_NET_NAME" "TP_CD_HFI1_CPU1_LED_N"
					( Origin gPackager )
				)
				( objectStatus "TP_CD_HFI1_CPU1_LED_N" )
			)
			( signal "@baseboard_fab2_lib.baseboard_fab2(sch_1):tp_cd_hfi1_cpu1_modprst_n"
				( attribute "CDS_PHYS_NET_NAME" "TP_CD_HFI1_CPU1_MODPRST_N"
					( Origin gPackager )
				)
				( objectStatus "TP_CD_HFI1_CPU1_MODPRST_N" )
			)
			( signal "@baseboard_fab2_lib.baseboard_fab2(sch_1):tp_cd_hfi1_cpu1_reset_n"
				( attribute "CDS_PHYS_NET_NAME" "TP_CD_HFI1_CPU1_RESET_N"
					( Origin gPackager )
				)
				( objectStatus "TP_CD_HFI1_CPU1_RESET_N" )
			)
			( signal "@baseboard_fab2_lib.baseboard_fab2(sch_1):tp_cpu1_dmi_rx_dn0"
				( attribute "CDS_PHYS_NET_NAME" "TP_CPU1_DMI_RX_DN0"
					( Origin gPackager )
				)
				( objectStatus "TP_CPU1_DMI_RX_DN0" )
			)
			( signal "@baseboard_fab2_lib.baseboard_fab2(sch_1):tp_cpu1_dmi_rx_dn1"
				( attribute "CDS_PHYS_NET_NAME" "TP_CPU1_DMI_RX_DN1"
					( Origin gPackager )
				)
				( objectStatus "TP_CPU1_DMI_RX_DN1" )
			)
			( signal "@baseboard_fab2_lib.baseboard_fab2(sch_1):tp_cpu1_dmi_rx_dn2"
				( attribute "CDS_PHYS_NET_NAME" "TP_CPU1_DMI_RX_DN2"
					( Origin gPackager )
				)
				( objectStatus "TP_CPU1_DMI_RX_DN2" )
			)
			( signal "@baseboard_fab2_lib.baseboard_fab2(sch_1):tp_cpu1_dmi_rx_dn3"
				( attribute "CDS_PHYS_NET_NAME" "TP_CPU1_DMI_RX_DN3"
					( Origin gPackager )
				)
				( objectStatus "TP_CPU1_DMI_RX_DN3" )
			)
			( signal "@baseboard_fab2_lib.baseboard_fab2(sch_1):tp_cpu1_dmi_rx_dp0"
				( attribute "CDS_PHYS_NET_NAME" "TP_CPU1_DMI_RX_DP0"
					( Origin gPackager )
				)
				( objectStatus "TP_CPU1_DMI_RX_DP0" )
			)
			( signal "@baseboard_fab2_lib.baseboard_fab2(sch_1):tp_cpu1_dmi_rx_dp1"
				( attribute "CDS_PHYS_NET_NAME" "TP_CPU1_DMI_RX_DP1"
					( Origin gPackager )
				)
				( objectStatus "TP_CPU1_DMI_RX_DP1" )
			)
			( signal "@baseboard_fab2_lib.baseboard_fab2(sch_1):tp_cpu1_dmi_rx_dp2"
				( attribute "CDS_PHYS_NET_NAME" "TP_CPU1_DMI_RX_DP2"
					( Origin gPackager )
				)
				( objectStatus "TP_CPU1_DMI_RX_DP2" )
			)
			( signal "@baseboard_fab2_lib.baseboard_fab2(sch_1):tp_cpu1_dmi_rx_dp3"
				( attribute "CDS_PHYS_NET_NAME" "TP_CPU1_DMI_RX_DP3"
					( Origin gPackager )
				)
				( objectStatus "TP_CPU1_DMI_RX_DP3" )
			)
			( signal "@baseboard_fab2_lib.baseboard_fab2(sch_1):tp_cpu1_dmi_tx_dn0"
				( attribute "CDS_PHYS_NET_NAME" "TP_CPU1_DMI_TX_DN0"
					( Origin gPackager )
				)
				( objectStatus "TP_CPU1_DMI_TX_DN0" )
			)
			( signal "@baseboard_fab2_lib.baseboard_fab2(sch_1):tp_cpu1_dmi_tx_dn1"
				( attribute "CDS_PHYS_NET_NAME" "TP_CPU1_DMI_TX_DN1"
					( Origin gPackager )
				)
				( objectStatus "TP_CPU1_DMI_TX_DN1" )
			)
			( signal "@baseboard_fab2_lib.baseboard_fab2(sch_1):tp_cpu1_dmi_tx_dn2"
				( attribute "CDS_PHYS_NET_NAME" "TP_CPU1_DMI_TX_DN2"
					( Origin gPackager )
				)
				( objectStatus "TP_CPU1_DMI_TX_DN2" )
			)
			( signal "@baseboard_fab2_lib.baseboard_fab2(sch_1):tp_cpu1_dmi_tx_dn3"
				( attribute "CDS_PHYS_NET_NAME" "TP_CPU1_DMI_TX_DN3"
					( Origin gPackager )
				)
				( objectStatus "TP_CPU1_DMI_TX_DN3" )
			)
			( signal "@baseboard_fab2_lib.baseboard_fab2(sch_1):tp_cpu1_dmi_tx_dp0"
				( attribute "CDS_PHYS_NET_NAME" "TP_CPU1_DMI_TX_DP0"
					( Origin gPackager )
				)
				( objectStatus "TP_CPU1_DMI_TX_DP0" )
			)
			( signal "@baseboard_fab2_lib.baseboard_fab2(sch_1):tp_cpu1_dmi_tx_dp1"
				( attribute "CDS_PHYS_NET_NAME" "TP_CPU1_DMI_TX_DP1"
					( Origin gPackager )
				)
				( objectStatus "TP_CPU1_DMI_TX_DP1" )
			)
			( signal "@baseboard_fab2_lib.baseboard_fab2(sch_1):tp_cpu1_dmi_tx_dp2"
				( attribute "CDS_PHYS_NET_NAME" "TP_CPU1_DMI_TX_DP2"
					( Origin gPackager )
				)
				( objectStatus "TP_CPU1_DMI_TX_DP2" )
			)
			( signal "@baseboard_fab2_lib.baseboard_fab2(sch_1):tp_cpu1_dmi_tx_dp3"
				( attribute "CDS_PHYS_NET_NAME" "TP_CPU1_DMI_TX_DP3"
					( Origin gPackager )
				)
				( objectStatus "TP_CPU1_DMI_TX_DP3" )
			)
			( signal "@baseboard_fab2_lib.baseboard_fab2(sch_1):tp_cpu1_rsvd_172"
				( attribute "CDS_PHYS_NET_NAME" "TP_CPU1_RSVD_172"
					( Origin gPackager )
				)
				( objectStatus "TP_CPU1_RSVD_172" )
			)
			( signal "@baseboard_fab2_lib.baseboard_fab2(sch_1):tp_cpu1_rsvd_173"
				( attribute "CDS_PHYS_NET_NAME" "TP_CPU1_RSVD_173"
					( Origin gPackager )
				)
				( objectStatus "TP_CPU1_RSVD_173" )
			)
			( signal "@baseboard_fab2_lib.baseboard_fab2(sch_1):tp_cpu1_rsvd_174"
				( attribute "CDS_PHYS_NET_NAME" "TP_CPU1_RSVD_174"
					( Origin gPackager )
				)
				( objectStatus "TP_CPU1_RSVD_174" )
			)
			( signal "@baseboard_fab2_lib.baseboard_fab2(sch_1):tp_cpu1_rsvd_175"
				( attribute "CDS_PHYS_NET_NAME" "TP_CPU1_RSVD_175"
					( Origin gPackager )
				)
				( objectStatus "TP_CPU1_RSVD_175" )
			)
			( signal "@baseboard_fab2_lib.baseboard_fab2(sch_1):tp_cpu1_rsvd_176"
				( attribute "CDS_PHYS_NET_NAME" "TP_CPU1_RSVD_176"
					( Origin gPackager )
				)
				( objectStatus "TP_CPU1_RSVD_176" )
			)
			( signal "@baseboard_fab2_lib.baseboard_fab2(sch_1):tp_cpu1_rsvd_177"
				( attribute "CDS_PHYS_NET_NAME" "TP_CPU1_RSVD_177"
					( Origin gPackager )
				)
				( objectStatus "TP_CPU1_RSVD_177" )
			)
			( signal "@baseboard_fab2_lib.baseboard_fab2(sch_1):tp_cpu1_rsvd_178"
				( attribute "CDS_PHYS_NET_NAME" "TP_CPU1_RSVD_178"
					( Origin gPackager )
				)
				( objectStatus "TP_CPU1_RSVD_178" )
			)
			( signal "@baseboard_fab2_lib.baseboard_fab2(sch_1):tp_cpu1_rsvd_179"
				( attribute "CDS_PHYS_NET_NAME" "TP_CPU1_RSVD_179"
					( Origin gPackager )
				)
				( objectStatus "TP_CPU1_RSVD_179" )
			)
			( signal "@baseboard_fab2_lib.baseboard_fab2(sch_1):tp_cpu1_rsvd_180"
				( attribute "CDS_PHYS_NET_NAME" "TP_CPU1_RSVD_180"
					( Origin gPackager )
				)
				( objectStatus "TP_CPU1_RSVD_180" )
			)
			( signal "@baseboard_fab2_lib.baseboard_fab2(sch_1):tp_cpu1_rsvd_181"
				( attribute "CDS_PHYS_NET_NAME" "TP_CPU1_RSVD_181"
					( Origin gPackager )
				)
				( objectStatus "TP_CPU1_RSVD_181" )
			)
			( signal "@baseboard_fab2_lib.baseboard_fab2(sch_1):tp_cpu1_rsvd_182"
				( attribute "CDS_PHYS_NET_NAME" "TP_CPU1_RSVD_182"
					( Origin gPackager )
				)
				( objectStatus "TP_CPU1_RSVD_182" )
			)
			( signal "@baseboard_fab2_lib.baseboard_fab2(sch_1):tp_cpu1_rsvd_183"
				( attribute "CDS_PHYS_NET_NAME" "TP_CPU1_RSVD_183"
					( Origin gPackager )
				)
				( objectStatus "TP_CPU1_RSVD_183" )
			)
			( signal "@baseboard_fab2_lib.baseboard_fab2(sch_1):tp_cpu1_rsvd_184"
				( attribute "CDS_PHYS_NET_NAME" "TP_CPU1_RSVD_184"
					( Origin gPackager )
				)
				( objectStatus "TP_CPU1_RSVD_184" )
			)
			( signal "@baseboard_fab2_lib.baseboard_fab2(sch_1):tp_cpu1_rsvd_186"
				( attribute "CDS_PHYS_NET_NAME" "TP_CPU1_RSVD_186"
					( Origin gPackager )
				)
				( objectStatus "TP_CPU1_RSVD_186" )
			)
			( signal "@baseboard_fab2_lib.baseboard_fab2(sch_1):tp_cpu1_rsvd_189"
				( attribute "CDS_PHYS_NET_NAME" "TP_CPU1_RSVD_189"
					( Origin gPackager )
				)
				( objectStatus "TP_CPU1_RSVD_189" )
			)
			( signal "@baseboard_fab2_lib.baseboard_fab2(sch_1):tp_cpu1_rsvd_190"
				( attribute "CDS_PHYS_NET_NAME" "TP_CPU1_RSVD_190"
					( Origin gPackager )
				)
				( objectStatus "TP_CPU1_RSVD_190" )
			)
			( signal "@baseboard_fab2_lib.baseboard_fab2(sch_1):tp_fm_cpu1_cd_hfi0_modprst_n"
				( attribute "CDS_PHYS_NET_NAME" "TP_FM_CPU1_CD_HFI0_MODPRST_N"
					( Origin gPackager )
				)
				( objectStatus "TP_FM_CPU1_CD_HFI0_MODPRST_N" )
			)
			( signal "@baseboard_fab2_lib.baseboard_fab2(sch_1):tp_irq_cpu1_cd_hfi0_n"
				( attribute "CDS_PHYS_NET_NAME" "TP_IRQ_CPU1_CD_HFI0_N"
					( Origin gPackager )
				)
				( objectStatus "TP_IRQ_CPU1_CD_HFI0_N" )
			)
			( signal "@baseboard_fab2_lib.baseboard_fab2(sch_1):tp_led_cpu1_cd_hfi0_n"
				( attribute "CDS_PHYS_NET_NAME" "TP_LED_CPU1_CD_HFI0_N"
					( Origin gPackager )
				)
				( objectStatus "TP_LED_CPU1_CD_HFI0_N" )
			)
			( signal "@baseboard_fab2_lib.baseboard_fab2(sch_1):tp_rst_cpu1_cd_hfi0_n"
				( attribute "CDS_PHYS_NET_NAME" "TP_RST_CPU1_CD_HFI0_N"
					( Origin gPackager )
				)
				( objectStatus "TP_RST_CPU1_CD_HFI0_N" )
			)
			( signal "@baseboard_fab2_lib.baseboard_fab2(sch_1):tp_smb_cpu1_cd_hfi0_i2cclk"
				( attribute "CDS_PHYS_NET_NAME" "TP_SMB_CPU1_CD_HFI0_I2CCLK"
					( Origin gPackager )
				)
				( objectStatus "TP_SMB_CPU1_CD_HFI0_I2CCLK" )
			)
			( signal "@baseboard_fab2_lib.baseboard_fab2(sch_1):tp_smb_cpu1_cd_hfi0_i2cdat"
				( attribute "CDS_PHYS_NET_NAME" "TP_SMB_CPU1_CD_HFI0_I2CDAT"
					( Origin gPackager )
				)
				( objectStatus "TP_SMB_CPU1_CD_HFI0_I2CDAT" )
			)
			( signal "@baseboard_fab2_lib.baseboard_fab2(sch_1):tp_p3e_cpu1_pe1_mp_rxn(0)"
				( attribute "CDS_PHYS_NET_NAME" "TP_P3E_CPU1_PE1_MP_RXN<0>"
					( Origin gPackager )
				)
				( attribute "PNN" "TP_P3E_CPU1_PE1_MP_RXN<0>"
					( Origin gPackager )
				)
				( objectStatus "TP_P3E_CPU1_PE1_MP_RXN<0>" )
			)
			( signal "@baseboard_fab2_lib.baseboard_fab2(sch_1):tp_p3e_cpu1_pe1_mp_rxn(1)"
				( attribute "CDS_PHYS_NET_NAME" "TP_P3E_CPU1_PE1_MP_RXN<1>"
					( Origin gPackager )
				)
				( attribute "PNN" "TP_P3E_CPU1_PE1_MP_RXN<1>"
					( Origin gPackager )
				)
				( objectStatus "TP_P3E_CPU1_PE1_MP_RXN<1>" )
			)
			( signal "@baseboard_fab2_lib.baseboard_fab2(sch_1):tp_p3e_cpu1_pe1_mp_rxn(2)"
				( attribute "CDS_PHYS_NET_NAME" "TP_P3E_CPU1_PE1_MP_RXN<2>"
					( Origin gPackager )
				)
				( attribute "PNN" "TP_P3E_CPU1_PE1_MP_RXN<2>"
					( Origin gPackager )
				)
				( objectStatus "TP_P3E_CPU1_PE1_MP_RXN<2>" )
			)
			( signal "@baseboard_fab2_lib.baseboard_fab2(sch_1):tp_p3e_cpu1_pe1_mp_rxn(3)"
				( attribute "CDS_PHYS_NET_NAME" "TP_P3E_CPU1_PE1_MP_RXN<3>"
					( Origin gPackager )
				)
				( attribute "PNN" "TP_P3E_CPU1_PE1_MP_RXN<3>"
					( Origin gPackager )
				)
				( objectStatus "TP_P3E_CPU1_PE1_MP_RXN<3>" )
			)
			( signal "@baseboard_fab2_lib.baseboard_fab2(sch_1):tp_p3e_cpu1_pe1_mp_rxn(4)"
				( attribute "CDS_PHYS_NET_NAME" "TP_P3E_CPU1_PE1_MP_RXN<4>"
					( Origin gPackager )
				)
				( attribute "PNN" "TP_P3E_CPU1_PE1_MP_RXN<4>"
					( Origin gPackager )
				)
				( objectStatus "TP_P3E_CPU1_PE1_MP_RXN<4>" )
			)
			( signal "@baseboard_fab2_lib.baseboard_fab2(sch_1):tp_p3e_cpu1_pe1_mp_rxn(5)"
				( attribute "CDS_PHYS_NET_NAME" "TP_P3E_CPU1_PE1_MP_RXN<5>"
					( Origin gPackager )
				)
				( attribute "PNN" "TP_P3E_CPU1_PE1_MP_RXN<5>"
					( Origin gPackager )
				)
				( objectStatus "TP_P3E_CPU1_PE1_MP_RXN<5>" )
			)
			( signal "@baseboard_fab2_lib.baseboard_fab2(sch_1):tp_p3e_cpu1_pe1_mp_rxn(6)"
				( attribute "CDS_PHYS_NET_NAME" "TP_P3E_CPU1_PE1_MP_RXN<6>"
					( Origin gPackager )
				)
				( attribute "PNN" "TP_P3E_CPU1_PE1_MP_RXN<6>"
					( Origin gPackager )
				)
				( objectStatus "TP_P3E_CPU1_PE1_MP_RXN<6>" )
			)
			( signal "@baseboard_fab2_lib.baseboard_fab2(sch_1):tp_p3e_cpu1_pe1_mp_rxn(7)"
				( attribute "CDS_PHYS_NET_NAME" "TP_P3E_CPU1_PE1_MP_RXN<7>"
					( Origin gPackager )
				)
				( attribute "PNN" "TP_P3E_CPU1_PE1_MP_RXN<7>"
					( Origin gPackager )
				)
				( objectStatus "TP_P3E_CPU1_PE1_MP_RXN<7>" )
			)
			( signal "@baseboard_fab2_lib.baseboard_fab2(sch_1):tp_p3e_cpu1_pe1_mp_rxp(0)"
				( attribute "CDS_PHYS_NET_NAME" "TP_P3E_CPU1_PE1_MP_RXP<0>"
					( Origin gPackager )
				)
				( attribute "PNN" "TP_P3E_CPU1_PE1_MP_RXP<0>"
					( Origin gPackager )
				)
				( objectStatus "TP_P3E_CPU1_PE1_MP_RXP<0>" )
			)
			( signal "@baseboard_fab2_lib.baseboard_fab2(sch_1):tp_p3e_cpu1_pe1_mp_rxp(1)"
				( attribute "CDS_PHYS_NET_NAME" "TP_P3E_CPU1_PE1_MP_RXP<1>"
					( Origin gPackager )
				)
				( attribute "PNN" "TP_P3E_CPU1_PE1_MP_RXP<1>"
					( Origin gPackager )
				)
				( objectStatus "TP_P3E_CPU1_PE1_MP_RXP<1>" )
			)
			( signal "@baseboard_fab2_lib.baseboard_fab2(sch_1):tp_p3e_cpu1_pe1_mp_rxp(2)"
				( attribute "CDS_PHYS_NET_NAME" "TP_P3E_CPU1_PE1_MP_RXP<2>"
					( Origin gPackager )
				)
				( attribute "PNN" "TP_P3E_CPU1_PE1_MP_RXP<2>"
					( Origin gPackager )
				)
				( objectStatus "TP_P3E_CPU1_PE1_MP_RXP<2>" )
			)
			( signal "@baseboard_fab2_lib.baseboard_fab2(sch_1):tp_p3e_cpu1_pe1_mp_rxp(3)"
				( attribute "CDS_PHYS_NET_NAME" "TP_P3E_CPU1_PE1_MP_RXP<3>"
					( Origin gPackager )
				)
				( attribute "PNN" "TP_P3E_CPU1_PE1_MP_RXP<3>"
					( Origin gPackager )
				)
				( objectStatus "TP_P3E_CPU1_PE1_MP_RXP<3>" )
			)
			( signal "@baseboard_fab2_lib.baseboard_fab2(sch_1):tp_p3e_cpu1_pe1_mp_rxp(4)"
				( attribute "CDS_PHYS_NET_NAME" "TP_P3E_CPU1_PE1_MP_RXP<4>"
					( Origin gPackager )
				)
				( attribute "PNN" "TP_P3E_CPU1_PE1_MP_RXP<4>"
					( Origin gPackager )
				)
				( objectStatus "TP_P3E_CPU1_PE1_MP_RXP<4>" )
			)
			( signal "@baseboard_fab2_lib.baseboard_fab2(sch_1):tp_p3e_cpu1_pe1_mp_rxp(5)"
				( attribute "CDS_PHYS_NET_NAME" "TP_P3E_CPU1_PE1_MP_RXP<5>"
					( Origin gPackager )
				)
				( attribute "PNN" "TP_P3E_CPU1_PE1_MP_RXP<5>"
					( Origin gPackager )
				)
				( objectStatus "TP_P3E_CPU1_PE1_MP_RXP<5>" )
			)
			( signal "@baseboard_fab2_lib.baseboard_fab2(sch_1):tp_p3e_cpu1_pe1_mp_rxp(6)"
				( attribute "CDS_PHYS_NET_NAME" "TP_P3E_CPU1_PE1_MP_RXP<6>"
					( Origin gPackager )
				)
				( attribute "PNN" "TP_P3E_CPU1_PE1_MP_RXP<6>"
					( Origin gPackager )
				)
				( objectStatus "TP_P3E_CPU1_PE1_MP_RXP<6>" )
			)
			( signal "@baseboard_fab2_lib.baseboard_fab2(sch_1):tp_p3e_cpu1_pe1_mp_rxp(7)"
				( attribute "CDS_PHYS_NET_NAME" "TP_P3E_CPU1_PE1_MP_RXP<7>"
					( Origin gPackager )
				)
				( attribute "PNN" "TP_P3E_CPU1_PE1_MP_RXP<7>"
					( Origin gPackager )
				)
				( objectStatus "TP_P3E_CPU1_PE1_MP_RXP<7>" )
			)
			( signal "@baseboard_fab2_lib.baseboard_fab2(sch_1):tp_p3e_cpu1_pe1_mp_txn(0)"
				( attribute "CDS_PHYS_NET_NAME" "TP_P3E_CPU1_PE1_MP_TXN<0>"
					( Origin gPackager )
				)
				( attribute "PNN" "TP_P3E_CPU1_PE1_MP_TXN<0>"
					( Origin gPackager )
				)
				( objectStatus "TP_P3E_CPU1_PE1_MP_TXN<0>" )
			)
			( signal "@baseboard_fab2_lib.baseboard_fab2(sch_1):tp_p3e_cpu1_pe1_mp_txn(1)"
				( attribute "CDS_PHYS_NET_NAME" "TP_P3E_CPU1_PE1_MP_TXN<1>"
					( Origin gPackager )
				)
				( attribute "PNN" "TP_P3E_CPU1_PE1_MP_TXN<1>"
					( Origin gPackager )
				)
				( objectStatus "TP_P3E_CPU1_PE1_MP_TXN<1>" )
			)
			( signal "@baseboard_fab2_lib.baseboard_fab2(sch_1):tp_p3e_cpu1_pe1_mp_txn(2)"
				( attribute "CDS_PHYS_NET_NAME" "TP_P3E_CPU1_PE1_MP_TXN<2>"
					( Origin gPackager )
				)
				( attribute "PNN" "TP_P3E_CPU1_PE1_MP_TXN<2>"
					( Origin gPackager )
				)
				( objectStatus "TP_P3E_CPU1_PE1_MP_TXN<2>" )
			)
			( signal "@baseboard_fab2_lib.baseboard_fab2(sch_1):tp_p3e_cpu1_pe1_mp_txn(3)"
				( attribute "CDS_PHYS_NET_NAME" "TP_P3E_CPU1_PE1_MP_TXN<3>"
					( Origin gPackager )
				)
				( attribute "PNN" "TP_P3E_CPU1_PE1_MP_TXN<3>"
					( Origin gPackager )
				)
				( objectStatus "TP_P3E_CPU1_PE1_MP_TXN<3>" )
			)
			( signal "@baseboard_fab2_lib.baseboard_fab2(sch_1):tp_p3e_cpu1_pe1_mp_txn(4)"
				( attribute "CDS_PHYS_NET_NAME" "TP_P3E_CPU1_PE1_MP_TXN<4>"
					( Origin gPackager )
				)
				( attribute "PNN" "TP_P3E_CPU1_PE1_MP_TXN<4>"
					( Origin gPackager )
				)
				( objectStatus "TP_P3E_CPU1_PE1_MP_TXN<4>" )
			)
			( signal "@baseboard_fab2_lib.baseboard_fab2(sch_1):tp_p3e_cpu1_pe1_mp_txn(5)"
				( attribute "CDS_PHYS_NET_NAME" "TP_P3E_CPU1_PE1_MP_TXN<5>"
					( Origin gPackager )
				)
				( attribute "PNN" "TP_P3E_CPU1_PE1_MP_TXN<5>"
					( Origin gPackager )
				)
				( objectStatus "TP_P3E_CPU1_PE1_MP_TXN<5>" )
			)
			( signal "@baseboard_fab2_lib.baseboard_fab2(sch_1):tp_p3e_cpu1_pe1_mp_txn(6)"
				( attribute "CDS_PHYS_NET_NAME" "TP_P3E_CPU1_PE1_MP_TXN<6>"
					( Origin gPackager )
				)
				( attribute "PNN" "TP_P3E_CPU1_PE1_MP_TXN<6>"
					( Origin gPackager )
				)
				( objectStatus "TP_P3E_CPU1_PE1_MP_TXN<6>" )
			)
			( signal "@baseboard_fab2_lib.baseboard_fab2(sch_1):tp_p3e_cpu1_pe1_mp_txn(7)"
				( attribute "CDS_PHYS_NET_NAME" "TP_P3E_CPU1_PE1_MP_TXN<7>"
					( Origin gPackager )
				)
				( attribute "PNN" "TP_P3E_CPU1_PE1_MP_TXN<7>"
					( Origin gPackager )
				)
				( objectStatus "TP_P3E_CPU1_PE1_MP_TXN<7>" )
			)
			( signal "@baseboard_fab2_lib.baseboard_fab2(sch_1):tp_p3e_cpu1_pe1_mp_txp(0)"
				( attribute "CDS_PHYS_NET_NAME" "TP_P3E_CPU1_PE1_MP_TXP<0>"
					( Origin gPackager )
				)
				( attribute "PNN" "TP_P3E_CPU1_PE1_MP_TXP<0>"
					( Origin gPackager )
				)
				( objectStatus "TP_P3E_CPU1_PE1_MP_TXP<0>" )
			)
			( signal "@baseboard_fab2_lib.baseboard_fab2(sch_1):tp_p3e_cpu1_pe1_mp_txp(1)"
				( attribute "CDS_PHYS_NET_NAME" "TP_P3E_CPU1_PE1_MP_TXP<1>"
					( Origin gPackager )
				)
				( attribute "PNN" "TP_P3E_CPU1_PE1_MP_TXP<1>"
					( Origin gPackager )
				)
				( objectStatus "TP_P3E_CPU1_PE1_MP_TXP<1>" )
			)
			( signal "@baseboard_fab2_lib.baseboard_fab2(sch_1):tp_p3e_cpu1_pe1_mp_txp(2)"
				( attribute "CDS_PHYS_NET_NAME" "TP_P3E_CPU1_PE1_MP_TXP<2>"
					( Origin gPackager )
				)
				( attribute "PNN" "TP_P3E_CPU1_PE1_MP_TXP<2>"
					( Origin gPackager )
				)
				( objectStatus "TP_P3E_CPU1_PE1_MP_TXP<2>" )
			)
			( signal "@baseboard_fab2_lib.baseboard_fab2(sch_1):tp_p3e_cpu1_pe1_mp_txp(3)"
				( attribute "CDS_PHYS_NET_NAME" "TP_P3E_CPU1_PE1_MP_TXP<3>"
					( Origin gPackager )
				)
				( attribute "PNN" "TP_P3E_CPU1_PE1_MP_TXP<3>"
					( Origin gPackager )
				)
				( objectStatus "TP_P3E_CPU1_PE1_MP_TXP<3>" )
			)
			( signal "@baseboard_fab2_lib.baseboard_fab2(sch_1):tp_p3e_cpu1_pe1_mp_txp(4)"
				( attribute "CDS_PHYS_NET_NAME" "TP_P3E_CPU1_PE1_MP_TXP<4>"
					( Origin gPackager )
				)
				( attribute "PNN" "TP_P3E_CPU1_PE1_MP_TXP<4>"
					( Origin gPackager )
				)
				( objectStatus "TP_P3E_CPU1_PE1_MP_TXP<4>" )
			)
			( signal "@baseboard_fab2_lib.baseboard_fab2(sch_1):tp_p3e_cpu1_pe1_mp_txp(5)"
				( attribute "CDS_PHYS_NET_NAME" "TP_P3E_CPU1_PE1_MP_TXP<5>"
					( Origin gPackager )
				)
				( attribute "PNN" "TP_P3E_CPU1_PE1_MP_TXP<5>"
					( Origin gPackager )
				)
				( objectStatus "TP_P3E_CPU1_PE1_MP_TXP<5>" )
			)
			( signal "@baseboard_fab2_lib.baseboard_fab2(sch_1):tp_p3e_cpu1_pe1_mp_txp(6)"
				( attribute "CDS_PHYS_NET_NAME" "TP_P3E_CPU1_PE1_MP_TXP<6>"
					( Origin gPackager )
				)
				( attribute "PNN" "TP_P3E_CPU1_PE1_MP_TXP<6>"
					( Origin gPackager )
				)
				( objectStatus "TP_P3E_CPU1_PE1_MP_TXP<6>" )
			)
			( signal "@baseboard_fab2_lib.baseboard_fab2(sch_1):tp_p3e_cpu1_pe1_mp_txp(7)"
				( attribute "CDS_PHYS_NET_NAME" "TP_P3E_CPU1_PE1_MP_TXP<7>"
					( Origin gPackager )
				)
				( attribute "PNN" "TP_P3E_CPU1_PE1_MP_TXP<7>"
					( Origin gPackager )
				)
				( objectStatus "TP_P3E_CPU1_PE1_MP_TXP<7>" )
			)
			( signal "@baseboard_fab2_lib.baseboard_fab2(sch_1):tp_p3e_cpu1_pe1_rsr3_rxn(8)"
				( attribute "CDS_PHYS_NET_NAME" "TP_P3E_CPU1_PE1_RSR3_RXN<8>"
					( Origin gPackager )
				)
				( attribute "PNN" "TP_P3E_CPU1_PE1_RSR3_RXN<8>"
					( Origin gPackager )
				)
				( objectStatus "TP_P3E_CPU1_PE1_RSR3_RXN<8>" )
			)
			( signal "@baseboard_fab2_lib.baseboard_fab2(sch_1):tp_p3e_cpu1_pe1_rsr3_rxn(9)"
				( attribute "CDS_PHYS_NET_NAME" "TP_P3E_CPU1_PE1_RSR3_RXN<9>"
					( Origin gPackager )
				)
				( attribute "PNN" "TP_P3E_CPU1_PE1_RSR3_RXN<9>"
					( Origin gPackager )
				)
				( objectStatus "TP_P3E_CPU1_PE1_RSR3_RXN<9>" )
			)
			( signal "@baseboard_fab2_lib.baseboard_fab2(sch_1):tp_p3e_cpu1_pe1_rsr3_rxn(10)"
				( attribute "CDS_PHYS_NET_NAME" "TP_P3E_CPU1_PE1_RSR3_RXN<10>"
					( Origin gPackager )
				)
				( attribute "PNN" "TP_P3E_CPU1_PE1_RSR3_RXN<10>"
					( Origin gPackager )
				)
				( objectStatus "TP_P3E_CPU1_PE1_RSR3_RXN<10>" )
			)
			( signal "@baseboard_fab2_lib.baseboard_fab2(sch_1):tp_p3e_cpu1_pe1_rsr3_rxn(11)"
				( attribute "CDS_PHYS_NET_NAME" "TP_P3E_CPU1_PE1_RSR3_RXN<11>"
					( Origin gPackager )
				)
				( attribute "PNN" "TP_P3E_CPU1_PE1_RSR3_RXN<11>"
					( Origin gPackager )
				)
				( objectStatus "TP_P3E_CPU1_PE1_RSR3_RXN<11>" )
			)
			( signal "@baseboard_fab2_lib.baseboard_fab2(sch_1):tp_p3e_cpu1_pe1_rsr3_rxn(12)"
				( attribute "CDS_PHYS_NET_NAME" "TP_P3E_CPU1_PE1_RSR3_RXN<12>"
					( Origin gPackager )
				)
				( attribute "PNN" "TP_P3E_CPU1_PE1_RSR3_RXN<12>"
					( Origin gPackager )
				)
				( objectStatus "TP_P3E_CPU1_PE1_RSR3_RXN<12>" )
			)
			( signal "@baseboard_fab2_lib.baseboard_fab2(sch_1):tp_p3e_cpu1_pe1_rsr3_rxn(13)"
				( attribute "CDS_PHYS_NET_NAME" "TP_P3E_CPU1_PE1_RSR3_RXN<13>"
					( Origin gPackager )
				)
				( attribute "PNN" "TP_P3E_CPU1_PE1_RSR3_RXN<13>"
					( Origin gPackager )
				)
				( objectStatus "TP_P3E_CPU1_PE1_RSR3_RXN<13>" )
			)
			( signal "@baseboard_fab2_lib.baseboard_fab2(sch_1):tp_p3e_cpu1_pe1_rsr3_rxn(14)"
				( attribute "CDS_PHYS_NET_NAME" "TP_P3E_CPU1_PE1_RSR3_RXN<14>"
					( Origin gPackager )
				)
				( attribute "PNN" "TP_P3E_CPU1_PE1_RSR3_RXN<14>"
					( Origin gPackager )
				)
				( objectStatus "TP_P3E_CPU1_PE1_RSR3_RXN<14>" )
			)
			( signal "@baseboard_fab2_lib.baseboard_fab2(sch_1):tp_p3e_cpu1_pe1_rsr3_rxn(15)"
				( attribute "CDS_PHYS_NET_NAME" "TP_P3E_CPU1_PE1_RSR3_RXN<15>"
					( Origin gPackager )
				)
				( attribute "PNN" "TP_P3E_CPU1_PE1_RSR3_RXN<15>"
					( Origin gPackager )
				)
				( objectStatus "TP_P3E_CPU1_PE1_RSR3_RXN<15>" )
			)
			( signal "@baseboard_fab2_lib.baseboard_fab2(sch_1):tp_p3e_cpu1_pe1_rsr3_rxp(8)"
				( attribute "CDS_PHYS_NET_NAME" "TP_P3E_CPU1_PE1_RSR3_RXP<8>"
					( Origin gPackager )
				)
				( attribute "PNN" "TP_P3E_CPU1_PE1_RSR3_RXP<8>"
					( Origin gPackager )
				)
				( objectStatus "TP_P3E_CPU1_PE1_RSR3_RXP<8>" )
			)
			( signal "@baseboard_fab2_lib.baseboard_fab2(sch_1):tp_p3e_cpu1_pe1_rsr3_rxp(9)"
				( attribute "CDS_PHYS_NET_NAME" "TP_P3E_CPU1_PE1_RSR3_RXP<9>"
					( Origin gPackager )
				)
				( attribute "PNN" "TP_P3E_CPU1_PE1_RSR3_RXP<9>"
					( Origin gPackager )
				)
				( objectStatus "TP_P3E_CPU1_PE1_RSR3_RXP<9>" )
			)
			( signal "@baseboard_fab2_lib.baseboard_fab2(sch_1):tp_p3e_cpu1_pe1_rsr3_rxp(10)"
				( attribute "CDS_PHYS_NET_NAME" "TP_P3E_CPU1_PE1_RSR3_RXP<10>"
					( Origin gPackager )
				)
				( attribute "PNN" "TP_P3E_CPU1_PE1_RSR3_RXP<10>"
					( Origin gPackager )
				)
				( objectStatus "TP_P3E_CPU1_PE1_RSR3_RXP<10>" )
			)
			( signal "@baseboard_fab2_lib.baseboard_fab2(sch_1):tp_p3e_cpu1_pe1_rsr3_rxp(11)"
				( attribute "CDS_PHYS_NET_NAME" "TP_P3E_CPU1_PE1_RSR3_RXP<11>"
					( Origin gPackager )
				)
				( attribute "PNN" "TP_P3E_CPU1_PE1_RSR3_RXP<11>"
					( Origin gPackager )
				)
				( objectStatus "TP_P3E_CPU1_PE1_RSR3_RXP<11>" )
			)
			( signal "@baseboard_fab2_lib.baseboard_fab2(sch_1):tp_p3e_cpu1_pe1_rsr3_rxp(12)"
				( attribute "CDS_PHYS_NET_NAME" "TP_P3E_CPU1_PE1_RSR3_RXP<12>"
					( Origin gPackager )
				)
				( attribute "PNN" "TP_P3E_CPU1_PE1_RSR3_RXP<12>"
					( Origin gPackager )
				)
				( objectStatus "TP_P3E_CPU1_PE1_RSR3_RXP<12>" )
			)
			( signal "@baseboard_fab2_lib.baseboard_fab2(sch_1):tp_p3e_cpu1_pe1_rsr3_rxp(13)"
				( attribute "CDS_PHYS_NET_NAME" "TP_P3E_CPU1_PE1_RSR3_RXP<13>"
					( Origin gPackager )
				)
				( attribute "PNN" "TP_P3E_CPU1_PE1_RSR3_RXP<13>"
					( Origin gPackager )
				)
				( objectStatus "TP_P3E_CPU1_PE1_RSR3_RXP<13>" )
			)
			( signal "@baseboard_fab2_lib.baseboard_fab2(sch_1):tp_p3e_cpu1_pe1_rsr3_rxp(14)"
				( attribute "CDS_PHYS_NET_NAME" "TP_P3E_CPU1_PE1_RSR3_RXP<14>"
					( Origin gPackager )
				)
				( attribute "PNN" "TP_P3E_CPU1_PE1_RSR3_RXP<14>"
					( Origin gPackager )
				)
				( objectStatus "TP_P3E_CPU1_PE1_RSR3_RXP<14>" )
			)
			( signal "@baseboard_fab2_lib.baseboard_fab2(sch_1):tp_p3e_cpu1_pe1_rsr3_rxp(15)"
				( attribute "CDS_PHYS_NET_NAME" "TP_P3E_CPU1_PE1_RSR3_RXP<15>"
					( Origin gPackager )
				)
				( attribute "PNN" "TP_P3E_CPU1_PE1_RSR3_RXP<15>"
					( Origin gPackager )
				)
				( objectStatus "TP_P3E_CPU1_PE1_RSR3_RXP<15>" )
			)
			( signal "@baseboard_fab2_lib.baseboard_fab2(sch_1):tp_p3e_cpu1_pe1_rsr3_txn(8)"
				( attribute "CDS_PHYS_NET_NAME" "TP_P3E_CPU1_PE1_RSR3_TXN<8>"
					( Origin gPackager )
				)
				( attribute "PNN" "TP_P3E_CPU1_PE1_RSR3_TXN<8>"
					( Origin gPackager )
				)
				( objectStatus "TP_P3E_CPU1_PE1_RSR3_TXN<8>" )
			)
			( signal "@baseboard_fab2_lib.baseboard_fab2(sch_1):tp_p3e_cpu1_pe1_rsr3_txn(9)"
				( attribute "CDS_PHYS_NET_NAME" "TP_P3E_CPU1_PE1_RSR3_TXN<9>"
					( Origin gPackager )
				)
				( attribute "PNN" "TP_P3E_CPU1_PE1_RSR3_TXN<9>"
					( Origin gPackager )
				)
				( objectStatus "TP_P3E_CPU1_PE1_RSR3_TXN<9>" )
			)
			( signal "@baseboard_fab2_lib.baseboard_fab2(sch_1):tp_p3e_cpu1_pe1_rsr3_txn(10)"
				( attribute "CDS_PHYS_NET_NAME" "TP_P3E_CPU1_PE1_RSR3_TXN<10>"
					( Origin gPackager )
				)
				( attribute "PNN" "TP_P3E_CPU1_PE1_RSR3_TXN<10>"
					( Origin gPackager )
				)
				( objectStatus "TP_P3E_CPU1_PE1_RSR3_TXN<10>" )
			)
			( signal "@baseboard_fab2_lib.baseboard_fab2(sch_1):tp_p3e_cpu1_pe1_rsr3_txn(11)"
				( attribute "CDS_PHYS_NET_NAME" "TP_P3E_CPU1_PE1_RSR3_TXN<11>"
					( Origin gPackager )
				)
				( attribute "PNN" "TP_P3E_CPU1_PE1_RSR3_TXN<11>"
					( Origin gPackager )
				)
				( objectStatus "TP_P3E_CPU1_PE1_RSR3_TXN<11>" )
			)
			( signal "@baseboard_fab2_lib.baseboard_fab2(sch_1):tp_p3e_cpu1_pe1_rsr3_txn(12)"
				( attribute "CDS_PHYS_NET_NAME" "TP_P3E_CPU1_PE1_RSR3_TXN<12>"
					( Origin gPackager )
				)
				( attribute "PNN" "TP_P3E_CPU1_PE1_RSR3_TXN<12>"
					( Origin gPackager )
				)
				( objectStatus "TP_P3E_CPU1_PE1_RSR3_TXN<12>" )
			)
			( signal "@baseboard_fab2_lib.baseboard_fab2(sch_1):tp_p3e_cpu1_pe1_rsr3_txn(13)"
				( attribute "CDS_PHYS_NET_NAME" "TP_P3E_CPU1_PE1_RSR3_TXN<13>"
					( Origin gPackager )
				)
				( attribute "PNN" "TP_P3E_CPU1_PE1_RSR3_TXN<13>"
					( Origin gPackager )
				)
				( objectStatus "TP_P3E_CPU1_PE1_RSR3_TXN<13>" )
			)
			( signal "@baseboard_fab2_lib.baseboard_fab2(sch_1):tp_p3e_cpu1_pe1_rsr3_txn(14)"
				( attribute "CDS_PHYS_NET_NAME" "TP_P3E_CPU1_PE1_RSR3_TXN<14>"
					( Origin gPackager )
				)
				( attribute "PNN" "TP_P3E_CPU1_PE1_RSR3_TXN<14>"
					( Origin gPackager )
				)
				( objectStatus "TP_P3E_CPU1_PE1_RSR3_TXN<14>" )
			)
			( signal "@baseboard_fab2_lib.baseboard_fab2(sch_1):tp_p3e_cpu1_pe1_rsr3_txn(15)"
				( attribute "CDS_PHYS_NET_NAME" "TP_P3E_CPU1_PE1_RSR3_TXN<15>"
					( Origin gPackager )
				)
				( attribute "PNN" "TP_P3E_CPU1_PE1_RSR3_TXN<15>"
					( Origin gPackager )
				)
				( objectStatus "TP_P3E_CPU1_PE1_RSR3_TXN<15>" )
			)
			( signal "@baseboard_fab2_lib.baseboard_fab2(sch_1):tp_p3e_cpu1_pe1_rsr3_txp(8)"
				( attribute "CDS_PHYS_NET_NAME" "TP_P3E_CPU1_PE1_RSR3_TXP<8>"
					( Origin gPackager )
				)
				( attribute "PNN" "TP_P3E_CPU1_PE1_RSR3_TXP<8>"
					( Origin gPackager )
				)
				( objectStatus "TP_P3E_CPU1_PE1_RSR3_TXP<8>" )
			)
			( signal "@baseboard_fab2_lib.baseboard_fab2(sch_1):tp_p3e_cpu1_pe1_rsr3_txp(9)"
				( attribute "CDS_PHYS_NET_NAME" "TP_P3E_CPU1_PE1_RSR3_TXP<9>"
					( Origin gPackager )
				)
				( attribute "PNN" "TP_P3E_CPU1_PE1_RSR3_TXP<9>"
					( Origin gPackager )
				)
				( objectStatus "TP_P3E_CPU1_PE1_RSR3_TXP<9>" )
			)
			( signal "@baseboard_fab2_lib.baseboard_fab2(sch_1):tp_p3e_cpu1_pe1_rsr3_txp(10)"
				( attribute "CDS_PHYS_NET_NAME" "TP_P3E_CPU1_PE1_RSR3_TXP<10>"
					( Origin gPackager )
				)
				( attribute "PNN" "TP_P3E_CPU1_PE1_RSR3_TXP<10>"
					( Origin gPackager )
				)
				( objectStatus "TP_P3E_CPU1_PE1_RSR3_TXP<10>" )
			)
			( signal "@baseboard_fab2_lib.baseboard_fab2(sch_1):tp_p3e_cpu1_pe1_rsr3_txp(11)"
				( attribute "CDS_PHYS_NET_NAME" "TP_P3E_CPU1_PE1_RSR3_TXP<11>"
					( Origin gPackager )
				)
				( attribute "PNN" "TP_P3E_CPU1_PE1_RSR3_TXP<11>"
					( Origin gPackager )
				)
				( objectStatus "TP_P3E_CPU1_PE1_RSR3_TXP<11>" )
			)
			( signal "@baseboard_fab2_lib.baseboard_fab2(sch_1):tp_p3e_cpu1_pe1_rsr3_txp(12)"
				( attribute "CDS_PHYS_NET_NAME" "TP_P3E_CPU1_PE1_RSR3_TXP<12>"
					( Origin gPackager )
				)
				( attribute "PNN" "TP_P3E_CPU1_PE1_RSR3_TXP<12>"
					( Origin gPackager )
				)
				( objectStatus "TP_P3E_CPU1_PE1_RSR3_TXP<12>" )
			)
			( signal "@baseboard_fab2_lib.baseboard_fab2(sch_1):tp_p3e_cpu1_pe1_rsr3_txp(13)"
				( attribute "CDS_PHYS_NET_NAME" "TP_P3E_CPU1_PE1_RSR3_TXP<13>"
					( Origin gPackager )
				)
				( attribute "PNN" "TP_P3E_CPU1_PE1_RSR3_TXP<13>"
					( Origin gPackager )
				)
				( objectStatus "TP_P3E_CPU1_PE1_RSR3_TXP<13>" )
			)
			( signal "@baseboard_fab2_lib.baseboard_fab2(sch_1):tp_p3e_cpu1_pe1_rsr3_txp(14)"
				( attribute "CDS_PHYS_NET_NAME" "TP_P3E_CPU1_PE1_RSR3_TXP<14>"
					( Origin gPackager )
				)
				( attribute "PNN" "TP_P3E_CPU1_PE1_RSR3_TXP<14>"
					( Origin gPackager )
				)
				( objectStatus "TP_P3E_CPU1_PE1_RSR3_TXP<14>" )
			)
			( signal "@baseboard_fab2_lib.baseboard_fab2(sch_1):tp_p3e_cpu1_pe1_rsr3_txp(15)"
				( attribute "CDS_PHYS_NET_NAME" "TP_P3E_CPU1_PE1_RSR3_TXP<15>"
					( Origin gPackager )
				)
				( attribute "PNN" "TP_P3E_CPU1_PE1_RSR3_TXP<15>"
					( Origin gPackager )
				)
				( objectStatus "TP_P3E_CPU1_PE1_RSR3_TXP<15>" )
			)
			( signal "@baseboard_fab2_lib.baseboard_fab2(sch_1):tp_p3e_cpu1_pe2_rsr_rxn(0)"
				( attribute "CDS_PHYS_NET_NAME" "TP_P3E_CPU1_PE2_RSR_RXN<0>"
					( Origin gPackager )
				)
				( attribute "PNN" "TP_P3E_CPU1_PE2_RSR_RXN<0>"
					( Origin gPackager )
				)
				( objectStatus "TP_P3E_CPU1_PE2_RSR_RXN<0>" )
			)
			( signal "@baseboard_fab2_lib.baseboard_fab2(sch_1):tp_p3e_cpu1_pe2_rsr_rxn(1)"
				( attribute "CDS_PHYS_NET_NAME" "TP_P3E_CPU1_PE2_RSR_RXN<1>"
					( Origin gPackager )
				)
				( attribute "PNN" "TP_P3E_CPU1_PE2_RSR_RXN<1>"
					( Origin gPackager )
				)
				( objectStatus "TP_P3E_CPU1_PE2_RSR_RXN<1>" )
			)
			( signal "@baseboard_fab2_lib.baseboard_fab2(sch_1):tp_p3e_cpu1_pe2_rsr_rxn(2)"
				( attribute "CDS_PHYS_NET_NAME" "TP_P3E_CPU1_PE2_RSR_RXN<2>"
					( Origin gPackager )
				)
				( attribute "PNN" "TP_P3E_CPU1_PE2_RSR_RXN<2>"
					( Origin gPackager )
				)
				( objectStatus "TP_P3E_CPU1_PE2_RSR_RXN<2>" )
			)
			( signal "@baseboard_fab2_lib.baseboard_fab2(sch_1):tp_p3e_cpu1_pe2_rsr_rxn(3)"
				( attribute "CDS_PHYS_NET_NAME" "TP_P3E_CPU1_PE2_RSR_RXN<3>"
					( Origin gPackager )
				)
				( attribute "PNN" "TP_P3E_CPU1_PE2_RSR_RXN<3>"
					( Origin gPackager )
				)
				( objectStatus "TP_P3E_CPU1_PE2_RSR_RXN<3>" )
			)
			( signal "@baseboard_fab2_lib.baseboard_fab2(sch_1):tp_p3e_cpu1_pe2_rsr_rxn(4)"
				( attribute "CDS_PHYS_NET_NAME" "TP_P3E_CPU1_PE2_RSR_RXN<4>"
					( Origin gPackager )
				)
				( attribute "PNN" "TP_P3E_CPU1_PE2_RSR_RXN<4>"
					( Origin gPackager )
				)
				( objectStatus "TP_P3E_CPU1_PE2_RSR_RXN<4>" )
			)
			( signal "@baseboard_fab2_lib.baseboard_fab2(sch_1):tp_p3e_cpu1_pe2_rsr_rxn(5)"
				( attribute "CDS_PHYS_NET_NAME" "TP_P3E_CPU1_PE2_RSR_RXN<5>"
					( Origin gPackager )
				)
				( attribute "PNN" "TP_P3E_CPU1_PE2_RSR_RXN<5>"
					( Origin gPackager )
				)
				( objectStatus "TP_P3E_CPU1_PE2_RSR_RXN<5>" )
			)
			( signal "@baseboard_fab2_lib.baseboard_fab2(sch_1):tp_p3e_cpu1_pe2_rsr_rxn(6)"
				( attribute "CDS_PHYS_NET_NAME" "TP_P3E_CPU1_PE2_RSR_RXN<6>"
					( Origin gPackager )
				)
				( attribute "PNN" "TP_P3E_CPU1_PE2_RSR_RXN<6>"
					( Origin gPackager )
				)
				( objectStatus "TP_P3E_CPU1_PE2_RSR_RXN<6>" )
			)
			( signal "@baseboard_fab2_lib.baseboard_fab2(sch_1):tp_p3e_cpu1_pe2_rsr_rxn(7)"
				( attribute "CDS_PHYS_NET_NAME" "TP_P3E_CPU1_PE2_RSR_RXN<7>"
					( Origin gPackager )
				)
				( attribute "PNN" "TP_P3E_CPU1_PE2_RSR_RXN<7>"
					( Origin gPackager )
				)
				( objectStatus "TP_P3E_CPU1_PE2_RSR_RXN<7>" )
			)
			( signal "@baseboard_fab2_lib.baseboard_fab2(sch_1):tp_p3e_cpu1_pe2_rsr_rxn(8)"
				( attribute "CDS_PHYS_NET_NAME" "TP_P3E_CPU1_PE2_RSR_RXN<8>"
					( Origin gPackager )
				)
				( attribute "PNN" "TP_P3E_CPU1_PE2_RSR_RXN<8>"
					( Origin gPackager )
				)
				( objectStatus "TP_P3E_CPU1_PE2_RSR_RXN<8>" )
			)
			( signal "@baseboard_fab2_lib.baseboard_fab2(sch_1):tp_p3e_cpu1_pe2_rsr_rxn(9)"
				( attribute "CDS_PHYS_NET_NAME" "TP_P3E_CPU1_PE2_RSR_RXN<9>"
					( Origin gPackager )
				)
				( attribute "PNN" "TP_P3E_CPU1_PE2_RSR_RXN<9>"
					( Origin gPackager )
				)
				( objectStatus "TP_P3E_CPU1_PE2_RSR_RXN<9>" )
			)
			( signal "@baseboard_fab2_lib.baseboard_fab2(sch_1):tp_p3e_cpu1_pe2_rsr_rxn(10)"
				( attribute "CDS_PHYS_NET_NAME" "TP_P3E_CPU1_PE2_RSR_RXN<10>"
					( Origin gPackager )
				)
				( attribute "PNN" "TP_P3E_CPU1_PE2_RSR_RXN<10>"
					( Origin gPackager )
				)
				( objectStatus "TP_P3E_CPU1_PE2_RSR_RXN<10>" )
			)
			( signal "@baseboard_fab2_lib.baseboard_fab2(sch_1):tp_p3e_cpu1_pe2_rsr_rxn(11)"
				( attribute "CDS_PHYS_NET_NAME" "TP_P3E_CPU1_PE2_RSR_RXN<11>"
					( Origin gPackager )
				)
				( attribute "PNN" "TP_P3E_CPU1_PE2_RSR_RXN<11>"
					( Origin gPackager )
				)
				( objectStatus "TP_P3E_CPU1_PE2_RSR_RXN<11>" )
			)
			( signal "@baseboard_fab2_lib.baseboard_fab2(sch_1):tp_p3e_cpu1_pe2_rsr_rxn(12)"
				( attribute "CDS_PHYS_NET_NAME" "TP_P3E_CPU1_PE2_RSR_RXN<12>"
					( Origin gPackager )
				)
				( attribute "PNN" "TP_P3E_CPU1_PE2_RSR_RXN<12>"
					( Origin gPackager )
				)
				( objectStatus "TP_P3E_CPU1_PE2_RSR_RXN<12>" )
			)
			( signal "@baseboard_fab2_lib.baseboard_fab2(sch_1):tp_p3e_cpu1_pe2_rsr_rxn(13)"
				( attribute "CDS_PHYS_NET_NAME" "TP_P3E_CPU1_PE2_RSR_RXN<13>"
					( Origin gPackager )
				)
				( attribute "PNN" "TP_P3E_CPU1_PE2_RSR_RXN<13>"
					( Origin gPackager )
				)
				( objectStatus "TP_P3E_CPU1_PE2_RSR_RXN<13>" )
			)
			( signal "@baseboard_fab2_lib.baseboard_fab2(sch_1):tp_p3e_cpu1_pe2_rsr_rxn(14)"
				( attribute "CDS_PHYS_NET_NAME" "TP_P3E_CPU1_PE2_RSR_RXN<14>"
					( Origin gPackager )
				)
				( attribute "PNN" "TP_P3E_CPU1_PE2_RSR_RXN<14>"
					( Origin gPackager )
				)
				( objectStatus "TP_P3E_CPU1_PE2_RSR_RXN<14>" )
			)
			( signal "@baseboard_fab2_lib.baseboard_fab2(sch_1):tp_p3e_cpu1_pe2_rsr_rxn(15)"
				( attribute "CDS_PHYS_NET_NAME" "TP_P3E_CPU1_PE2_RSR_RXN<15>"
					( Origin gPackager )
				)
				( attribute "PNN" "TP_P3E_CPU1_PE2_RSR_RXN<15>"
					( Origin gPackager )
				)
				( objectStatus "TP_P3E_CPU1_PE2_RSR_RXN<15>" )
			)
			( signal "@baseboard_fab2_lib.baseboard_fab2(sch_1):tp_p3e_cpu1_pe2_rsr_rxp(0)"
				( attribute "CDS_PHYS_NET_NAME" "TP_P3E_CPU1_PE2_RSR_RXP<0>"
					( Origin gPackager )
				)
				( attribute "PNN" "TP_P3E_CPU1_PE2_RSR_RXP<0>"
					( Origin gPackager )
				)
				( objectStatus "TP_P3E_CPU1_PE2_RSR_RXP<0>" )
			)
			( signal "@baseboard_fab2_lib.baseboard_fab2(sch_1):tp_p3e_cpu1_pe2_rsr_rxp(1)"
				( attribute "CDS_PHYS_NET_NAME" "TP_P3E_CPU1_PE2_RSR_RXP<1>"
					( Origin gPackager )
				)
				( attribute "PNN" "TP_P3E_CPU1_PE2_RSR_RXP<1>"
					( Origin gPackager )
				)
				( objectStatus "TP_P3E_CPU1_PE2_RSR_RXP<1>" )
			)
			( signal "@baseboard_fab2_lib.baseboard_fab2(sch_1):tp_p3e_cpu1_pe2_rsr_rxp(2)"
				( attribute "CDS_PHYS_NET_NAME" "TP_P3E_CPU1_PE2_RSR_RXP<2>"
					( Origin gPackager )
				)
				( attribute "PNN" "TP_P3E_CPU1_PE2_RSR_RXP<2>"
					( Origin gPackager )
				)
				( objectStatus "TP_P3E_CPU1_PE2_RSR_RXP<2>" )
			)
			( signal "@baseboard_fab2_lib.baseboard_fab2(sch_1):tp_p3e_cpu1_pe2_rsr_rxp(3)"
				( attribute "CDS_PHYS_NET_NAME" "TP_P3E_CPU1_PE2_RSR_RXP<3>"
					( Origin gPackager )
				)
				( attribute "PNN" "TP_P3E_CPU1_PE2_RSR_RXP<3>"
					( Origin gPackager )
				)
				( objectStatus "TP_P3E_CPU1_PE2_RSR_RXP<3>" )
			)
			( signal "@baseboard_fab2_lib.baseboard_fab2(sch_1):tp_p3e_cpu1_pe2_rsr_rxp(4)"
				( attribute "CDS_PHYS_NET_NAME" "TP_P3E_CPU1_PE2_RSR_RXP<4>"
					( Origin gPackager )
				)
				( attribute "PNN" "TP_P3E_CPU1_PE2_RSR_RXP<4>"
					( Origin gPackager )
				)
				( objectStatus "TP_P3E_CPU1_PE2_RSR_RXP<4>" )
			)
			( signal "@baseboard_fab2_lib.baseboard_fab2(sch_1):tp_p3e_cpu1_pe2_rsr_rxp(5)"
				( attribute "CDS_PHYS_NET_NAME" "TP_P3E_CPU1_PE2_RSR_RXP<5>"
					( Origin gPackager )
				)
				( attribute "PNN" "TP_P3E_CPU1_PE2_RSR_RXP<5>"
					( Origin gPackager )
				)
				( objectStatus "TP_P3E_CPU1_PE2_RSR_RXP<5>" )
			)
			( signal "@baseboard_fab2_lib.baseboard_fab2(sch_1):tp_p3e_cpu1_pe2_rsr_rxp(6)"
				( attribute "CDS_PHYS_NET_NAME" "TP_P3E_CPU1_PE2_RSR_RXP<6>"
					( Origin gPackager )
				)
				( attribute "PNN" "TP_P3E_CPU1_PE2_RSR_RXP<6>"
					( Origin gPackager )
				)
				( objectStatus "TP_P3E_CPU1_PE2_RSR_RXP<6>" )
			)
			( signal "@baseboard_fab2_lib.baseboard_fab2(sch_1):tp_p3e_cpu1_pe2_rsr_rxp(7)"
				( attribute "CDS_PHYS_NET_NAME" "TP_P3E_CPU1_PE2_RSR_RXP<7>"
					( Origin gPackager )
				)
				( attribute "PNN" "TP_P3E_CPU1_PE2_RSR_RXP<7>"
					( Origin gPackager )
				)
				( objectStatus "TP_P3E_CPU1_PE2_RSR_RXP<7>" )
			)
			( signal "@baseboard_fab2_lib.baseboard_fab2(sch_1):tp_p3e_cpu1_pe2_rsr_rxp(8)"
				( attribute "CDS_PHYS_NET_NAME" "TP_P3E_CPU1_PE2_RSR_RXP<8>"
					( Origin gPackager )
				)
				( attribute "PNN" "TP_P3E_CPU1_PE2_RSR_RXP<8>"
					( Origin gPackager )
				)
				( objectStatus "TP_P3E_CPU1_PE2_RSR_RXP<8>" )
			)
			( signal "@baseboard_fab2_lib.baseboard_fab2(sch_1):tp_p3e_cpu1_pe2_rsr_rxp(9)"
				( attribute "CDS_PHYS_NET_NAME" "TP_P3E_CPU1_PE2_RSR_RXP<9>"
					( Origin gPackager )
				)
				( attribute "PNN" "TP_P3E_CPU1_PE2_RSR_RXP<9>"
					( Origin gPackager )
				)
				( objectStatus "TP_P3E_CPU1_PE2_RSR_RXP<9>" )
			)
			( signal "@baseboard_fab2_lib.baseboard_fab2(sch_1):tp_p3e_cpu1_pe2_rsr_rxp(10)"
				( attribute "CDS_PHYS_NET_NAME" "TP_P3E_CPU1_PE2_RSR_RXP<10>"
					( Origin gPackager )
				)
				( attribute "PNN" "TP_P3E_CPU1_PE2_RSR_RXP<10>"
					( Origin gPackager )
				)
				( objectStatus "TP_P3E_CPU1_PE2_RSR_RXP<10>" )
			)
			( signal "@baseboard_fab2_lib.baseboard_fab2(sch_1):tp_p3e_cpu1_pe2_rsr_rxp(11)"
				( attribute "CDS_PHYS_NET_NAME" "TP_P3E_CPU1_PE2_RSR_RXP<11>"
					( Origin gPackager )
				)
				( attribute "PNN" "TP_P3E_CPU1_PE2_RSR_RXP<11>"
					( Origin gPackager )
				)
				( objectStatus "TP_P3E_CPU1_PE2_RSR_RXP<11>" )
			)
			( signal "@baseboard_fab2_lib.baseboard_fab2(sch_1):tp_p3e_cpu1_pe2_rsr_rxp(12)"
				( attribute "CDS_PHYS_NET_NAME" "TP_P3E_CPU1_PE2_RSR_RXP<12>"
					( Origin gPackager )
				)
				( attribute "PNN" "TP_P3E_CPU1_PE2_RSR_RXP<12>"
					( Origin gPackager )
				)
				( objectStatus "TP_P3E_CPU1_PE2_RSR_RXP<12>" )
			)
			( signal "@baseboard_fab2_lib.baseboard_fab2(sch_1):tp_p3e_cpu1_pe2_rsr_rxp(13)"
				( attribute "CDS_PHYS_NET_NAME" "TP_P3E_CPU1_PE2_RSR_RXP<13>"
					( Origin gPackager )
				)
				( attribute "PNN" "TP_P3E_CPU1_PE2_RSR_RXP<13>"
					( Origin gPackager )
				)
				( objectStatus "TP_P3E_CPU1_PE2_RSR_RXP<13>" )
			)
			( signal "@baseboard_fab2_lib.baseboard_fab2(sch_1):tp_p3e_cpu1_pe2_rsr_rxp(14)"
				( attribute "CDS_PHYS_NET_NAME" "TP_P3E_CPU1_PE2_RSR_RXP<14>"
					( Origin gPackager )
				)
				( attribute "PNN" "TP_P3E_CPU1_PE2_RSR_RXP<14>"
					( Origin gPackager )
				)
				( objectStatus "TP_P3E_CPU1_PE2_RSR_RXP<14>" )
			)
			( signal "@baseboard_fab2_lib.baseboard_fab2(sch_1):tp_p3e_cpu1_pe2_rsr_rxp(15)"
				( attribute "CDS_PHYS_NET_NAME" "TP_P3E_CPU1_PE2_RSR_RXP<15>"
					( Origin gPackager )
				)
				( attribute "PNN" "TP_P3E_CPU1_PE2_RSR_RXP<15>"
					( Origin gPackager )
				)
				( objectStatus "TP_P3E_CPU1_PE2_RSR_RXP<15>" )
			)
			( signal "@baseboard_fab2_lib.baseboard_fab2(sch_1):tp_p3e_cpu1_pe2_rsr_txn(0)"
				( attribute "CDS_PHYS_NET_NAME" "TP_P3E_CPU1_PE2_RSR_TXN<0>"
					( Origin gPackager )
				)
				( attribute "PNN" "TP_P3E_CPU1_PE2_RSR_TXN<0>"
					( Origin gPackager )
				)
				( objectStatus "TP_P3E_CPU1_PE2_RSR_TXN<0>" )
			)
			( signal "@baseboard_fab2_lib.baseboard_fab2(sch_1):tp_p3e_cpu1_pe2_rsr_txn(1)"
				( attribute "CDS_PHYS_NET_NAME" "TP_P3E_CPU1_PE2_RSR_TXN<1>"
					( Origin gPackager )
				)
				( attribute "PNN" "TP_P3E_CPU1_PE2_RSR_TXN<1>"
					( Origin gPackager )
				)
				( objectStatus "TP_P3E_CPU1_PE2_RSR_TXN<1>" )
			)
			( signal "@baseboard_fab2_lib.baseboard_fab2(sch_1):tp_p3e_cpu1_pe2_rsr_txn(2)"
				( attribute "CDS_PHYS_NET_NAME" "TP_P3E_CPU1_PE2_RSR_TXN<2>"
					( Origin gPackager )
				)
				( attribute "PNN" "TP_P3E_CPU1_PE2_RSR_TXN<2>"
					( Origin gPackager )
				)
				( objectStatus "TP_P3E_CPU1_PE2_RSR_TXN<2>" )
			)
			( signal "@baseboard_fab2_lib.baseboard_fab2(sch_1):tp_p3e_cpu1_pe2_rsr_txn(3)"
				( attribute "CDS_PHYS_NET_NAME" "TP_P3E_CPU1_PE2_RSR_TXN<3>"
					( Origin gPackager )
				)
				( attribute "PNN" "TP_P3E_CPU1_PE2_RSR_TXN<3>"
					( Origin gPackager )
				)
				( objectStatus "TP_P3E_CPU1_PE2_RSR_TXN<3>" )
			)
			( signal "@baseboard_fab2_lib.baseboard_fab2(sch_1):tp_p3e_cpu1_pe2_rsr_txn(4)"
				( attribute "CDS_PHYS_NET_NAME" "TP_P3E_CPU1_PE2_RSR_TXN<4>"
					( Origin gPackager )
				)
				( attribute "PNN" "TP_P3E_CPU1_PE2_RSR_TXN<4>"
					( Origin gPackager )
				)
				( objectStatus "TP_P3E_CPU1_PE2_RSR_TXN<4>" )
			)
			( signal "@baseboard_fab2_lib.baseboard_fab2(sch_1):tp_p3e_cpu1_pe2_rsr_txn(5)"
				( attribute "CDS_PHYS_NET_NAME" "TP_P3E_CPU1_PE2_RSR_TXN<5>"
					( Origin gPackager )
				)
				( attribute "PNN" "TP_P3E_CPU1_PE2_RSR_TXN<5>"
					( Origin gPackager )
				)
				( objectStatus "TP_P3E_CPU1_PE2_RSR_TXN<5>" )
			)
			( signal "@baseboard_fab2_lib.baseboard_fab2(sch_1):tp_p3e_cpu1_pe2_rsr_txn(6)"
				( attribute "CDS_PHYS_NET_NAME" "TP_P3E_CPU1_PE2_RSR_TXN<6>"
					( Origin gPackager )
				)
				( attribute "PNN" "TP_P3E_CPU1_PE2_RSR_TXN<6>"
					( Origin gPackager )
				)
				( objectStatus "TP_P3E_CPU1_PE2_RSR_TXN<6>" )
			)
			( signal "@baseboard_fab2_lib.baseboard_fab2(sch_1):tp_p3e_cpu1_pe2_rsr_txn(7)"
				( attribute "CDS_PHYS_NET_NAME" "TP_P3E_CPU1_PE2_RSR_TXN<7>"
					( Origin gPackager )
				)
				( attribute "PNN" "TP_P3E_CPU1_PE2_RSR_TXN<7>"
					( Origin gPackager )
				)
				( objectStatus "TP_P3E_CPU1_PE2_RSR_TXN<7>" )
			)
			( signal "@baseboard_fab2_lib.baseboard_fab2(sch_1):tp_p3e_cpu1_pe2_rsr_txn(8)"
				( attribute "CDS_PHYS_NET_NAME" "TP_P3E_CPU1_PE2_RSR_TXN<8>"
					( Origin gPackager )
				)
				( attribute "PNN" "TP_P3E_CPU1_PE2_RSR_TXN<8>"
					( Origin gPackager )
				)
				( objectStatus "TP_P3E_CPU1_PE2_RSR_TXN<8>" )
			)
			( signal "@baseboard_fab2_lib.baseboard_fab2(sch_1):tp_p3e_cpu1_pe2_rsr_txn(9)"
				( attribute "CDS_PHYS_NET_NAME" "TP_P3E_CPU1_PE2_RSR_TXN<9>"
					( Origin gPackager )
				)
				( attribute "PNN" "TP_P3E_CPU1_PE2_RSR_TXN<9>"
					( Origin gPackager )
				)
				( objectStatus "TP_P3E_CPU1_PE2_RSR_TXN<9>" )
			)
			( signal "@baseboard_fab2_lib.baseboard_fab2(sch_1):tp_p3e_cpu1_pe2_rsr_txn(10)"
				( attribute "CDS_PHYS_NET_NAME" "TP_P3E_CPU1_PE2_RSR_TXN<10>"
					( Origin gPackager )
				)
				( attribute "PNN" "TP_P3E_CPU1_PE2_RSR_TXN<10>"
					( Origin gPackager )
				)
				( objectStatus "TP_P3E_CPU1_PE2_RSR_TXN<10>" )
			)
			( signal "@baseboard_fab2_lib.baseboard_fab2(sch_1):tp_p3e_cpu1_pe2_rsr_txn(11)"
				( attribute "CDS_PHYS_NET_NAME" "TP_P3E_CPU1_PE2_RSR_TXN<11>"
					( Origin gPackager )
				)
				( attribute "PNN" "TP_P3E_CPU1_PE2_RSR_TXN<11>"
					( Origin gPackager )
				)
				( objectStatus "TP_P3E_CPU1_PE2_RSR_TXN<11>" )
			)
			( signal "@baseboard_fab2_lib.baseboard_fab2(sch_1):tp_p3e_cpu1_pe2_rsr_txn(12)"
				( attribute "CDS_PHYS_NET_NAME" "TP_P3E_CPU1_PE2_RSR_TXN<12>"
					( Origin gPackager )
				)
				( attribute "PNN" "TP_P3E_CPU1_PE2_RSR_TXN<12>"
					( Origin gPackager )
				)
				( objectStatus "TP_P3E_CPU1_PE2_RSR_TXN<12>" )
			)
			( signal "@baseboard_fab2_lib.baseboard_fab2(sch_1):tp_p3e_cpu1_pe2_rsr_txn(13)"
				( attribute "CDS_PHYS_NET_NAME" "TP_P3E_CPU1_PE2_RSR_TXN<13>"
					( Origin gPackager )
				)
				( attribute "PNN" "TP_P3E_CPU1_PE2_RSR_TXN<13>"
					( Origin gPackager )
				)
				( objectStatus "TP_P3E_CPU1_PE2_RSR_TXN<13>" )
			)
			( signal "@baseboard_fab2_lib.baseboard_fab2(sch_1):tp_p3e_cpu1_pe2_rsr_txn(14)"
				( attribute "CDS_PHYS_NET_NAME" "TP_P3E_CPU1_PE2_RSR_TXN<14>"
					( Origin gPackager )
				)
				( attribute "PNN" "TP_P3E_CPU1_PE2_RSR_TXN<14>"
					( Origin gPackager )
				)
				( objectStatus "TP_P3E_CPU1_PE2_RSR_TXN<14>" )
			)
			( signal "@baseboard_fab2_lib.baseboard_fab2(sch_1):tp_p3e_cpu1_pe2_rsr_txn(15)"
				( attribute "CDS_PHYS_NET_NAME" "TP_P3E_CPU1_PE2_RSR_TXN<15>"
					( Origin gPackager )
				)
				( attribute "PNN" "TP_P3E_CPU1_PE2_RSR_TXN<15>"
					( Origin gPackager )
				)
				( objectStatus "TP_P3E_CPU1_PE2_RSR_TXN<15>" )
			)
			( signal "@baseboard_fab2_lib.baseboard_fab2(sch_1):tp_p3e_cpu1_pe2_rsr_txp(0)"
				( attribute "CDS_PHYS_NET_NAME" "TP_P3E_CPU1_PE2_RSR_TXP<0>"
					( Origin gPackager )
				)
				( attribute "PNN" "TP_P3E_CPU1_PE2_RSR_TXP<0>"
					( Origin gPackager )
				)
				( objectStatus "TP_P3E_CPU1_PE2_RSR_TXP<0>" )
			)
			( signal "@baseboard_fab2_lib.baseboard_fab2(sch_1):tp_p3e_cpu1_pe2_rsr_txp(1)"
				( attribute "CDS_PHYS_NET_NAME" "TP_P3E_CPU1_PE2_RSR_TXP<1>"
					( Origin gPackager )
				)
				( attribute "PNN" "TP_P3E_CPU1_PE2_RSR_TXP<1>"
					( Origin gPackager )
				)
				( objectStatus "TP_P3E_CPU1_PE2_RSR_TXP<1>" )
			)
			( signal "@baseboard_fab2_lib.baseboard_fab2(sch_1):tp_p3e_cpu1_pe2_rsr_txp(2)"
				( attribute "CDS_PHYS_NET_NAME" "TP_P3E_CPU1_PE2_RSR_TXP<2>"
					( Origin gPackager )
				)
				( attribute "PNN" "TP_P3E_CPU1_PE2_RSR_TXP<2>"
					( Origin gPackager )
				)
				( objectStatus "TP_P3E_CPU1_PE2_RSR_TXP<2>" )
			)
			( signal "@baseboard_fab2_lib.baseboard_fab2(sch_1):tp_p3e_cpu1_pe2_rsr_txp(3)"
				( attribute "CDS_PHYS_NET_NAME" "TP_P3E_CPU1_PE2_RSR_TXP<3>"
					( Origin gPackager )
				)
				( attribute "PNN" "TP_P3E_CPU1_PE2_RSR_TXP<3>"
					( Origin gPackager )
				)
				( objectStatus "TP_P3E_CPU1_PE2_RSR_TXP<3>" )
			)
			( signal "@baseboard_fab2_lib.baseboard_fab2(sch_1):tp_p3e_cpu1_pe2_rsr_txp(4)"
				( attribute "CDS_PHYS_NET_NAME" "TP_P3E_CPU1_PE2_RSR_TXP<4>"
					( Origin gPackager )
				)
				( attribute "PNN" "TP_P3E_CPU1_PE2_RSR_TXP<4>"
					( Origin gPackager )
				)
				( objectStatus "TP_P3E_CPU1_PE2_RSR_TXP<4>" )
			)
			( signal "@baseboard_fab2_lib.baseboard_fab2(sch_1):tp_p3e_cpu1_pe2_rsr_txp(5)"
				( attribute "CDS_PHYS_NET_NAME" "TP_P3E_CPU1_PE2_RSR_TXP<5>"
					( Origin gPackager )
				)
				( attribute "PNN" "TP_P3E_CPU1_PE2_RSR_TXP<5>"
					( Origin gPackager )
				)
				( objectStatus "TP_P3E_CPU1_PE2_RSR_TXP<5>" )
			)
			( signal "@baseboard_fab2_lib.baseboard_fab2(sch_1):tp_p3e_cpu1_pe2_rsr_txp(6)"
				( attribute "CDS_PHYS_NET_NAME" "TP_P3E_CPU1_PE2_RSR_TXP<6>"
					( Origin gPackager )
				)
				( attribute "PNN" "TP_P3E_CPU1_PE2_RSR_TXP<6>"
					( Origin gPackager )
				)
				( objectStatus "TP_P3E_CPU1_PE2_RSR_TXP<6>" )
			)
			( signal "@baseboard_fab2_lib.baseboard_fab2(sch_1):tp_p3e_cpu1_pe2_rsr_txp(7)"
				( attribute "CDS_PHYS_NET_NAME" "TP_P3E_CPU1_PE2_RSR_TXP<7>"
					( Origin gPackager )
				)
				( attribute "PNN" "TP_P3E_CPU1_PE2_RSR_TXP<7>"
					( Origin gPackager )
				)
				( objectStatus "TP_P3E_CPU1_PE2_RSR_TXP<7>" )
			)
			( signal "@baseboard_fab2_lib.baseboard_fab2(sch_1):tp_p3e_cpu1_pe2_rsr_txp(8)"
				( attribute "CDS_PHYS_NET_NAME" "TP_P3E_CPU1_PE2_RSR_TXP<8>"
					( Origin gPackager )
				)
				( attribute "PNN" "TP_P3E_CPU1_PE2_RSR_TXP<8>"
					( Origin gPackager )
				)
				( objectStatus "TP_P3E_CPU1_PE2_RSR_TXP<8>" )
			)
			( signal "@baseboard_fab2_lib.baseboard_fab2(sch_1):tp_p3e_cpu1_pe2_rsr_txp(9)"
				( attribute "CDS_PHYS_NET_NAME" "TP_P3E_CPU1_PE2_RSR_TXP<9>"
					( Origin gPackager )
				)
				( attribute "PNN" "TP_P3E_CPU1_PE2_RSR_TXP<9>"
					( Origin gPackager )
				)
				( objectStatus "TP_P3E_CPU1_PE2_RSR_TXP<9>" )
			)
			( signal "@baseboard_fab2_lib.baseboard_fab2(sch_1):tp_p3e_cpu1_pe2_rsr_txp(10)"
				( attribute "CDS_PHYS_NET_NAME" "TP_P3E_CPU1_PE2_RSR_TXP<10>"
					( Origin gPackager )
				)
				( attribute "PNN" "TP_P3E_CPU1_PE2_RSR_TXP<10>"
					( Origin gPackager )
				)
				( objectStatus "TP_P3E_CPU1_PE2_RSR_TXP<10>" )
			)
			( signal "@baseboard_fab2_lib.baseboard_fab2(sch_1):tp_p3e_cpu1_pe2_rsr_txp(11)"
				( attribute "CDS_PHYS_NET_NAME" "TP_P3E_CPU1_PE2_RSR_TXP<11>"
					( Origin gPackager )
				)
				( attribute "PNN" "TP_P3E_CPU1_PE2_RSR_TXP<11>"
					( Origin gPackager )
				)
				( objectStatus "TP_P3E_CPU1_PE2_RSR_TXP<11>" )
			)
			( signal "@baseboard_fab2_lib.baseboard_fab2(sch_1):tp_p3e_cpu1_pe2_rsr_txp(12)"
				( attribute "CDS_PHYS_NET_NAME" "TP_P3E_CPU1_PE2_RSR_TXP<12>"
					( Origin gPackager )
				)
				( attribute "PNN" "TP_P3E_CPU1_PE2_RSR_TXP<12>"
					( Origin gPackager )
				)
				( objectStatus "TP_P3E_CPU1_PE2_RSR_TXP<12>" )
			)
			( signal "@baseboard_fab2_lib.baseboard_fab2(sch_1):tp_p3e_cpu1_pe2_rsr_txp(13)"
				( attribute "CDS_PHYS_NET_NAME" "TP_P3E_CPU1_PE2_RSR_TXP<13>"
					( Origin gPackager )
				)
				( attribute "PNN" "TP_P3E_CPU1_PE2_RSR_TXP<13>"
					( Origin gPackager )
				)
				( objectStatus "TP_P3E_CPU1_PE2_RSR_TXP<13>" )
			)
			( signal "@baseboard_fab2_lib.baseboard_fab2(sch_1):tp_p3e_cpu1_pe2_rsr_txp(14)"
				( attribute "CDS_PHYS_NET_NAME" "TP_P3E_CPU1_PE2_RSR_TXP<14>"
					( Origin gPackager )
				)
				( attribute "PNN" "TP_P3E_CPU1_PE2_RSR_TXP<14>"
					( Origin gPackager )
				)
				( objectStatus "TP_P3E_CPU1_PE2_RSR_TXP<14>" )
			)
			( signal "@baseboard_fab2_lib.baseboard_fab2(sch_1):tp_p3e_cpu1_pe2_rsr_txp(15)"
				( attribute "CDS_PHYS_NET_NAME" "TP_P3E_CPU1_PE2_RSR_TXP<15>"
					( Origin gPackager )
				)
				( attribute "PNN" "TP_P3E_CPU1_PE2_RSR_TXP<15>"
					( Origin gPackager )
				)
				( objectStatus "TP_P3E_CPU1_PE2_RSR_TXP<15>" )
			)
			( signal "@baseboard_fab2_lib.baseboard_fab2(sch_1):p3e_cpu1_pe3_mp_rxn(0)"
				( attribute "CDS_PHYS_NET_NAME" "P3E_CPU1_PE3_MP_RXN<0>"
					( Origin gPackager )
				)
				( attribute "PNN" "P3E_CPU1_PE3_MP_RXN<0>"
					( Origin gPackager )
				)
				( objectStatus "P3E_CPU1_PE3_MP_RXN<0>" )
			)
			( signal "@baseboard_fab2_lib.baseboard_fab2(sch_1):p3e_cpu1_pe3_mp_rxn(1)"
				( attribute "CDS_PHYS_NET_NAME" "P3E_CPU1_PE3_MP_RXN<1>"
					( Origin gPackager )
				)
				( attribute "PNN" "P3E_CPU1_PE3_MP_RXN<1>"
					( Origin gPackager )
				)
				( objectStatus "P3E_CPU1_PE3_MP_RXN<1>" )
			)
			( signal "@baseboard_fab2_lib.baseboard_fab2(sch_1):p3e_cpu1_pe3_mp_rxn(2)"
				( attribute "CDS_PHYS_NET_NAME" "P3E_CPU1_PE3_MP_RXN<2>"
					( Origin gPackager )
				)
				( attribute "PNN" "P3E_CPU1_PE3_MP_RXN<2>"
					( Origin gPackager )
				)
				( objectStatus "P3E_CPU1_PE3_MP_RXN<2>" )
			)
			( signal "@baseboard_fab2_lib.baseboard_fab2(sch_1):p3e_cpu1_pe3_mp_rxn(3)"
				( attribute "CDS_PHYS_NET_NAME" "P3E_CPU1_PE3_MP_RXN<3>"
					( Origin gPackager )
				)
				( attribute "PNN" "P3E_CPU1_PE3_MP_RXN<3>"
					( Origin gPackager )
				)
				( objectStatus "P3E_CPU1_PE3_MP_RXN<3>" )
			)
			( signal "@baseboard_fab2_lib.baseboard_fab2(sch_1):p3e_cpu1_pe3_mp_rxn(4)"
				( attribute "CDS_PHYS_NET_NAME" "P3E_CPU1_PE3_MP_RXN<4>"
					( Origin gPackager )
				)
				( attribute "PNN" "P3E_CPU1_PE3_MP_RXN<4>"
					( Origin gPackager )
				)
				( objectStatus "P3E_CPU1_PE3_MP_RXN<4>" )
			)
			( signal "@baseboard_fab2_lib.baseboard_fab2(sch_1):p3e_cpu1_pe3_mp_rxn(5)"
				( attribute "CDS_PHYS_NET_NAME" "P3E_CPU1_PE3_MP_RXN<5>"
					( Origin gPackager )
				)
				( attribute "PNN" "P3E_CPU1_PE3_MP_RXN<5>"
					( Origin gPackager )
				)
				( objectStatus "P3E_CPU1_PE3_MP_RXN<5>" )
			)
			( signal "@baseboard_fab2_lib.baseboard_fab2(sch_1):p3e_cpu1_pe3_mp_rxn(6)"
				( attribute "CDS_PHYS_NET_NAME" "P3E_CPU1_PE3_MP_RXN<6>"
					( Origin gPackager )
				)
				( attribute "PNN" "P3E_CPU1_PE3_MP_RXN<6>"
					( Origin gPackager )
				)
				( objectStatus "P3E_CPU1_PE3_MP_RXN<6>" )
			)
			( signal "@baseboard_fab2_lib.baseboard_fab2(sch_1):p3e_cpu1_pe3_mp_rxn(7)"
				( attribute "CDS_PHYS_NET_NAME" "P3E_CPU1_PE3_MP_RXN<7>"
					( Origin gPackager )
				)
				( attribute "PNN" "P3E_CPU1_PE3_MP_RXN<7>"
					( Origin gPackager )
				)
				( objectStatus "P3E_CPU1_PE3_MP_RXN<7>" )
			)
			( signal "@baseboard_fab2_lib.baseboard_fab2(sch_1):p3e_cpu1_pe3_mp_rxn(8)"
				( attribute "CDS_PHYS_NET_NAME" "P3E_CPU1_PE3_MP_RXN<8>"
					( Origin gPackager )
				)
				( attribute "PNN" "P3E_CPU1_PE3_MP_RXN<8>"
					( Origin gPackager )
				)
				( objectStatus "P3E_CPU1_PE3_MP_RXN<8>" )
			)
			( signal "@baseboard_fab2_lib.baseboard_fab2(sch_1):p3e_cpu1_pe3_mp_rxn(9)"
				( attribute "CDS_PHYS_NET_NAME" "P3E_CPU1_PE3_MP_RXN<9>"
					( Origin gPackager )
				)
				( attribute "PNN" "P3E_CPU1_PE3_MP_RXN<9>"
					( Origin gPackager )
				)
				( objectStatus "P3E_CPU1_PE3_MP_RXN<9>" )
			)
			( signal "@baseboard_fab2_lib.baseboard_fab2(sch_1):p3e_cpu1_pe3_mp_rxn(10)"
				( attribute "CDS_PHYS_NET_NAME" "P3E_CPU1_PE3_MP_RXN<10>"
					( Origin gPackager )
				)
				( attribute "PNN" "P3E_CPU1_PE3_MP_RXN<10>"
					( Origin gPackager )
				)
				( objectStatus "P3E_CPU1_PE3_MP_RXN<10>" )
			)
			( signal "@baseboard_fab2_lib.baseboard_fab2(sch_1):p3e_cpu1_pe3_mp_rxn(11)"
				( attribute "CDS_PHYS_NET_NAME" "P3E_CPU1_PE3_MP_RXN<11>"
					( Origin gPackager )
				)
				( attribute "PNN" "P3E_CPU1_PE3_MP_RXN<11>"
					( Origin gPackager )
				)
				( objectStatus "P3E_CPU1_PE3_MP_RXN<11>" )
			)
			( signal "@baseboard_fab2_lib.baseboard_fab2(sch_1):p3e_cpu1_pe3_mp_rxn(12)"
				( attribute "CDS_PHYS_NET_NAME" "P3E_CPU1_PE3_MP_RXN<12>"
					( Origin gPackager )
				)
				( attribute "PNN" "P3E_CPU1_PE3_MP_RXN<12>"
					( Origin gPackager )
				)
				( objectStatus "P3E_CPU1_PE3_MP_RXN<12>" )
			)
			( signal "@baseboard_fab2_lib.baseboard_fab2(sch_1):p3e_cpu1_pe3_mp_rxn(13)"
				( attribute "CDS_PHYS_NET_NAME" "P3E_CPU1_PE3_MP_RXN<13>"
					( Origin gPackager )
				)
				( attribute "PNN" "P3E_CPU1_PE3_MP_RXN<13>"
					( Origin gPackager )
				)
				( objectStatus "P3E_CPU1_PE3_MP_RXN<13>" )
			)
			( signal "@baseboard_fab2_lib.baseboard_fab2(sch_1):p3e_cpu1_pe3_mp_rxn(14)"
				( attribute "CDS_PHYS_NET_NAME" "P3E_CPU1_PE3_MP_RXN<14>"
					( Origin gPackager )
				)
				( attribute "PNN" "P3E_CPU1_PE3_MP_RXN<14>"
					( Origin gPackager )
				)
				( objectStatus "P3E_CPU1_PE3_MP_RXN<14>" )
			)
			( signal "@baseboard_fab2_lib.baseboard_fab2(sch_1):p3e_cpu1_pe3_mp_rxn(15)"
				( attribute "CDS_PHYS_NET_NAME" "P3E_CPU1_PE3_MP_RXN<15>"
					( Origin gPackager )
				)
				( attribute "PNN" "P3E_CPU1_PE3_MP_RXN<15>"
					( Origin gPackager )
				)
				( objectStatus "P3E_CPU1_PE3_MP_RXN<15>" )
			)
			( signal "@baseboard_fab2_lib.baseboard_fab2(sch_1):p3e_cpu1_pe3_mp_rxp(0)"
				( attribute "CDS_PHYS_NET_NAME" "P3E_CPU1_PE3_MP_RXP<0>"
					( Origin gPackager )
				)
				( attribute "PNN" "P3E_CPU1_PE3_MP_RXP<0>"
					( Origin gPackager )
				)
				( objectStatus "P3E_CPU1_PE3_MP_RXP<0>" )
			)
			( signal "@baseboard_fab2_lib.baseboard_fab2(sch_1):p3e_cpu1_pe3_mp_rxp(1)"
				( attribute "CDS_PHYS_NET_NAME" "P3E_CPU1_PE3_MP_RXP<1>"
					( Origin gPackager )
				)
				( attribute "PNN" "P3E_CPU1_PE3_MP_RXP<1>"
					( Origin gPackager )
				)
				( objectStatus "P3E_CPU1_PE3_MP_RXP<1>" )
			)
			( signal "@baseboard_fab2_lib.baseboard_fab2(sch_1):p3e_cpu1_pe3_mp_rxp(2)"
				( attribute "CDS_PHYS_NET_NAME" "P3E_CPU1_PE3_MP_RXP<2>"
					( Origin gPackager )
				)
				( attribute "PNN" "P3E_CPU1_PE3_MP_RXP<2>"
					( Origin gPackager )
				)
				( objectStatus "P3E_CPU1_PE3_MP_RXP<2>" )
			)
			( signal "@baseboard_fab2_lib.baseboard_fab2(sch_1):p3e_cpu1_pe3_mp_rxp(3)"
				( attribute "CDS_PHYS_NET_NAME" "P3E_CPU1_PE3_MP_RXP<3>"
					( Origin gPackager )
				)
				( attribute "PNN" "P3E_CPU1_PE3_MP_RXP<3>"
					( Origin gPackager )
				)
				( objectStatus "P3E_CPU1_PE3_MP_RXP<3>" )
			)
			( signal "@baseboard_fab2_lib.baseboard_fab2(sch_1):p3e_cpu1_pe3_mp_rxp(4)"
				( attribute "CDS_PHYS_NET_NAME" "P3E_CPU1_PE3_MP_RXP<4>"
					( Origin gPackager )
				)
				( attribute "PNN" "P3E_CPU1_PE3_MP_RXP<4>"
					( Origin gPackager )
				)
				( objectStatus "P3E_CPU1_PE3_MP_RXP<4>" )
			)
			( signal "@baseboard_fab2_lib.baseboard_fab2(sch_1):p3e_cpu1_pe3_mp_rxp(5)"
				( attribute "CDS_PHYS_NET_NAME" "P3E_CPU1_PE3_MP_RXP<5>"
					( Origin gPackager )
				)
				( attribute "PNN" "P3E_CPU1_PE3_MP_RXP<5>"
					( Origin gPackager )
				)
				( objectStatus "P3E_CPU1_PE3_MP_RXP<5>" )
			)
			( signal "@baseboard_fab2_lib.baseboard_fab2(sch_1):p3e_cpu1_pe3_mp_rxp(6)"
				( attribute "CDS_PHYS_NET_NAME" "P3E_CPU1_PE3_MP_RXP<6>"
					( Origin gPackager )
				)
				( attribute "PNN" "P3E_CPU1_PE3_MP_RXP<6>"
					( Origin gPackager )
				)
				( objectStatus "P3E_CPU1_PE3_MP_RXP<6>" )
			)
			( signal "@baseboard_fab2_lib.baseboard_fab2(sch_1):p3e_cpu1_pe3_mp_rxp(7)"
				( attribute "CDS_PHYS_NET_NAME" "P3E_CPU1_PE3_MP_RXP<7>"
					( Origin gPackager )
				)
				( attribute "PNN" "P3E_CPU1_PE3_MP_RXP<7>"
					( Origin gPackager )
				)
				( objectStatus "P3E_CPU1_PE3_MP_RXP<7>" )
			)
			( signal "@baseboard_fab2_lib.baseboard_fab2(sch_1):p3e_cpu1_pe3_mp_rxp(8)"
				( attribute "CDS_PHYS_NET_NAME" "P3E_CPU1_PE3_MP_RXP<8>"
					( Origin gPackager )
				)
				( attribute "PNN" "P3E_CPU1_PE3_MP_RXP<8>"
					( Origin gPackager )
				)
				( objectStatus "P3E_CPU1_PE3_MP_RXP<8>" )
			)
			( signal "@baseboard_fab2_lib.baseboard_fab2(sch_1):p3e_cpu1_pe3_mp_rxp(9)"
				( attribute "CDS_PHYS_NET_NAME" "P3E_CPU1_PE3_MP_RXP<9>"
					( Origin gPackager )
				)
				( attribute "PNN" "P3E_CPU1_PE3_MP_RXP<9>"
					( Origin gPackager )
				)
				( objectStatus "P3E_CPU1_PE3_MP_RXP<9>" )
			)
			( signal "@baseboard_fab2_lib.baseboard_fab2(sch_1):p3e_cpu1_pe3_mp_rxp(10)"
				( attribute "CDS_PHYS_NET_NAME" "P3E_CPU1_PE3_MP_RXP<10>"
					( Origin gPackager )
				)
				( attribute "PNN" "P3E_CPU1_PE3_MP_RXP<10>"
					( Origin gPackager )
				)
				( objectStatus "P3E_CPU1_PE3_MP_RXP<10>" )
			)
			( signal "@baseboard_fab2_lib.baseboard_fab2(sch_1):p3e_cpu1_pe3_mp_rxp(11)"
				( attribute "CDS_PHYS_NET_NAME" "P3E_CPU1_PE3_MP_RXP<11>"
					( Origin gPackager )
				)
				( attribute "PNN" "P3E_CPU1_PE3_MP_RXP<11>"
					( Origin gPackager )
				)
				( objectStatus "P3E_CPU1_PE3_MP_RXP<11>" )
			)
			( signal "@baseboard_fab2_lib.baseboard_fab2(sch_1):p3e_cpu1_pe3_mp_rxp(12)"
				( attribute "CDS_PHYS_NET_NAME" "P3E_CPU1_PE3_MP_RXP<12>"
					( Origin gPackager )
				)
				( attribute "PNN" "P3E_CPU1_PE3_MP_RXP<12>"
					( Origin gPackager )
				)
				( objectStatus "P3E_CPU1_PE3_MP_RXP<12>" )
			)
			( signal "@baseboard_fab2_lib.baseboard_fab2(sch_1):p3e_cpu1_pe3_mp_rxp(13)"
				( attribute "CDS_PHYS_NET_NAME" "P3E_CPU1_PE3_MP_RXP<13>"
					( Origin gPackager )
				)
				( attribute "PNN" "P3E_CPU1_PE3_MP_RXP<13>"
					( Origin gPackager )
				)
				( objectStatus "P3E_CPU1_PE3_MP_RXP<13>" )
			)
			( signal "@baseboard_fab2_lib.baseboard_fab2(sch_1):p3e_cpu1_pe3_mp_rxp(14)"
				( attribute "CDS_PHYS_NET_NAME" "P3E_CPU1_PE3_MP_RXP<14>"
					( Origin gPackager )
				)
				( attribute "PNN" "P3E_CPU1_PE3_MP_RXP<14>"
					( Origin gPackager )
				)
				( objectStatus "P3E_CPU1_PE3_MP_RXP<14>" )
			)
			( signal "@baseboard_fab2_lib.baseboard_fab2(sch_1):p3e_cpu1_pe3_mp_rxp(15)"
				( attribute "CDS_PHYS_NET_NAME" "P3E_CPU1_PE3_MP_RXP<15>"
					( Origin gPackager )
				)
				( attribute "PNN" "P3E_CPU1_PE3_MP_RXP<15>"
					( Origin gPackager )
				)
				( objectStatus "P3E_CPU1_PE3_MP_RXP<15>" )
			)
			( signal "@baseboard_fab2_lib.baseboard_fab2(sch_1):p3e_cpu1_pe3_mp_txn(0)"
				( attribute "CDS_PHYS_NET_NAME" "P3E_CPU1_PE3_MP_TXN<0>"
					( Origin gPackager )
				)
				( attribute "PNN" "P3E_CPU1_PE3_MP_TXN<0>"
					( Origin gPackager )
				)
				( objectStatus "P3E_CPU1_PE3_MP_TXN<0>" )
			)
			( signal "@baseboard_fab2_lib.baseboard_fab2(sch_1):p3e_cpu1_pe3_mp_txn(1)"
				( attribute "CDS_PHYS_NET_NAME" "P3E_CPU1_PE3_MP_TXN<1>"
					( Origin gPackager )
				)
				( attribute "PNN" "P3E_CPU1_PE3_MP_TXN<1>"
					( Origin gPackager )
				)
				( objectStatus "P3E_CPU1_PE3_MP_TXN<1>" )
			)
			( signal "@baseboard_fab2_lib.baseboard_fab2(sch_1):p3e_cpu1_pe3_mp_txn(2)"
				( attribute "CDS_PHYS_NET_NAME" "P3E_CPU1_PE3_MP_TXN<2>"
					( Origin gPackager )
				)
				( attribute "PNN" "P3E_CPU1_PE3_MP_TXN<2>"
					( Origin gPackager )
				)
				( objectStatus "P3E_CPU1_PE3_MP_TXN<2>" )
			)
			( signal "@baseboard_fab2_lib.baseboard_fab2(sch_1):p3e_cpu1_pe3_mp_txn(3)"
				( attribute "CDS_PHYS_NET_NAME" "P3E_CPU1_PE3_MP_TXN<3>"
					( Origin gPackager )
				)
				( attribute "PNN" "P3E_CPU1_PE3_MP_TXN<3>"
					( Origin gPackager )
				)
				( objectStatus "P3E_CPU1_PE3_MP_TXN<3>" )
			)
			( signal "@baseboard_fab2_lib.baseboard_fab2(sch_1):p3e_cpu1_pe3_mp_txn(4)"
				( attribute "CDS_PHYS_NET_NAME" "P3E_CPU1_PE3_MP_TXN<4>"
					( Origin gPackager )
				)
				( attribute "PNN" "P3E_CPU1_PE3_MP_TXN<4>"
					( Origin gPackager )
				)
				( objectStatus "P3E_CPU1_PE3_MP_TXN<4>" )
			)
			( signal "@baseboard_fab2_lib.baseboard_fab2(sch_1):p3e_cpu1_pe3_mp_txn(5)"
				( attribute "CDS_PHYS_NET_NAME" "P3E_CPU1_PE3_MP_TXN<5>"
					( Origin gPackager )
				)
				( attribute "PNN" "P3E_CPU1_PE3_MP_TXN<5>"
					( Origin gPackager )
				)
				( objectStatus "P3E_CPU1_PE3_MP_TXN<5>" )
			)
			( signal "@baseboard_fab2_lib.baseboard_fab2(sch_1):p3e_cpu1_pe3_mp_txn(6)"
				( attribute "CDS_PHYS_NET_NAME" "P3E_CPU1_PE3_MP_TXN<6>"
					( Origin gPackager )
				)
				( attribute "PNN" "P3E_CPU1_PE3_MP_TXN<6>"
					( Origin gPackager )
				)
				( objectStatus "P3E_CPU1_PE3_MP_TXN<6>" )
			)
			( signal "@baseboard_fab2_lib.baseboard_fab2(sch_1):p3e_cpu1_pe3_mp_txn(7)"
				( attribute "CDS_PHYS_NET_NAME" "P3E_CPU1_PE3_MP_TXN<7>"
					( Origin gPackager )
				)
				( attribute "PNN" "P3E_CPU1_PE3_MP_TXN<7>"
					( Origin gPackager )
				)
				( objectStatus "P3E_CPU1_PE3_MP_TXN<7>" )
			)
			( signal "@baseboard_fab2_lib.baseboard_fab2(sch_1):p3e_cpu1_pe3_mp_txn(8)"
				( attribute "CDS_PHYS_NET_NAME" "P3E_CPU1_PE3_MP_TXN<8>"
					( Origin gPackager )
				)
				( attribute "PNN" "P3E_CPU1_PE3_MP_TXN<8>"
					( Origin gPackager )
				)
				( objectStatus "P3E_CPU1_PE3_MP_TXN<8>" )
			)
			( signal "@baseboard_fab2_lib.baseboard_fab2(sch_1):p3e_cpu1_pe3_mp_txn(9)"
				( attribute "CDS_PHYS_NET_NAME" "P3E_CPU1_PE3_MP_TXN<9>"
					( Origin gPackager )
				)
				( attribute "PNN" "P3E_CPU1_PE3_MP_TXN<9>"
					( Origin gPackager )
				)
				( objectStatus "P3E_CPU1_PE3_MP_TXN<9>" )
			)
			( signal "@baseboard_fab2_lib.baseboard_fab2(sch_1):p3e_cpu1_pe3_mp_txn(10)"
				( attribute "CDS_PHYS_NET_NAME" "P3E_CPU1_PE3_MP_TXN<10>"
					( Origin gPackager )
				)
				( attribute "PNN" "P3E_CPU1_PE3_MP_TXN<10>"
					( Origin gPackager )
				)
				( objectStatus "P3E_CPU1_PE3_MP_TXN<10>" )
			)
			( signal "@baseboard_fab2_lib.baseboard_fab2(sch_1):p3e_cpu1_pe3_mp_txn(11)"
				( attribute "CDS_PHYS_NET_NAME" "P3E_CPU1_PE3_MP_TXN<11>"
					( Origin gPackager )
				)
				( attribute "PNN" "P3E_CPU1_PE3_MP_TXN<11>"
					( Origin gPackager )
				)
				( objectStatus "P3E_CPU1_PE3_MP_TXN<11>" )
			)
			( signal "@baseboard_fab2_lib.baseboard_fab2(sch_1):p3e_cpu1_pe3_mp_txn(12)"
				( attribute "CDS_PHYS_NET_NAME" "P3E_CPU1_PE3_MP_TXN<12>"
					( Origin gPackager )
				)
				( attribute "PNN" "P3E_CPU1_PE3_MP_TXN<12>"
					( Origin gPackager )
				)
				( objectStatus "P3E_CPU1_PE3_MP_TXN<12>" )
			)
			( signal "@baseboard_fab2_lib.baseboard_fab2(sch_1):p3e_cpu1_pe3_mp_txn(13)"
				( attribute "CDS_PHYS_NET_NAME" "P3E_CPU1_PE3_MP_TXN<13>"
					( Origin gPackager )
				)
				( attribute "PNN" "P3E_CPU1_PE3_MP_TXN<13>"
					( Origin gPackager )
				)
				( objectStatus "P3E_CPU1_PE3_MP_TXN<13>" )
			)
			( signal "@baseboard_fab2_lib.baseboard_fab2(sch_1):p3e_cpu1_pe3_mp_txn(14)"
				( attribute "CDS_PHYS_NET_NAME" "P3E_CPU1_PE3_MP_TXN<14>"
					( Origin gPackager )
				)
				( attribute "PNN" "P3E_CPU1_PE3_MP_TXN<14>"
					( Origin gPackager )
				)
				( objectStatus "P3E_CPU1_PE3_MP_TXN<14>" )
			)
			( signal "@baseboard_fab2_lib.baseboard_fab2(sch_1):p3e_cpu1_pe3_mp_txn(15)"
				( attribute "CDS_PHYS_NET_NAME" "P3E_CPU1_PE3_MP_TXN<15>"
					( Origin gPackager )
				)
				( attribute "PNN" "P3E_CPU1_PE3_MP_TXN<15>"
					( Origin gPackager )
				)
				( objectStatus "P3E_CPU1_PE3_MP_TXN<15>" )
			)
			( signal "@baseboard_fab2_lib.baseboard_fab2(sch_1):p3e_cpu1_pe3_mp_txp(0)"
				( attribute "CDS_PHYS_NET_NAME" "P3E_CPU1_PE3_MP_TXP<0>"
					( Origin gPackager )
				)
				( attribute "PNN" "P3E_CPU1_PE3_MP_TXP<0>"
					( Origin gPackager )
				)
				( objectStatus "P3E_CPU1_PE3_MP_TXP<0>" )
			)
			( signal "@baseboard_fab2_lib.baseboard_fab2(sch_1):p3e_cpu1_pe3_mp_txp(1)"
				( attribute "CDS_PHYS_NET_NAME" "P3E_CPU1_PE3_MP_TXP<1>"
					( Origin gPackager )
				)
				( attribute "PNN" "P3E_CPU1_PE3_MP_TXP<1>"
					( Origin gPackager )
				)
				( objectStatus "P3E_CPU1_PE3_MP_TXP<1>" )
			)
			( signal "@baseboard_fab2_lib.baseboard_fab2(sch_1):p3e_cpu1_pe3_mp_txp(2)"
				( attribute "CDS_PHYS_NET_NAME" "P3E_CPU1_PE3_MP_TXP<2>"
					( Origin gPackager )
				)
				( attribute "PNN" "P3E_CPU1_PE3_MP_TXP<2>"
					( Origin gPackager )
				)
				( objectStatus "P3E_CPU1_PE3_MP_TXP<2>" )
			)
			( signal "@baseboard_fab2_lib.baseboard_fab2(sch_1):p3e_cpu1_pe3_mp_txp(3)"
				( attribute "CDS_PHYS_NET_NAME" "P3E_CPU1_PE3_MP_TXP<3>"
					( Origin gPackager )
				)
				( attribute "PNN" "P3E_CPU1_PE3_MP_TXP<3>"
					( Origin gPackager )
				)
				( objectStatus "P3E_CPU1_PE3_MP_TXP<3>" )
			)
			( signal "@baseboard_fab2_lib.baseboard_fab2(sch_1):p3e_cpu1_pe3_mp_txp(4)"
				( attribute "CDS_PHYS_NET_NAME" "P3E_CPU1_PE3_MP_TXP<4>"
					( Origin gPackager )
				)
				( attribute "PNN" "P3E_CPU1_PE3_MP_TXP<4>"
					( Origin gPackager )
				)
				( objectStatus "P3E_CPU1_PE3_MP_TXP<4>" )
			)
			( signal "@baseboard_fab2_lib.baseboard_fab2(sch_1):p3e_cpu1_pe3_mp_txp(5)"
				( attribute "CDS_PHYS_NET_NAME" "P3E_CPU1_PE3_MP_TXP<5>"
					( Origin gPackager )
				)
				( attribute "PNN" "P3E_CPU1_PE3_MP_TXP<5>"
					( Origin gPackager )
				)
				( objectStatus "P3E_CPU1_PE3_MP_TXP<5>" )
			)
			( signal "@baseboard_fab2_lib.baseboard_fab2(sch_1):p3e_cpu1_pe3_mp_txp(6)"
				( attribute "CDS_PHYS_NET_NAME" "P3E_CPU1_PE3_MP_TXP<6>"
					( Origin gPackager )
				)
				( attribute "PNN" "P3E_CPU1_PE3_MP_TXP<6>"
					( Origin gPackager )
				)
				( objectStatus "P3E_CPU1_PE3_MP_TXP<6>" )
			)
			( signal "@baseboard_fab2_lib.baseboard_fab2(sch_1):p3e_cpu1_pe3_mp_txp(7)"
				( attribute "CDS_PHYS_NET_NAME" "P3E_CPU1_PE3_MP_TXP<7>"
					( Origin gPackager )
				)
				( attribute "PNN" "P3E_CPU1_PE3_MP_TXP<7>"
					( Origin gPackager )
				)
				( objectStatus "P3E_CPU1_PE3_MP_TXP<7>" )
			)
			( signal "@baseboard_fab2_lib.baseboard_fab2(sch_1):p3e_cpu1_pe3_mp_txp(8)"
				( attribute "CDS_PHYS_NET_NAME" "P3E_CPU1_PE3_MP_TXP<8>"
					( Origin gPackager )
				)
				( attribute "PNN" "P3E_CPU1_PE3_MP_TXP<8>"
					( Origin gPackager )
				)
				( objectStatus "P3E_CPU1_PE3_MP_TXP<8>" )
			)
			( signal "@baseboard_fab2_lib.baseboard_fab2(sch_1):p3e_cpu1_pe3_mp_txp(9)"
				( attribute "CDS_PHYS_NET_NAME" "P3E_CPU1_PE3_MP_TXP<9>"
					( Origin gPackager )
				)
				( attribute "PNN" "P3E_CPU1_PE3_MP_TXP<9>"
					( Origin gPackager )
				)
				( objectStatus "P3E_CPU1_PE3_MP_TXP<9>" )
			)
			( signal "@baseboard_fab2_lib.baseboard_fab2(sch_1):p3e_cpu1_pe3_mp_txp(10)"
				( attribute "CDS_PHYS_NET_NAME" "P3E_CPU1_PE3_MP_TXP<10>"
					( Origin gPackager )
				)
				( attribute "PNN" "P3E_CPU1_PE3_MP_TXP<10>"
					( Origin gPackager )
				)
				( objectStatus "P3E_CPU1_PE3_MP_TXP<10>" )
			)
			( signal "@baseboard_fab2_lib.baseboard_fab2(sch_1):p3e_cpu1_pe3_mp_txp(11)"
				( attribute "CDS_PHYS_NET_NAME" "P3E_CPU1_PE3_MP_TXP<11>"
					( Origin gPackager )
				)
				( attribute "PNN" "P3E_CPU1_PE3_MP_TXP<11>"
					( Origin gPackager )
				)
				( objectStatus "P3E_CPU1_PE3_MP_TXP<11>" )
			)
			( signal "@baseboard_fab2_lib.baseboard_fab2(sch_1):p3e_cpu1_pe3_mp_txp(12)"
				( attribute "CDS_PHYS_NET_NAME" "P3E_CPU1_PE3_MP_TXP<12>"
					( Origin gPackager )
				)
				( attribute "PNN" "P3E_CPU1_PE3_MP_TXP<12>"
					( Origin gPackager )
				)
				( objectStatus "P3E_CPU1_PE3_MP_TXP<12>" )
			)
			( signal "@baseboard_fab2_lib.baseboard_fab2(sch_1):p3e_cpu1_pe3_mp_txp(13)"
				( attribute "CDS_PHYS_NET_NAME" "P3E_CPU1_PE3_MP_TXP<13>"
					( Origin gPackager )
				)
				( attribute "PNN" "P3E_CPU1_PE3_MP_TXP<13>"
					( Origin gPackager )
				)
				( objectStatus "P3E_CPU1_PE3_MP_TXP<13>" )
			)
			( signal "@baseboard_fab2_lib.baseboard_fab2(sch_1):p3e_cpu1_pe3_mp_txp(14)"
				( attribute "CDS_PHYS_NET_NAME" "P3E_CPU1_PE3_MP_TXP<14>"
					( Origin gPackager )
				)
				( attribute "PNN" "P3E_CPU1_PE3_MP_TXP<14>"
					( Origin gPackager )
				)
				( objectStatus "P3E_CPU1_PE3_MP_TXP<14>" )
			)
			( signal "@baseboard_fab2_lib.baseboard_fab2(sch_1):p3e_cpu1_pe3_mp_txp(15)"
				( attribute "CDS_PHYS_NET_NAME" "P3E_CPU1_PE3_MP_TXP<15>"
					( Origin gPackager )
				)
				( attribute "PNN" "P3E_CPU1_PE3_MP_TXP<15>"
					( Origin gPackager )
				)
				( objectStatus "P3E_CPU1_PE3_MP_TXP<15>" )
			)
			( signal "@baseboard_fab2_lib.baseboard_fab2(sch_1):tp_cpu1_upi2_rsvd_ca12"
				( attribute "CDS_PHYS_NET_NAME" "TP_CPU1_UPI2_RSVD_CA12"
					( Origin gPackager )
				)
				( objectStatus "TP_CPU1_UPI2_RSVD_CA12" )
			)
			( signal "@baseboard_fab2_lib.baseboard_fab2(sch_1):tp_cpu1_upi2_rsvd_cb11"
				( attribute "CDS_PHYS_NET_NAME" "TP_CPU1_UPI2_RSVD_CB11"
					( Origin gPackager )
				)
				( objectStatus "TP_CPU1_UPI2_RSVD_CB11" )
			)
			( signal "@baseboard_fab2_lib.baseboard_fab2(sch_1):tp_cpu1_upi2_rsvd_cc10"
				( attribute "CDS_PHYS_NET_NAME" "TP_CPU1_UPI2_RSVD_CC10"
					( Origin gPackager )
				)
				( objectStatus "TP_CPU1_UPI2_RSVD_CC10" )
			)
			( signal "@baseboard_fab2_lib.baseboard_fab2(sch_1):tp_cpu1_upi2_rsvd_cc12"
				( attribute "CDS_PHYS_NET_NAME" "TP_CPU1_UPI2_RSVD_CC12"
					( Origin gPackager )
				)
				( objectStatus "TP_CPU1_UPI2_RSVD_CC12" )
			)
			( signal "@baseboard_fab2_lib.baseboard_fab2(sch_1):tp_cpu1_upi2_rsvd_cd11"
				( attribute "CDS_PHYS_NET_NAME" "TP_CPU1_UPI2_RSVD_CD11"
					( Origin gPackager )
				)
				( objectStatus "TP_CPU1_UPI2_RSVD_CD11" )
			)
			( signal "@baseboard_fab2_lib.baseboard_fab2(sch_1):tp_cpu1_upi2_rsvd_ce12"
				( attribute "CDS_PHYS_NET_NAME" "TP_CPU1_UPI2_RSVD_CE12"
					( Origin gPackager )
				)
				( objectStatus "TP_CPU1_UPI2_RSVD_CE12" )
			)
			( signal "@baseboard_fab2_lib.baseboard_fab2(sch_1):tp_cpu1_upi2_rsvd_cf11"
				( attribute "CDS_PHYS_NET_NAME" "TP_CPU1_UPI2_RSVD_CF11"
					( Origin gPackager )
				)
				( objectStatus "TP_CPU1_UPI2_RSVD_CF11" )
			)
			( signal "@baseboard_fab2_lib.baseboard_fab2(sch_1):tp_cpu1_upi2_rsvd_cf13"
				( attribute "CDS_PHYS_NET_NAME" "TP_CPU1_UPI2_RSVD_CF13"
					( Origin gPackager )
				)
				( objectStatus "TP_CPU1_UPI2_RSVD_CF13" )
			)
			( signal "@baseboard_fab2_lib.baseboard_fab2(sch_1):tp_cpu1_upi2_rsvd_cg12"
				( attribute "CDS_PHYS_NET_NAME" "TP_CPU1_UPI2_RSVD_CG12"
					( Origin gPackager )
				)
				( objectStatus "TP_CPU1_UPI2_RSVD_CG12" )
			)
			( signal "@baseboard_fab2_lib.baseboard_fab2(sch_1):tp_cpu1_upi2_rsvd_ch11"
				( attribute "CDS_PHYS_NET_NAME" "TP_CPU1_UPI2_RSVD_CH11"
					( Origin gPackager )
				)
				( objectStatus "TP_CPU1_UPI2_RSVD_CH11" )
			)
			( signal "@baseboard_fab2_lib.baseboard_fab2(sch_1):tp_cpu1_upi2_rsvd_ch13"
				( attribute "CDS_PHYS_NET_NAME" "TP_CPU1_UPI2_RSVD_CH13"
					( Origin gPackager )
				)
				( objectStatus "TP_CPU1_UPI2_RSVD_CH13" )
			)
			( signal "@baseboard_fab2_lib.baseboard_fab2(sch_1):tp_cpu1_upi2_rsvd_cj14"
				( attribute "CDS_PHYS_NET_NAME" "TP_CPU1_UPI2_RSVD_CJ14"
					( Origin gPackager )
				)
				( objectStatus "TP_CPU1_UPI2_RSVD_CJ14" )
			)
			( signal "@baseboard_fab2_lib.baseboard_fab2(sch_1):tp_cpu1_upi2_rsvd_ck13"
				( attribute "CDS_PHYS_NET_NAME" "TP_CPU1_UPI2_RSVD_CK13"
					( Origin gPackager )
				)
				( objectStatus "TP_CPU1_UPI2_RSVD_CK13" )
			)
			( signal "@baseboard_fab2_lib.baseboard_fab2(sch_1):tp_cpu1_upi2_rsvd_cm13"
				( attribute "CDS_PHYS_NET_NAME" "TP_CPU1_UPI2_RSVD_CM13"
					( Origin gPackager )
				)
				( objectStatus "TP_CPU1_UPI2_RSVD_CM13" )
			)
			( signal "@baseboard_fab2_lib.baseboard_fab2(sch_1):tp_cpu1_upi2_rsvd_cr14"
				( attribute "CDS_PHYS_NET_NAME" "TP_CPU1_UPI2_RSVD_CR14"
					( Origin gPackager )
				)
				( objectStatus "TP_CPU1_UPI2_RSVD_CR14" )
			)
			( signal "@baseboard_fab2_lib.baseboard_fab2(sch_1):tp_cpu1_upi2_rsvd_cu14"
				( attribute "CDS_PHYS_NET_NAME" "TP_CPU1_UPI2_RSVD_CU14"
					( Origin gPackager )
				)
				( objectStatus "TP_CPU1_UPI2_RSVD_CU14" )
			)
			( signal "@baseboard_fab2_lib.baseboard_fab2(sch_1):tp_cpu1_upi2_rsvd_cv13"
				( attribute "CDS_PHYS_NET_NAME" "TP_CPU1_UPI2_RSVD_CV13"
					( Origin gPackager )
				)
				( objectStatus "TP_CPU1_UPI2_RSVD_CV13" )
			)
			( signal "@baseboard_fab2_lib.baseboard_fab2(sch_1):tp_cpu1_upi2_rsvd_cw14"
				( attribute "CDS_PHYS_NET_NAME" "TP_CPU1_UPI2_RSVD_CW14"
					( Origin gPackager )
				)
				( objectStatus "TP_CPU1_UPI2_RSVD_CW14" )
			)
			( signal "@baseboard_fab2_lib.baseboard_fab2(sch_1):tp_cpu1_upi2_rsvd_cw16"
				( attribute "CDS_PHYS_NET_NAME" "TP_CPU1_UPI2_RSVD_CW16"
					( Origin gPackager )
				)
				( objectStatus "TP_CPU1_UPI2_RSVD_CW16" )
			)
			( signal "@baseboard_fab2_lib.baseboard_fab2(sch_1):tp_cpu1_upi2_rsvd_da16"
				( attribute "CDS_PHYS_NET_NAME" "TP_CPU1_UPI2_RSVD_DA16"
					( Origin gPackager )
				)
				( objectStatus "TP_CPU1_UPI2_RSVD_DA16" )
			)
			( signal "@baseboard_fab2_lib.baseboard_fab2(sch_1):tp_cpu1_upi2_rsvd_db15"
				( attribute "CDS_PHYS_NET_NAME" "TP_CPU1_UPI2_RSVD_DB15"
					( Origin gPackager )
				)
				( objectStatus "TP_CPU1_UPI2_RSVD_DB15" )
			)
			( signal "@baseboard_fab2_lib.baseboard_fab2(sch_1):tp_cpu1_upi2_rsvd_dc16"
				( attribute "CDS_PHYS_NET_NAME" "TP_CPU1_UPI2_RSVD_DC16"
					( Origin gPackager )
				)
				( objectStatus "TP_CPU1_UPI2_RSVD_DC16" )
			)
			( signal "@baseboard_fab2_lib.baseboard_fab2(sch_1):tp_cpu1_upi2_rsvd_dd15"
				( attribute "CDS_PHYS_NET_NAME" "TP_CPU1_UPI2_RSVD_DD15"
					( Origin gPackager )
				)
				( objectStatus "TP_CPU1_UPI2_RSVD_DD15" )
			)
			( signal "@baseboard_fab2_lib.baseboard_fab2(sch_1):tp_cpu1_upi2_rsvd_dd17"
				( attribute "CDS_PHYS_NET_NAME" "TP_CPU1_UPI2_RSVD_DD17"
					( Origin gPackager )
				)
				( objectStatus "TP_CPU1_UPI2_RSVD_DD17" )
			)
			( signal "@baseboard_fab2_lib.baseboard_fab2(sch_1):tp_cpu1_upi2_rsvd_de16"
				( attribute "CDS_PHYS_NET_NAME" "TP_CPU1_UPI2_RSVD_DE16"
					( Origin gPackager )
				)
				( objectStatus "TP_CPU1_UPI2_RSVD_DE16" )
			)
			( signal "@baseboard_fab2_lib.baseboard_fab2(sch_1):tp_cpu1_upi2_rsvd_df15"
				( attribute "CDS_PHYS_NET_NAME" "TP_CPU1_UPI2_RSVD_DF15"
					( Origin gPackager )
				)
				( objectStatus "TP_CPU1_UPI2_RSVD_DF15" )
			)
			( signal "@baseboard_fab2_lib.baseboard_fab2(sch_1):tp_cpu1_upi2_rsvd_df17"
				( attribute "CDS_PHYS_NET_NAME" "TP_CPU1_UPI2_RSVD_DF17"
					( Origin gPackager )
				)
				( objectStatus "TP_CPU1_UPI2_RSVD_DF17" )
			)
			( signal "@baseboard_fab2_lib.baseboard_fab2(sch_1):tp_cpu1_upi2_rsvd_dg18"
				( attribute "CDS_PHYS_NET_NAME" "TP_CPU1_UPI2_RSVD_DG18"
					( Origin gPackager )
				)
				( objectStatus "TP_CPU1_UPI2_RSVD_DG18" )
			)
			( signal "@baseboard_fab2_lib.baseboard_fab2(sch_1):tp_cpu1_upi2_rsvd_dg20"
				( attribute "CDS_PHYS_NET_NAME" "TP_CPU1_UPI2_RSVD_DG20"
					( Origin gPackager )
				)
				( objectStatus "TP_CPU1_UPI2_RSVD_DG20" )
			)
			( signal "@baseboard_fab2_lib.baseboard_fab2(sch_1):tp_cpu1_upi2_rsvd_dh17"
				( attribute "CDS_PHYS_NET_NAME" "TP_CPU1_UPI2_RSVD_DH17"
					( Origin gPackager )
				)
				( objectStatus "TP_CPU1_UPI2_RSVD_DH17" )
			)
			( signal "@baseboard_fab2_lib.baseboard_fab2(sch_1):tp_cpu1_upi2_rsvd_dh19"
				( attribute "CDS_PHYS_NET_NAME" "TP_CPU1_UPI2_RSVD_DH19"
					( Origin gPackager )
				)
				( objectStatus "TP_CPU1_UPI2_RSVD_DH19" )
			)
			( signal "@baseboard_fab2_lib.baseboard_fab2(sch_1):tp_cpu1_upi2_rsvd_dj18"
				( attribute "CDS_PHYS_NET_NAME" "TP_CPU1_UPI2_RSVD_DJ18"
					( Origin gPackager )
				)
				( objectStatus "TP_CPU1_UPI2_RSVD_DJ18" )
			)
			( signal "@baseboard_fab2_lib.baseboard_fab2(sch_1):tp_cpu1_upi2_rsvd_dj20"
				( attribute "CDS_PHYS_NET_NAME" "TP_CPU1_UPI2_RSVD_DJ20"
					( Origin gPackager )
				)
				( objectStatus "TP_CPU1_UPI2_RSVD_DJ20" )
			)
			( signal "@baseboard_fab2_lib.baseboard_fab2(sch_1):tp_cpu1_upi2_rsvd_dk17"
				( attribute "CDS_PHYS_NET_NAME" "TP_CPU1_UPI2_RSVD_DK17"
					( Origin gPackager )
				)
				( objectStatus "TP_CPU1_UPI2_RSVD_DK17" )
			)
			( signal "@baseboard_fab2_lib.baseboard_fab2(sch_1):tp_cpu1_upi2_rsvd_dk19"
				( attribute "CDS_PHYS_NET_NAME" "TP_CPU1_UPI2_RSVD_DK19"
					( Origin gPackager )
				)
				( objectStatus "TP_CPU1_UPI2_RSVD_DK19" )
			)
			( signal "@baseboard_fab2_lib.baseboard_fab2(sch_1):tp_cpu1_upi2_rsvd_dl20"
				( attribute "CDS_PHYS_NET_NAME" "TP_CPU1_UPI2_RSVD_DL20"
					( Origin gPackager )
				)
				( objectStatus "TP_CPU1_UPI2_RSVD_DL20" )
			)
			( signal "@baseboard_fab2_lib.baseboard_fab2(sch_1):tp_cpu1_upi2_rsvd_dm21"
				( attribute "CDS_PHYS_NET_NAME" "TP_CPU1_UPI2_RSVD_DM21"
					( Origin gPackager )
				)
				( objectStatus "TP_CPU1_UPI2_RSVD_DM21" )
			)
			( signal "@baseboard_fab2_lib.baseboard_fab2(sch_1):tp_cpu1_upi2_rsvd_dn20"
				( attribute "CDS_PHYS_NET_NAME" "TP_CPU1_UPI2_RSVD_DN20"
					( Origin gPackager )
				)
				( objectStatus "TP_CPU1_UPI2_RSVD_DN20" )
			)
			( signal "@baseboard_fab2_lib.baseboard_fab2(sch_1):tp_cpu1_upi2_rsvd_dp21"
				( attribute "CDS_PHYS_NET_NAME" "TP_CPU1_UPI2_RSVD_DP21"
					( Origin gPackager )
				)
				( objectStatus "TP_CPU1_UPI2_RSVD_DP21" )
			)
			( signal "@baseboard_fab2_lib.baseboard_fab2(sch_1):tp_cpu1_upi2_rsvd_dt21"
				( attribute "CDS_PHYS_NET_NAME" "TP_CPU1_UPI2_RSVD_DT21"
					( Origin gPackager )
				)
				( objectStatus "TP_CPU1_UPI2_RSVD_DT21" )
			)
			( signal "@baseboard_fab2_lib.baseboard_fab2(sch_1):clk_100m_cpu1_rc_refclk1_dn"
				( attribute "CDS_PHYS_NET_NAME" "CLK_100M_CPU1_RC_REFCLK1_DN"
					( Origin gPackager )
				)
				( objectStatus "CLK_100M_CPU1_RC_REFCLK1_DN" )
			)
			( signal "@baseboard_fab2_lib.baseboard_fab2(sch_1):clk_100m_cpu1_rc_refclk1_dp"
				( attribute "CDS_PHYS_NET_NAME" "CLK_100M_CPU1_RC_REFCLK1_DP"
					( Origin gPackager )
				)
				( objectStatus "CLK_100M_CPU1_RC_REFCLK1_DP" )
			)
			( signal "@baseboard_fab2_lib.baseboard_fab2(sch_1):tp_cpu1_rsvd_100"
				( attribute "CDS_PHYS_NET_NAME" "TP_CPU1_RSVD_100"
					( Origin gPackager )
				)
				( objectStatus "TP_CPU1_RSVD_100" )
			)
			( signal "@baseboard_fab2_lib.baseboard_fab2(sch_1):tp_cpu1_rsvd_101"
				( attribute "CDS_PHYS_NET_NAME" "TP_CPU1_RSVD_101"
					( Origin gPackager )
				)
				( objectStatus "TP_CPU1_RSVD_101" )
			)
			( signal "@baseboard_fab2_lib.baseboard_fab2(sch_1):tp_cpu1_rsvd_105"
				( attribute "CDS_PHYS_NET_NAME" "TP_CPU1_RSVD_105"
					( Origin gPackager )
				)
				( objectStatus "TP_CPU1_RSVD_105" )
			)
			( signal "@baseboard_fab2_lib.baseboard_fab2(sch_1):tp_cpu1_rsvd_106"
				( attribute "CDS_PHYS_NET_NAME" "TP_CPU1_RSVD_106"
					( Origin gPackager )
				)
				( objectStatus "TP_CPU1_RSVD_106" )
			)
			( signal "@baseboard_fab2_lib.baseboard_fab2(sch_1):tp_cpu1_rsvd_108"
				( attribute "CDS_PHYS_NET_NAME" "TP_CPU1_RSVD_108"
					( Origin gPackager )
				)
				( objectStatus "TP_CPU1_RSVD_108" )
			)
			( signal "@baseboard_fab2_lib.baseboard_fab2(sch_1):tp_cpu1_rsvd_111"
				( attribute "CDS_PHYS_NET_NAME" "TP_CPU1_RSVD_111"
					( Origin gPackager )
				)
				( objectStatus "TP_CPU1_RSVD_111" )
			)
			( signal "@baseboard_fab2_lib.baseboard_fab2(sch_1):tp_cpu1_rsvd_113"
				( attribute "CDS_PHYS_NET_NAME" "TP_CPU1_RSVD_113"
					( Origin gPackager )
				)
				( objectStatus "TP_CPU1_RSVD_113" )
			)
			( signal "@baseboard_fab2_lib.baseboard_fab2(sch_1):tp_cpu1_rsvd_114"
				( attribute "CDS_PHYS_NET_NAME" "TP_CPU1_RSVD_114"
					( Origin gPackager )
				)
				( objectStatus "TP_CPU1_RSVD_114" )
			)
			( signal "@baseboard_fab2_lib.baseboard_fab2(sch_1):tp_cpu1_rsvd_117"
				( attribute "CDS_PHYS_NET_NAME" "TP_CPU1_RSVD_117"
					( Origin gPackager )
				)
				( objectStatus "TP_CPU1_RSVD_117" )
			)
			( signal "@baseboard_fab2_lib.baseboard_fab2(sch_1):tp_cpu1_rsvd_119"
				( attribute "CDS_PHYS_NET_NAME" "TP_CPU1_RSVD_119"
					( Origin gPackager )
				)
				( objectStatus "TP_CPU1_RSVD_119" )
			)
			( signal "@baseboard_fab2_lib.baseboard_fab2(sch_1):tp_cpu1_rsvd_121"
				( attribute "CDS_PHYS_NET_NAME" "TP_CPU1_RSVD_121"
					( Origin gPackager )
				)
				( objectStatus "TP_CPU1_RSVD_121" )
			)
			( signal "@baseboard_fab2_lib.baseboard_fab2(sch_1):tp_cpu1_rsvd_123"
				( attribute "CDS_PHYS_NET_NAME" "TP_CPU1_RSVD_123"
					( Origin gPackager )
				)
				( objectStatus "TP_CPU1_RSVD_123" )
			)
			( signal "@baseboard_fab2_lib.baseboard_fab2(sch_1):tp_cpu1_rsvd_124"
				( attribute "CDS_PHYS_NET_NAME" "TP_CPU1_RSVD_124"
					( Origin gPackager )
				)
				( objectStatus "TP_CPU1_RSVD_124" )
			)
			( signal "@baseboard_fab2_lib.baseboard_fab2(sch_1):tp_cpu1_rsvd_144"
				( attribute "CDS_PHYS_NET_NAME" "TP_CPU1_RSVD_144"
					( Origin gPackager )
				)
				( objectStatus "TP_CPU1_RSVD_144" )
			)
			( signal "@baseboard_fab2_lib.baseboard_fab2(sch_1):tp_cpu1_rsvd_145"
				( attribute "CDS_PHYS_NET_NAME" "TP_CPU1_RSVD_145"
					( Origin gPackager )
				)
				( objectStatus "TP_CPU1_RSVD_145" )
			)
			( signal "@baseboard_fab2_lib.baseboard_fab2(sch_1):tp_cpu1_rsvd_146"
				( attribute "CDS_PHYS_NET_NAME" "TP_CPU1_RSVD_146"
					( Origin gPackager )
				)
				( objectStatus "TP_CPU1_RSVD_146" )
			)
			( signal "@baseboard_fab2_lib.baseboard_fab2(sch_1):tp_cpu1_rsvd_147"
				( attribute "CDS_PHYS_NET_NAME" "TP_CPU1_RSVD_147"
					( Origin gPackager )
				)
				( objectStatus "TP_CPU1_RSVD_147" )
			)
			( signal "@baseboard_fab2_lib.baseboard_fab2(sch_1):tp_cpu1_rsvd_148"
				( attribute "CDS_PHYS_NET_NAME" "TP_CPU1_RSVD_148"
					( Origin gPackager )
				)
				( objectStatus "TP_CPU1_RSVD_148" )
			)
			( signal "@baseboard_fab2_lib.baseboard_fab2(sch_1):tp_cpu1_rsvd_149"
				( attribute "CDS_PHYS_NET_NAME" "TP_CPU1_RSVD_149"
					( Origin gPackager )
				)
				( objectStatus "TP_CPU1_RSVD_149" )
			)
			( signal "@baseboard_fab2_lib.baseboard_fab2(sch_1):tp_cpu1_rsvd_150"
				( attribute "CDS_PHYS_NET_NAME" "TP_CPU1_RSVD_150"
					( Origin gPackager )
				)
				( objectStatus "TP_CPU1_RSVD_150" )
			)
			( signal "@baseboard_fab2_lib.baseboard_fab2(sch_1):tp_cpu1_rsvd_151"
				( attribute "CDS_PHYS_NET_NAME" "TP_CPU1_RSVD_151"
					( Origin gPackager )
				)
				( objectStatus "TP_CPU1_RSVD_151" )
			)
			( signal "@baseboard_fab2_lib.baseboard_fab2(sch_1):tp_cpu1_rsvd_152"
				( attribute "CDS_PHYS_NET_NAME" "TP_CPU1_RSVD_152"
					( Origin gPackager )
				)
				( objectStatus "TP_CPU1_RSVD_152" )
			)
			( signal "@baseboard_fab2_lib.baseboard_fab2(sch_1):tp_cpu1_rsvd_154"
				( attribute "CDS_PHYS_NET_NAME" "TP_CPU1_RSVD_154"
					( Origin gPackager )
				)
				( objectStatus "TP_CPU1_RSVD_154" )
			)
			( signal "@baseboard_fab2_lib.baseboard_fab2(sch_1):tp_cpu1_rsvd_155"
				( attribute "CDS_PHYS_NET_NAME" "TP_CPU1_RSVD_155"
					( Origin gPackager )
				)
				( objectStatus "TP_CPU1_RSVD_155" )
			)
			( signal "@baseboard_fab2_lib.baseboard_fab2(sch_1):tp_cpu1_rsvd_156"
				( attribute "CDS_PHYS_NET_NAME" "TP_CPU1_RSVD_156"
					( Origin gPackager )
				)
				( objectStatus "TP_CPU1_RSVD_156" )
			)
			( signal "@baseboard_fab2_lib.baseboard_fab2(sch_1):tp_cpu1_rsvd_157"
				( attribute "CDS_PHYS_NET_NAME" "TP_CPU1_RSVD_157"
					( Origin gPackager )
				)
				( objectStatus "TP_CPU1_RSVD_157" )
			)
			( signal "@baseboard_fab2_lib.baseboard_fab2(sch_1):tp_cpu1_rsvd_158"
				( attribute "CDS_PHYS_NET_NAME" "TP_CPU1_RSVD_158"
					( Origin gPackager )
				)
				( objectStatus "TP_CPU1_RSVD_158" )
			)
			( signal "@baseboard_fab2_lib.baseboard_fab2(sch_1):tp_cpu1_rsvd_159"
				( attribute "CDS_PHYS_NET_NAME" "TP_CPU1_RSVD_159"
					( Origin gPackager )
				)
				( objectStatus "TP_CPU1_RSVD_159" )
			)
			( signal "@baseboard_fab2_lib.baseboard_fab2(sch_1):tp_cpu1_rsvd_160"
				( attribute "CDS_PHYS_NET_NAME" "TP_CPU1_RSVD_160"
					( Origin gPackager )
				)
				( objectStatus "TP_CPU1_RSVD_160" )
			)
			( signal "@baseboard_fab2_lib.baseboard_fab2(sch_1):tp_cpu1_rsvd_161"
				( attribute "CDS_PHYS_NET_NAME" "TP_CPU1_RSVD_161"
					( Origin gPackager )
				)
				( objectStatus "TP_CPU1_RSVD_161" )
			)
			( signal "@baseboard_fab2_lib.baseboard_fab2(sch_1):tp_cpu1_rsvd_162"
				( attribute "CDS_PHYS_NET_NAME" "TP_CPU1_RSVD_162"
					( Origin gPackager )
				)
				( objectStatus "TP_CPU1_RSVD_162" )
			)
			( signal "@baseboard_fab2_lib.baseboard_fab2(sch_1):tp_cpu1_rsvd_163"
				( attribute "CDS_PHYS_NET_NAME" "TP_CPU1_RSVD_163"
					( Origin gPackager )
				)
				( objectStatus "TP_CPU1_RSVD_163" )
			)
			( signal "@baseboard_fab2_lib.baseboard_fab2(sch_1):tp_cpu1_rsvd_164"
				( attribute "CDS_PHYS_NET_NAME" "TP_CPU1_RSVD_164"
					( Origin gPackager )
				)
				( objectStatus "TP_CPU1_RSVD_164" )
			)
			( signal "@baseboard_fab2_lib.baseboard_fab2(sch_1):tp_cpu1_rsvd_166"
				( attribute "CDS_PHYS_NET_NAME" "TP_CPU1_RSVD_166"
					( Origin gPackager )
				)
				( objectStatus "TP_CPU1_RSVD_166" )
			)
			( signal "@baseboard_fab2_lib.baseboard_fab2(sch_1):tp_cpu1_rsvd_167"
				( attribute "CDS_PHYS_NET_NAME" "TP_CPU1_RSVD_167"
					( Origin gPackager )
				)
				( objectStatus "TP_CPU1_RSVD_167" )
			)
			( signal "@baseboard_fab2_lib.baseboard_fab2(sch_1):tp_cpu1_rsvd_168"
				( attribute "CDS_PHYS_NET_NAME" "TP_CPU1_RSVD_168"
					( Origin gPackager )
				)
				( objectStatus "TP_CPU1_RSVD_168" )
			)
			( signal "@baseboard_fab2_lib.baseboard_fab2(sch_1):tp_cpu1_rsvd_169"
				( attribute "CDS_PHYS_NET_NAME" "TP_CPU1_RSVD_169"
					( Origin gPackager )
				)
				( objectStatus "TP_CPU1_RSVD_169" )
			)
			( signal "@baseboard_fab2_lib.baseboard_fab2(sch_1):tp_cpu1_rsvd_170"
				( attribute "CDS_PHYS_NET_NAME" "TP_CPU1_RSVD_170"
					( Origin gPackager )
				)
				( objectStatus "TP_CPU1_RSVD_170" )
			)
			( signal "@baseboard_fab2_lib.baseboard_fab2(sch_1):tp_cpu1_rsvd_171"
				( attribute "CDS_PHYS_NET_NAME" "TP_CPU1_RSVD_171"
					( Origin gPackager )
				)
				( objectStatus "TP_CPU1_RSVD_171" )
			)
			( signal "@baseboard_fab2_lib.baseboard_fab2(sch_1):tp_cpu1_rsvd_255"
				( attribute "CDS_PHYS_NET_NAME" "TP_CPU1_RSVD_255"
					( Origin gPackager )
				)
				( objectStatus "TP_CPU1_RSVD_255" )
			)
			( signal "@baseboard_fab2_lib.baseboard_fab2(sch_1):tp_cpu1_rsvd_82"
				( attribute "CDS_PHYS_NET_NAME" "TP_CPU1_RSVD_82"
					( Origin gPackager )
				)
				( objectStatus "TP_CPU1_RSVD_82" )
			)
			( signal "@baseboard_fab2_lib.baseboard_fab2(sch_1):tp_cpu1_rsvd_85"
				( attribute "CDS_PHYS_NET_NAME" "TP_CPU1_RSVD_85"
					( Origin gPackager )
				)
				( objectStatus "TP_CPU1_RSVD_85" )
			)
			( signal "@baseboard_fab2_lib.baseboard_fab2(sch_1):tp_cpu1_rsvd_90"
				( attribute "CDS_PHYS_NET_NAME" "TP_CPU1_RSVD_90"
					( Origin gPackager )
				)
				( objectStatus "TP_CPU1_RSVD_90" )
			)
			( signal "@baseboard_fab2_lib.baseboard_fab2(sch_1):tp_cpu1_rsvd_91"
				( attribute "CDS_PHYS_NET_NAME" "TP_CPU1_RSVD_91"
					( Origin gPackager )
				)
				( objectStatus "TP_CPU1_RSVD_91" )
			)
			( signal "@baseboard_fab2_lib.baseboard_fab2(sch_1):tp_cpu1_rsvd_94"
				( attribute "CDS_PHYS_NET_NAME" "TP_CPU1_RSVD_94"
					( Origin gPackager )
				)
				( objectStatus "TP_CPU1_RSVD_94" )
			)
			( signal "@baseboard_fab2_lib.baseboard_fab2(sch_1):tp_cpu1_rsvd_95"
				( attribute "CDS_PHYS_NET_NAME" "TP_CPU1_RSVD_95"
					( Origin gPackager )
				)
				( objectStatus "TP_CPU1_RSVD_95" )
			)
			( signal "@baseboard_fab2_lib.baseboard_fab2(sch_1):tp_cpu1_rsvd_97"
				( attribute "CDS_PHYS_NET_NAME" "TP_CPU1_RSVD_97"
					( Origin gPackager )
				)
				( objectStatus "TP_CPU1_RSVD_97" )
			)
			( signal "@baseboard_fab2_lib.baseboard_fab2(sch_1):tp_cpu1_rsvd_99"
				( attribute "CDS_PHYS_NET_NAME" "TP_CPU1_RSVD_99"
					( Origin gPackager )
				)
				( objectStatus "TP_CPU1_RSVD_99" )
			)
			( signal "@baseboard_fab2_lib.baseboard_fab2(sch_1):tp_cpu1_test_10"
				( attribute "CDS_PHYS_NET_NAME" "TP_CPU1_TEST_10"
					( Origin gPackager )
				)
				( objectStatus "TP_CPU1_TEST_10" )
			)
			( signal "@baseboard_fab2_lib.baseboard_fab2(sch_1):tp_cpu1_test_6"
				( attribute "CDS_PHYS_NET_NAME" "TP_CPU1_TEST_6"
					( Origin gPackager )
				)
				( objectStatus "TP_CPU1_TEST_6" )
			)
			( signal "@baseboard_fab2_lib.baseboard_fab2(sch_1):tp_cpu1_test_7"
				( attribute "CDS_PHYS_NET_NAME" "TP_CPU1_TEST_7"
					( Origin gPackager )
				)
				( objectStatus "TP_CPU1_TEST_7" )
			)
			( signal "@baseboard_fab2_lib.baseboard_fab2(sch_1):tp_cpu1_test_8"
				( attribute "CDS_PHYS_NET_NAME" "TP_CPU1_TEST_8"
					( Origin gPackager )
				)
				( objectStatus "TP_CPU1_TEST_8" )
			)
			( signal "@baseboard_fab2_lib.baseboard_fab2(sch_1):tp_cpu1_test_9"
				( attribute "CDS_PHYS_NET_NAME" "TP_CPU1_TEST_9"
					( Origin gPackager )
				)
				( objectStatus "TP_CPU1_TEST_9" )
			)
			( signal "@baseboard_fab2_lib.baseboard_fab2(sch_1):pvccin_cpu1"
				( alias ( signalRef "@baseboard_fab2_lib.baseboard_fab2(sch_1):page71_pvccin_cpu1") )
				( alias ( signalRef "@baseboard_fab2_lib.baseboard_fab2(sch_1):page76_pvccin_cpu1") )
				( alias ( signalRef "@baseboard_fab2_lib.baseboard_fab2(sch_1):page207_pvccin_cpu1") )
				( alias ( signalRef "@baseboard_fab2_lib.baseboard_fab2(sch_1):page208_pvccin_cpu1") )
				( alias ( signalRef "@baseboard_fab2_lib.baseboard_fab2(sch_1):page209_pvccin_cpu1") )
				( attribute "VOLTAGE" "2.0V"
					( Units "uVoltage" "V" 1.000000)
					( Status sAliasFlattened )
					( Origin gFrontEnd )
				)
				( attribute "CDS_PHYS_NET_NAME" "PVCCIN_CPU1"
					( Origin gPackager )
				)
				( objectStatus "PVCCIN_CPU1" )
			)
			( signal "@baseboard_fab2_lib.baseboard_fab2(sch_1):page71_pvccin_cpu1"
				( attribute "VOLTAGE" "2.0V"
					( Units "uVoltage" "V" 1.000000)
					( Origin gFrontEnd )
				)
				( objectFlag fObjectAlias )
				( objectStatus "page71_pvccin_cpu1" )
			)
			( signal "@baseboard_fab2_lib.baseboard_fab2(sch_1):page76_pvccin_cpu1"
				( attribute "VOLTAGE" "2.0V"
					( Units "uVoltage" "V" 1.000000)
					( Origin gFrontEnd )
				)
				( objectFlag fObjectAlias )
				( objectStatus "page76_pvccin_cpu1" )
			)
			( signal "@baseboard_fab2_lib.baseboard_fab2(sch_1):page207_pvccin_cpu1"
				( attribute "VOLTAGE" "2.0V"
					( Units "uVoltage" "V" 1.000000)
					( Origin gFrontEnd )
				)
				( objectFlag fObjectAlias )
				( objectStatus "page207_pvccin_cpu1" )
			)
			( signal "@baseboard_fab2_lib.baseboard_fab2(sch_1):page208_pvccin_cpu1"
				( attribute "VOLTAGE" "2.0V"
					( Units "uVoltage" "V" 1.000000)
					( Origin gFrontEnd )
				)
				( objectFlag fObjectAlias )
				( objectStatus "page208_pvccin_cpu1" )
			)
			( signal "@baseboard_fab2_lib.baseboard_fab2(sch_1):page209_pvccin_cpu1"
				( attribute "VOLTAGE" "2.0V"
					( Units "uVoltage" "V" 1.000000)
					( Origin gFrontEnd )
				)
				( objectFlag fObjectAlias )
				( objectStatus "page209_pvccin_cpu1" )
			)
			( signal "@baseboard_fab2_lib.baseboard_fab2(sch_1):vsense_pmax_cpu1"
				( attribute "CDS_PHYS_NET_NAME" "VSENSE_PMAX_CPU1"
					( Origin gPackager )
				)
				( objectStatus "VSENSE_PMAX_CPU1" )
			)
			( signal "@baseboard_fab2_lib.baseboard_fab2(sch_1):vsense_pvccin_cpu1_skt_vrtn"
				( attribute "CDS_PHYS_NET_NAME" "VSENSE_PVCCIN_CPU1_SKT_VRTN"
					( Origin gPackager )
				)
				( objectStatus "VSENSE_PVCCIN_CPU1_SKT_VRTN" )
			)
			( signal "@baseboard_fab2_lib.baseboard_fab2(sch_1):vsense_pvccin_cpu1_skt_vsen"
				( attribute "CDS_PHYS_NET_NAME" "VSENSE_PVCCIN_CPU1_SKT_VSEN"
					( Origin gPackager )
				)
				( objectStatus "VSENSE_PVCCIN_CPU1_SKT_VSEN" )
			)
			( signal "@baseboard_fab2_lib.baseboard_fab2(sch_1):vsense_vccinr2pmax_cpu1"
				( attribute "CDS_PHYS_NET_NAME" "VSENSE_VCCINR2PMAX_CPU1"
					( Origin gPackager )
				)
				( objectStatus "VSENSE_VCCINR2PMAX_CPU1" )
			)
			( signal "@baseboard_fab2_lib.baseboard_fab2(sch_1):pvcciomcp_cpu1"
				( alias ( signalRef "@baseboard_fab2_lib.baseboard_fab2(sch_1):page72_pvcciomcp_cpu1") )
				( alias ( signalRef "@baseboard_fab2_lib.baseboard_fab2(sch_1):page193_pvcciomcp_cpu1") )
				( attribute "VOLTAGE" "+0.95V"
					( Units "uVoltage" "V" 1.000000)
					( Status sAliasFlattened )
					( Status sAliasConflict )
					( Origin gFrontEnd )
				)
				( attribute "CDS_PHYS_NET_NAME" "PVCCIOMCP_CPU1"
					( Origin gPackager )
				)
				( objectStatus "PVCCIOMCP_CPU1" )
			)
			( signal "@baseboard_fab2_lib.baseboard_fab2(sch_1):page72_pvcciomcp_cpu1"
				( attribute "VOLTAGE" "+0.95V"
					( Units "uVoltage" "V" 1.000000)
					( Origin gFrontEnd )
				)
				( objectFlag fObjectAlias )
				( objectStatus "page72_pvcciomcp_cpu1" )
			)
			( signal "@baseboard_fab2_lib.baseboard_fab2(sch_1):page193_pvcciomcp_cpu1"
				( attribute "VOLTAGE" "+0.95"
					( Units "uVoltage" "V" 1.000000)
					( Origin gFrontEnd )
				)
				( objectFlag fObjectAlias )
				( objectStatus "page193_pvcciomcp_cpu1" )
			)
			( signal "@baseboard_fab2_lib.baseboard_fab2(sch_1):pvddq_ghj"
				( alias ( signalRef "@baseboard_fab2_lib.baseboard_fab2(sch_1):page72_pvddq_ghj") )
				( alias ( signalRef "@baseboard_fab2_lib.baseboard_fab2(sch_1):page77_pvddq_ghj") )
				( alias ( signalRef "@baseboard_fab2_lib.baseboard_fab2(sch_1):page78_pvddq_ghj") )
				( alias ( signalRef "@baseboard_fab2_lib.baseboard_fab2(sch_1):page79_pvddq_ghj") )
				( alias ( signalRef "@baseboard_fab2_lib.baseboard_fab2(sch_1):page80_pvddq_ghj") )
				( alias ( signalRef "@baseboard_fab2_lib.baseboard_fab2(sch_1):page81_pvddq_ghj") )
				( alias ( signalRef "@baseboard_fab2_lib.baseboard_fab2(sch_1):page82_pvddq_ghj") )
				( alias ( signalRef "@baseboard_fab2_lib.baseboard_fab2(sch_1):page96_pvddq_ghj") )
				( alias ( signalRef "@baseboard_fab2_lib.baseboard_fab2(sch_1):page100_pvddq_ghj") )
				( alias ( signalRef "@baseboard_fab2_lib.baseboard_fab2(sch_1):page224_pvddq_ghj") )
				( alias ( signalRef "@baseboard_fab2_lib.baseboard_fab2(sch_1):page225_pvddq_ghj") )
				( alias ( signalRef "@baseboard_fab2_lib.baseboard_fab2(sch_1):page229_pvddq_ghj") )
				( alias ( signalRef "@baseboard_fab2_lib.baseboard_fab2(sch_1):page243_pvddq_ghj") )
				( attribute "VOLTAGE" "1.2V"
					( Units "uVoltage" "V" 1.000000)
					( Status sAliasFlattened )
					( Origin gFrontEnd )
				)
				( attribute "CDS_PHYS_NET_NAME" "PVDDQ_GHJ"
					( Origin gPackager )
				)
				( objectStatus "PVDDQ_GHJ" )
			)
			( signal "@baseboard_fab2_lib.baseboard_fab2(sch_1):page72_pvddq_ghj"
				( attribute "VOLTAGE" "1.2V"
					( Units "uVoltage" "V" 1.000000)
					( Origin gFrontEnd )
				)
				( objectFlag fObjectAlias )
				( objectStatus "page72_pvddq_ghj" )
			)
			( signal "@baseboard_fab2_lib.baseboard_fab2(sch_1):page77_pvddq_ghj"
				( attribute "VOLTAGE" "1.2V"
					( Units "uVoltage" "V" 1.000000)
					( Origin gFrontEnd )
				)
				( objectFlag fObjectAlias )
				( objectStatus "page77_pvddq_ghj" )
			)
			( signal "@baseboard_fab2_lib.baseboard_fab2(sch_1):page78_pvddq_ghj"
				( attribute "VOLTAGE" "1.2V"
					( Units "uVoltage" "V" 1.000000)
					( Origin gFrontEnd )
				)
				( objectFlag fObjectAlias )
				( objectStatus "page78_pvddq_ghj" )
			)
			( signal "@baseboard_fab2_lib.baseboard_fab2(sch_1):page79_pvddq_ghj"
				( attribute "VOLTAGE" "1.2V"
					( Units "uVoltage" "V" 1.000000)
					( Origin gFrontEnd )
				)
				( objectFlag fObjectAlias )
				( objectStatus "page79_pvddq_ghj" )
			)
			( signal "@baseboard_fab2_lib.baseboard_fab2(sch_1):page80_pvddq_ghj"
				( attribute "VOLTAGE" "1.2V"
					( Units "uVoltage" "V" 1.000000)
					( Origin gFrontEnd )
				)
				( objectFlag fObjectAlias )
				( objectStatus "page80_pvddq_ghj" )
			)
			( signal "@baseboard_fab2_lib.baseboard_fab2(sch_1):page81_pvddq_ghj"
				( attribute "VOLTAGE" "1.2V"
					( Units "uVoltage" "V" 1.000000)
					( Origin gFrontEnd )
				)
				( objectFlag fObjectAlias )
				( objectStatus "page81_pvddq_ghj" )
			)
			( signal "@baseboard_fab2_lib.baseboard_fab2(sch_1):page82_pvddq_ghj"
				( attribute "VOLTAGE" "1.2V"
					( Units "uVoltage" "V" 1.000000)
					( Origin gFrontEnd )
				)
				( objectFlag fObjectAlias )
				( objectStatus "page82_pvddq_ghj" )
			)
			( signal "@baseboard_fab2_lib.baseboard_fab2(sch_1):page96_pvddq_ghj"
				( attribute "VOLTAGE" "1.2V"
					( Units "uVoltage" "V" 1.000000)
					( Origin gFrontEnd )
				)
				( objectFlag fObjectAlias )
				( objectStatus "page96_pvddq_ghj" )
			)
			( signal "@baseboard_fab2_lib.baseboard_fab2(sch_1):page100_pvddq_ghj"
				( attribute "VOLTAGE" "1.2V"
					( Units "uVoltage" "V" 1.000000)
					( Origin gFrontEnd )
				)
				( objectFlag fObjectAlias )
				( objectStatus "page100_pvddq_ghj" )
			)
			( signal "@baseboard_fab2_lib.baseboard_fab2(sch_1):page224_pvddq_ghj"
				( attribute "VOLTAGE" "1.2V"
					( Units "uVoltage" "V" 1.000000)
					( Origin gFrontEnd )
				)
				( objectFlag fObjectAlias )
				( objectStatus "page224_pvddq_ghj" )
			)
			( signal "@baseboard_fab2_lib.baseboard_fab2(sch_1):page225_pvddq_ghj"
				( attribute "VOLTAGE" "1.2V"
					( Units "uVoltage" "V" 1.000000)
					( Origin gFrontEnd )
				)
				( objectFlag fObjectAlias )
				( objectStatus "page225_pvddq_ghj" )
			)
			( signal "@baseboard_fab2_lib.baseboard_fab2(sch_1):page229_pvddq_ghj"
				( attribute "VOLTAGE" "1.2V"
					( Units "uVoltage" "V" 1.000000)
					( Origin gFrontEnd )
				)
				( objectFlag fObjectAlias )
				( objectStatus "page229_pvddq_ghj" )
			)
			( signal "@baseboard_fab2_lib.baseboard_fab2(sch_1):page243_pvddq_ghj"
				( attribute "VOLTAGE" "1.2V"
					( Units "uVoltage" "V" 1.000000)
					( Origin gFrontEnd )
				)
				( objectFlag fObjectAlias )
				( objectStatus "page243_pvddq_ghj" )
			)
			( signal "@baseboard_fab2_lib.baseboard_fab2(sch_1):pvddq_klm"
				( alias ( signalRef "@baseboard_fab2_lib.baseboard_fab2(sch_1):page72_pvddq_klm") )
				( alias ( signalRef "@baseboard_fab2_lib.baseboard_fab2(sch_1):page83_pvddq_klm") )
				( alias ( signalRef "@baseboard_fab2_lib.baseboard_fab2(sch_1):page84_pvddq_klm") )
				( alias ( signalRef "@baseboard_fab2_lib.baseboard_fab2(sch_1):page85_pvddq_klm") )
				( alias ( signalRef "@baseboard_fab2_lib.baseboard_fab2(sch_1):page86_pvddq_klm") )
				( alias ( signalRef "@baseboard_fab2_lib.baseboard_fab2(sch_1):page87_pvddq_klm") )
				( alias ( signalRef "@baseboard_fab2_lib.baseboard_fab2(sch_1):page88_pvddq_klm") )
				( alias ( signalRef "@baseboard_fab2_lib.baseboard_fab2(sch_1):page96_pvddq_klm") )
				( alias ( signalRef "@baseboard_fab2_lib.baseboard_fab2(sch_1):page100_pvddq_klm") )
				( alias ( signalRef "@baseboard_fab2_lib.baseboard_fab2(sch_1):page227_pvddq_klm") )
				( alias ( signalRef "@baseboard_fab2_lib.baseboard_fab2(sch_1):page228_pvddq_klm") )
				( alias ( signalRef "@baseboard_fab2_lib.baseboard_fab2(sch_1):page230_pvddq_klm") )
				( alias ( signalRef "@baseboard_fab2_lib.baseboard_fab2(sch_1):page243_pvddq_klm") )
				( attribute "VOLTAGE" "1.2V"
					( Units "uVoltage" "V" 1.000000)
					( Status sAliasFlattened )
					( Origin gFrontEnd )
				)
				( attribute "CDS_PHYS_NET_NAME" "PVDDQ_KLM"
					( Origin gPackager )
				)
				( objectStatus "PVDDQ_KLM" )
			)
			( signal "@baseboard_fab2_lib.baseboard_fab2(sch_1):page72_pvddq_klm"
				( attribute "VOLTAGE" "1.2V"
					( Units "uVoltage" "V" 1.000000)
					( Origin gFrontEnd )
				)
				( objectFlag fObjectAlias )
				( objectStatus "page72_pvddq_klm" )
			)
			( signal "@baseboard_fab2_lib.baseboard_fab2(sch_1):page83_pvddq_klm"
				( attribute "VOLTAGE" "1.2V"
					( Units "uVoltage" "V" 1.000000)
					( Origin gFrontEnd )
				)
				( objectFlag fObjectAlias )
				( objectStatus "page83_pvddq_klm" )
			)
			( signal "@baseboard_fab2_lib.baseboard_fab2(sch_1):page84_pvddq_klm"
				( attribute "VOLTAGE" "1.2V"
					( Units "uVoltage" "V" 1.000000)
					( Origin gFrontEnd )
				)
				( objectFlag fObjectAlias )
				( objectStatus "page84_pvddq_klm" )
			)
			( signal "@baseboard_fab2_lib.baseboard_fab2(sch_1):page85_pvddq_klm"
				( attribute "VOLTAGE" "1.2V"
					( Units "uVoltage" "V" 1.000000)
					( Origin gFrontEnd )
				)
				( objectFlag fObjectAlias )
				( objectStatus "page85_pvddq_klm" )
			)
			( signal "@baseboard_fab2_lib.baseboard_fab2(sch_1):page86_pvddq_klm"
				( attribute "VOLTAGE" "1.2V"
					( Units "uVoltage" "V" 1.000000)
					( Origin gFrontEnd )
				)
				( objectFlag fObjectAlias )
				( objectStatus "page86_pvddq_klm" )
			)
			( signal "@baseboard_fab2_lib.baseboard_fab2(sch_1):page87_pvddq_klm"
				( attribute "VOLTAGE" "1.2V"
					( Units "uVoltage" "V" 1.000000)
					( Origin gFrontEnd )
				)
				( objectFlag fObjectAlias )
				( objectStatus "page87_pvddq_klm" )
			)
			( signal "@baseboard_fab2_lib.baseboard_fab2(sch_1):page88_pvddq_klm"
				( attribute "VOLTAGE" "1.2V"
					( Units "uVoltage" "V" 1.000000)
					( Origin gFrontEnd )
				)
				( objectFlag fObjectAlias )
				( objectStatus "page88_pvddq_klm" )
			)
			( signal "@baseboard_fab2_lib.baseboard_fab2(sch_1):page96_pvddq_klm"
				( attribute "VOLTAGE" "1.2V"
					( Units "uVoltage" "V" 1.000000)
					( Origin gFrontEnd )
				)
				( objectFlag fObjectAlias )
				( objectStatus "page96_pvddq_klm" )
			)
			( signal "@baseboard_fab2_lib.baseboard_fab2(sch_1):page100_pvddq_klm"
				( attribute "VOLTAGE" "1.2V"
					( Units "uVoltage" "V" 1.000000)
					( Origin gFrontEnd )
				)
				( objectFlag fObjectAlias )
				( objectStatus "page100_pvddq_klm" )
			)
			( signal "@baseboard_fab2_lib.baseboard_fab2(sch_1):page227_pvddq_klm"
				( attribute "VOLTAGE" "1.2V"
					( Units "uVoltage" "V" 1.000000)
					( Origin gFrontEnd )
				)
				( objectFlag fObjectAlias )
				( objectStatus "page227_pvddq_klm" )
			)
			( signal "@baseboard_fab2_lib.baseboard_fab2(sch_1):page228_pvddq_klm"
				( attribute "VOLTAGE" "1.2V"
					( Units "uVoltage" "V" 1.000000)
					( Origin gFrontEnd )
				)
				( objectFlag fObjectAlias )
				( objectStatus "page228_pvddq_klm" )
			)
			( signal "@baseboard_fab2_lib.baseboard_fab2(sch_1):page230_pvddq_klm"
				( attribute "VOLTAGE" "1.2V"
					( Units "uVoltage" "V" 1.000000)
					( Origin gFrontEnd )
				)
				( objectFlag fObjectAlias )
				( objectStatus "page230_pvddq_klm" )
			)
			( signal "@baseboard_fab2_lib.baseboard_fab2(sch_1):page243_pvddq_klm"
				( attribute "VOLTAGE" "1.2V"
					( Units "uVoltage" "V" 1.000000)
					( Origin gFrontEnd )
				)
				( objectFlag fObjectAlias )
				( objectStatus "page243_pvddq_klm" )
			)
			( signal "@baseboard_fab2_lib.baseboard_fab2(sch_1):pvpp_ghj"
				( alias ( signalRef "@baseboard_fab2_lib.baseboard_fab2(sch_1):page72_pvpp_ghj") )
				( alias ( signalRef "@baseboard_fab2_lib.baseboard_fab2(sch_1):page77_pvpp_ghj") )
				( alias ( signalRef "@baseboard_fab2_lib.baseboard_fab2(sch_1):page78_pvpp_ghj") )
				( alias ( signalRef "@baseboard_fab2_lib.baseboard_fab2(sch_1):page79_pvpp_ghj") )
				( alias ( signalRef "@baseboard_fab2_lib.baseboard_fab2(sch_1):page80_pvpp_ghj") )
				( alias ( signalRef "@baseboard_fab2_lib.baseboard_fab2(sch_1):page81_pvpp_ghj") )
				( alias ( signalRef "@baseboard_fab2_lib.baseboard_fab2(sch_1):page82_pvpp_ghj") )
				( alias ( signalRef "@baseboard_fab2_lib.baseboard_fab2(sch_1):page99_pvpp_ghj") )
				( alias ( signalRef "@baseboard_fab2_lib.baseboard_fab2(sch_1):page233_pvpp_ghj") )
				( attribute "VOLTAGE" "2.5V"
					( Units "uVoltage" "V" 1.000000)
					( Status sAliasFlattened )
					( Origin gFrontEnd )
				)
				( attribute "CDS_PHYS_NET_NAME" "PVPP_GHJ"
					( Origin gPackager )
				)
				( objectStatus "PVPP_GHJ" )
			)
			( signal "@baseboard_fab2_lib.baseboard_fab2(sch_1):page72_pvpp_ghj"
				( attribute "VOLTAGE" "2.5V"
					( Units "uVoltage" "V" 1.000000)
					( Origin gFrontEnd )
				)
				( objectFlag fObjectAlias )
				( objectStatus "page72_pvpp_ghj" )
			)
			( signal "@baseboard_fab2_lib.baseboard_fab2(sch_1):page77_pvpp_ghj"
				( attribute "VOLTAGE" "2.5V"
					( Units "uVoltage" "V" 1.000000)
					( Origin gFrontEnd )
				)
				( objectFlag fObjectAlias )
				( objectStatus "page77_pvpp_ghj" )
			)
			( signal "@baseboard_fab2_lib.baseboard_fab2(sch_1):page78_pvpp_ghj"
				( attribute "VOLTAGE" "2.5V"
					( Units "uVoltage" "V" 1.000000)
					( Origin gFrontEnd )
				)
				( objectFlag fObjectAlias )
				( objectStatus "page78_pvpp_ghj" )
			)
			( signal "@baseboard_fab2_lib.baseboard_fab2(sch_1):page79_pvpp_ghj"
				( attribute "VOLTAGE" "2.5V"
					( Units "uVoltage" "V" 1.000000)
					( Origin gFrontEnd )
				)
				( objectFlag fObjectAlias )
				( objectStatus "page79_pvpp_ghj" )
			)
			( signal "@baseboard_fab2_lib.baseboard_fab2(sch_1):page80_pvpp_ghj"
				( attribute "VOLTAGE" "2.5V"
					( Units "uVoltage" "V" 1.000000)
					( Origin gFrontEnd )
				)
				( objectFlag fObjectAlias )
				( objectStatus "page80_pvpp_ghj" )
			)
			( signal "@baseboard_fab2_lib.baseboard_fab2(sch_1):page81_pvpp_ghj"
				( attribute "VOLTAGE" "2.5V"
					( Units "uVoltage" "V" 1.000000)
					( Origin gFrontEnd )
				)
				( objectFlag fObjectAlias )
				( objectStatus "page81_pvpp_ghj" )
			)
			( signal "@baseboard_fab2_lib.baseboard_fab2(sch_1):page82_pvpp_ghj"
				( attribute "VOLTAGE" "2.5V"
					( Units "uVoltage" "V" 1.000000)
					( Origin gFrontEnd )
				)
				( objectFlag fObjectAlias )
				( objectStatus "page82_pvpp_ghj" )
			)
			( signal "@baseboard_fab2_lib.baseboard_fab2(sch_1):page99_pvpp_ghj"
				( attribute "VOLTAGE" "2.5V"
					( Units "uVoltage" "V" 1.000000)
					( Origin gFrontEnd )
				)
				( objectFlag fObjectAlias )
				( objectStatus "page99_pvpp_ghj" )
			)
			( signal "@baseboard_fab2_lib.baseboard_fab2(sch_1):page233_pvpp_ghj"
				( attribute "VOLTAGE" "2.5V"
					( Units "uVoltage" "V" 1.000000)
					( Origin gFrontEnd )
				)
				( objectFlag fObjectAlias )
				( objectStatus "page233_pvpp_ghj" )
			)
			( signal "@baseboard_fab2_lib.baseboard_fab2(sch_1):pvsa_cpu1"
				( alias ( signalRef "@baseboard_fab2_lib.baseboard_fab2(sch_1):page72_pvsa_cpu1") )
				( alias ( signalRef "@baseboard_fab2_lib.baseboard_fab2(sch_1):page76_pvsa_cpu1") )
				( alias ( signalRef "@baseboard_fab2_lib.baseboard_fab2(sch_1):page210_pvsa_cpu1") )
				( attribute "VOLTAGE" "1.1V"
					( Units "uVoltage" "V" 1.000000)
					( Status sAliasFlattened )
					( Origin gFrontEnd )
				)
				( attribute "CDS_PHYS_NET_NAME" "PVSA_CPU1"
					( Origin gPackager )
				)
				( objectStatus "PVSA_CPU1" )
			)
			( signal "@baseboard_fab2_lib.baseboard_fab2(sch_1):page72_pvsa_cpu1"
				( attribute "VOLTAGE" "1.1V"
					( Units "uVoltage" "V" 1.000000)
					( Origin gFrontEnd )
				)
				( objectFlag fObjectAlias )
				( objectStatus "page72_pvsa_cpu1" )
			)
			( signal "@baseboard_fab2_lib.baseboard_fab2(sch_1):page76_pvsa_cpu1"
				( attribute "VOLTAGE" "1.1V"
					( Units "uVoltage" "V" 1.000000)
					( Origin gFrontEnd )
				)
				( objectFlag fObjectAlias )
				( objectStatus "page76_pvsa_cpu1" )
			)
			( signal "@baseboard_fab2_lib.baseboard_fab2(sch_1):page210_pvsa_cpu1"
				( attribute "VOLTAGE" "1.1V"
					( Units "uVoltage" "V" 1.000000)
					( Origin gFrontEnd )
				)
				( objectFlag fObjectAlias )
				( objectStatus "page210_pvsa_cpu1" )
			)
			( signal "@baseboard_fab2_lib.baseboard_fab2(sch_1):pd_cpu1_mcp01_dmon"
				( attribute "CDS_PHYS_NET_NAME" "PD_CPU1_MCP01_DMON"
					( Origin gPackager )
				)
				( objectStatus "PD_CPU1_MCP01_DMON" )
			)
			( signal "@baseboard_fab2_lib.baseboard_fab2(sch_1):tp_cpu1_kti2_amonv"
				( attribute "CDS_PHYS_NET_NAME" "TP_CPU1_KTI2_AMONV"
					( Origin gPackager )
				)
				( objectStatus "TP_CPU1_KTI2_AMONV" )
			)
			( signal "@baseboard_fab2_lib.baseboard_fab2(sch_1):tp_cpu1_kti2_dfx_dn"
				( attribute "CDS_PHYS_NET_NAME" "TP_CPU1_KTI2_DFX_DN"
					( Origin gPackager )
				)
				( objectStatus "TP_CPU1_KTI2_DFX_DN" )
			)
			( signal "@baseboard_fab2_lib.baseboard_fab2(sch_1):tp_cpu1_rsvd_0"
				( attribute "CDS_PHYS_NET_NAME" "TP_CPU1_RSVD_0"
					( Origin gPackager )
				)
				( objectStatus "TP_CPU1_RSVD_0" )
			)
			( signal "@baseboard_fab2_lib.baseboard_fab2(sch_1):tp_cpu1_rsvd_1"
				( attribute "CDS_PHYS_NET_NAME" "TP_CPU1_RSVD_1"
					( Origin gPackager )
				)
				( objectStatus "TP_CPU1_RSVD_1" )
			)
			( signal "@baseboard_fab2_lib.baseboard_fab2(sch_1):tp_cpu1_rsvd_10"
				( attribute "CDS_PHYS_NET_NAME" "TP_CPU1_RSVD_10"
					( Origin gPackager )
				)
				( objectStatus "TP_CPU1_RSVD_10" )
			)
			( signal "@baseboard_fab2_lib.baseboard_fab2(sch_1):tp_cpu1_rsvd_11"
				( attribute "CDS_PHYS_NET_NAME" "TP_CPU1_RSVD_11"
					( Origin gPackager )
				)
				( objectStatus "TP_CPU1_RSVD_11" )
			)
			( signal "@baseboard_fab2_lib.baseboard_fab2(sch_1):tp_cpu1_rsvd_12"
				( attribute "CDS_PHYS_NET_NAME" "TP_CPU1_RSVD_12"
					( Origin gPackager )
				)
				( objectStatus "TP_CPU1_RSVD_12" )
			)
			( signal "@baseboard_fab2_lib.baseboard_fab2(sch_1):tp_cpu1_rsvd_13"
				( attribute "CDS_PHYS_NET_NAME" "TP_CPU1_RSVD_13"
					( Origin gPackager )
				)
				( objectStatus "TP_CPU1_RSVD_13" )
			)
			( signal "@baseboard_fab2_lib.baseboard_fab2(sch_1):tp_cpu1_rsvd_14"
				( attribute "CDS_PHYS_NET_NAME" "TP_CPU1_RSVD_14"
					( Origin gPackager )
				)
				( objectStatus "TP_CPU1_RSVD_14" )
			)
			( signal "@baseboard_fab2_lib.baseboard_fab2(sch_1):tp_cpu1_rsvd_15"
				( attribute "CDS_PHYS_NET_NAME" "TP_CPU1_RSVD_15"
					( Origin gPackager )
				)
				( objectStatus "TP_CPU1_RSVD_15" )
			)
			( signal "@baseboard_fab2_lib.baseboard_fab2(sch_1):tp_cpu1_rsvd_16"
				( attribute "CDS_PHYS_NET_NAME" "TP_CPU1_RSVD_16"
					( Origin gPackager )
				)
				( objectStatus "TP_CPU1_RSVD_16" )
			)
			( signal "@baseboard_fab2_lib.baseboard_fab2(sch_1):tp_cpu1_rsvd_17"
				( attribute "CDS_PHYS_NET_NAME" "TP_CPU1_RSVD_17"
					( Origin gPackager )
				)
				( objectStatus "TP_CPU1_RSVD_17" )
			)
			( signal "@baseboard_fab2_lib.baseboard_fab2(sch_1):tp_cpu1_rsvd_18"
				( attribute "CDS_PHYS_NET_NAME" "TP_CPU1_RSVD_18"
					( Origin gPackager )
				)
				( objectStatus "TP_CPU1_RSVD_18" )
			)
			( signal "@baseboard_fab2_lib.baseboard_fab2(sch_1):tp_cpu1_rsvd_19"
				( attribute "CDS_PHYS_NET_NAME" "TP_CPU1_RSVD_19"
					( Origin gPackager )
				)
				( objectStatus "TP_CPU1_RSVD_19" )
			)
			( signal "@baseboard_fab2_lib.baseboard_fab2(sch_1):tp_cpu1_rsvd_2"
				( attribute "CDS_PHYS_NET_NAME" "TP_CPU1_RSVD_2"
					( Origin gPackager )
				)
				( objectStatus "TP_CPU1_RSVD_2" )
			)
			( signal "@baseboard_fab2_lib.baseboard_fab2(sch_1):tp_cpu1_rsvd_20"
				( attribute "CDS_PHYS_NET_NAME" "TP_CPU1_RSVD_20"
					( Origin gPackager )
				)
				( objectStatus "TP_CPU1_RSVD_20" )
			)
			( signal "@baseboard_fab2_lib.baseboard_fab2(sch_1):tp_cpu1_rsvd_21"
				( attribute "CDS_PHYS_NET_NAME" "TP_CPU1_RSVD_21"
					( Origin gPackager )
				)
				( objectStatus "TP_CPU1_RSVD_21" )
			)
			( signal "@baseboard_fab2_lib.baseboard_fab2(sch_1):tp_cpu1_rsvd_22"
				( attribute "CDS_PHYS_NET_NAME" "TP_CPU1_RSVD_22"
					( Origin gPackager )
				)
				( objectStatus "TP_CPU1_RSVD_22" )
			)
			( signal "@baseboard_fab2_lib.baseboard_fab2(sch_1):tp_cpu1_rsvd_23"
				( attribute "CDS_PHYS_NET_NAME" "TP_CPU1_RSVD_23"
					( Origin gPackager )
				)
				( objectStatus "TP_CPU1_RSVD_23" )
			)
			( signal "@baseboard_fab2_lib.baseboard_fab2(sch_1):tp_cpu1_rsvd_24"
				( attribute "CDS_PHYS_NET_NAME" "TP_CPU1_RSVD_24"
					( Origin gPackager )
				)
				( objectStatus "TP_CPU1_RSVD_24" )
			)
			( signal "@baseboard_fab2_lib.baseboard_fab2(sch_1):tp_cpu1_rsvd_25"
				( attribute "CDS_PHYS_NET_NAME" "TP_CPU1_RSVD_25"
					( Origin gPackager )
				)
				( objectStatus "TP_CPU1_RSVD_25" )
			)
			( signal "@baseboard_fab2_lib.baseboard_fab2(sch_1):tp_cpu1_rsvd_26"
				( attribute "CDS_PHYS_NET_NAME" "TP_CPU1_RSVD_26"
					( Origin gPackager )
				)
				( objectStatus "TP_CPU1_RSVD_26" )
			)
			( signal "@baseboard_fab2_lib.baseboard_fab2(sch_1):tp_cpu1_rsvd_27"
				( attribute "CDS_PHYS_NET_NAME" "TP_CPU1_RSVD_27"
					( Origin gPackager )
				)
				( objectStatus "TP_CPU1_RSVD_27" )
			)
			( signal "@baseboard_fab2_lib.baseboard_fab2(sch_1):tp_cpu1_rsvd_28"
				( attribute "CDS_PHYS_NET_NAME" "TP_CPU1_RSVD_28"
					( Origin gPackager )
				)
				( objectStatus "TP_CPU1_RSVD_28" )
			)
			( signal "@baseboard_fab2_lib.baseboard_fab2(sch_1):tp_cpu1_rsvd_29"
				( attribute "CDS_PHYS_NET_NAME" "TP_CPU1_RSVD_29"
					( Origin gPackager )
				)
				( objectStatus "TP_CPU1_RSVD_29" )
			)
			( signal "@baseboard_fab2_lib.baseboard_fab2(sch_1):tp_cpu1_rsvd_3"
				( attribute "CDS_PHYS_NET_NAME" "TP_CPU1_RSVD_3"
					( Origin gPackager )
				)
				( objectStatus "TP_CPU1_RSVD_3" )
			)
			( signal "@baseboard_fab2_lib.baseboard_fab2(sch_1):tp_cpu1_rsvd_30"
				( attribute "CDS_PHYS_NET_NAME" "TP_CPU1_RSVD_30"
					( Origin gPackager )
				)
				( objectStatus "TP_CPU1_RSVD_30" )
			)
			( signal "@baseboard_fab2_lib.baseboard_fab2(sch_1):tp_cpu1_rsvd_31"
				( attribute "CDS_PHYS_NET_NAME" "TP_CPU1_RSVD_31"
					( Origin gPackager )
				)
				( objectStatus "TP_CPU1_RSVD_31" )
			)
			( signal "@baseboard_fab2_lib.baseboard_fab2(sch_1):tp_cpu1_rsvd_32"
				( attribute "CDS_PHYS_NET_NAME" "TP_CPU1_RSVD_32"
					( Origin gPackager )
				)
				( objectStatus "TP_CPU1_RSVD_32" )
			)
			( signal "@baseboard_fab2_lib.baseboard_fab2(sch_1):tp_cpu1_rsvd_33"
				( attribute "CDS_PHYS_NET_NAME" "TP_CPU1_RSVD_33"
					( Origin gPackager )
				)
				( objectStatus "TP_CPU1_RSVD_33" )
			)
			( signal "@baseboard_fab2_lib.baseboard_fab2(sch_1):tp_cpu1_rsvd_34"
				( attribute "CDS_PHYS_NET_NAME" "TP_CPU1_RSVD_34"
					( Origin gPackager )
				)
				( objectStatus "TP_CPU1_RSVD_34" )
			)
			( signal "@baseboard_fab2_lib.baseboard_fab2(sch_1):tp_cpu1_rsvd_35"
				( attribute "CDS_PHYS_NET_NAME" "TP_CPU1_RSVD_35"
					( Origin gPackager )
				)
				( objectStatus "TP_CPU1_RSVD_35" )
			)
			( signal "@baseboard_fab2_lib.baseboard_fab2(sch_1):tp_cpu1_rsvd_36"
				( attribute "CDS_PHYS_NET_NAME" "TP_CPU1_RSVD_36"
					( Origin gPackager )
				)
				( objectStatus "TP_CPU1_RSVD_36" )
			)
			( signal "@baseboard_fab2_lib.baseboard_fab2(sch_1):tp_cpu1_rsvd_37"
				( attribute "CDS_PHYS_NET_NAME" "TP_CPU1_RSVD_37"
					( Origin gPackager )
				)
				( objectStatus "TP_CPU1_RSVD_37" )
			)
			( signal "@baseboard_fab2_lib.baseboard_fab2(sch_1):tp_cpu1_rsvd_38"
				( attribute "CDS_PHYS_NET_NAME" "TP_CPU1_RSVD_38"
					( Origin gPackager )
				)
				( objectStatus "TP_CPU1_RSVD_38" )
			)
			( signal "@baseboard_fab2_lib.baseboard_fab2(sch_1):tp_cpu1_rsvd_39"
				( attribute "CDS_PHYS_NET_NAME" "TP_CPU1_RSVD_39"
					( Origin gPackager )
				)
				( objectStatus "TP_CPU1_RSVD_39" )
			)
			( signal "@baseboard_fab2_lib.baseboard_fab2(sch_1):tp_cpu1_rsvd_4"
				( attribute "CDS_PHYS_NET_NAME" "TP_CPU1_RSVD_4"
					( Origin gPackager )
				)
				( objectStatus "TP_CPU1_RSVD_4" )
			)
			( signal "@baseboard_fab2_lib.baseboard_fab2(sch_1):tp_cpu1_rsvd_40"
				( attribute "CDS_PHYS_NET_NAME" "TP_CPU1_RSVD_40"
					( Origin gPackager )
				)
				( objectStatus "TP_CPU1_RSVD_40" )
			)
			( signal "@baseboard_fab2_lib.baseboard_fab2(sch_1):tp_cpu1_rsvd_41"
				( attribute "CDS_PHYS_NET_NAME" "TP_CPU1_RSVD_41"
					( Origin gPackager )
				)
				( objectStatus "TP_CPU1_RSVD_41" )
			)
			( signal "@baseboard_fab2_lib.baseboard_fab2(sch_1):tp_cpu1_rsvd_42"
				( attribute "CDS_PHYS_NET_NAME" "TP_CPU1_RSVD_42"
					( Origin gPackager )
				)
				( objectStatus "TP_CPU1_RSVD_42" )
			)
			( signal "@baseboard_fab2_lib.baseboard_fab2(sch_1):tp_cpu1_rsvd_43"
				( attribute "CDS_PHYS_NET_NAME" "TP_CPU1_RSVD_43"
					( Origin gPackager )
				)
				( objectStatus "TP_CPU1_RSVD_43" )
			)
			( signal "@baseboard_fab2_lib.baseboard_fab2(sch_1):tp_cpu1_rsvd_44"
				( attribute "CDS_PHYS_NET_NAME" "TP_CPU1_RSVD_44"
					( Origin gPackager )
				)
				( objectStatus "TP_CPU1_RSVD_44" )
			)
			( signal "@baseboard_fab2_lib.baseboard_fab2(sch_1):tp_cpu1_rsvd_45"
				( attribute "CDS_PHYS_NET_NAME" "TP_CPU1_RSVD_45"
					( Origin gPackager )
				)
				( objectStatus "TP_CPU1_RSVD_45" )
			)
			( signal "@baseboard_fab2_lib.baseboard_fab2(sch_1):tp_cpu1_rsvd_46"
				( attribute "CDS_PHYS_NET_NAME" "TP_CPU1_RSVD_46"
					( Origin gPackager )
				)
				( objectStatus "TP_CPU1_RSVD_46" )
			)
			( signal "@baseboard_fab2_lib.baseboard_fab2(sch_1):tp_cpu1_rsvd_47"
				( attribute "CDS_PHYS_NET_NAME" "TP_CPU1_RSVD_47"
					( Origin gPackager )
				)
				( objectStatus "TP_CPU1_RSVD_47" )
			)
			( signal "@baseboard_fab2_lib.baseboard_fab2(sch_1):tp_cpu1_rsvd_48"
				( attribute "CDS_PHYS_NET_NAME" "TP_CPU1_RSVD_48"
					( Origin gPackager )
				)
				( objectStatus "TP_CPU1_RSVD_48" )
			)
			( signal "@baseboard_fab2_lib.baseboard_fab2(sch_1):tp_cpu1_rsvd_49"
				( attribute "CDS_PHYS_NET_NAME" "TP_CPU1_RSVD_49"
					( Origin gPackager )
				)
				( objectStatus "TP_CPU1_RSVD_49" )
			)
			( signal "@baseboard_fab2_lib.baseboard_fab2(sch_1):tp_cpu1_rsvd_5"
				( attribute "CDS_PHYS_NET_NAME" "TP_CPU1_RSVD_5"
					( Origin gPackager )
				)
				( objectStatus "TP_CPU1_RSVD_5" )
			)
			( signal "@baseboard_fab2_lib.baseboard_fab2(sch_1):tp_cpu1_rsvd_50"
				( attribute "CDS_PHYS_NET_NAME" "TP_CPU1_RSVD_50"
					( Origin gPackager )
				)
				( objectStatus "TP_CPU1_RSVD_50" )
			)
			( signal "@baseboard_fab2_lib.baseboard_fab2(sch_1):tp_cpu1_rsvd_51"
				( attribute "CDS_PHYS_NET_NAME" "TP_CPU1_RSVD_51"
					( Origin gPackager )
				)
				( objectStatus "TP_CPU1_RSVD_51" )
			)
			( signal "@baseboard_fab2_lib.baseboard_fab2(sch_1):tp_cpu1_rsvd_53"
				( attribute "CDS_PHYS_NET_NAME" "TP_CPU1_RSVD_53"
					( Origin gPackager )
				)
				( objectStatus "TP_CPU1_RSVD_53" )
			)
			( signal "@baseboard_fab2_lib.baseboard_fab2(sch_1):tp_cpu1_rsvd_54"
				( attribute "CDS_PHYS_NET_NAME" "TP_CPU1_RSVD_54"
					( Origin gPackager )
				)
				( objectStatus "TP_CPU1_RSVD_54" )
			)
			( signal "@baseboard_fab2_lib.baseboard_fab2(sch_1):tp_cpu1_rsvd_55"
				( attribute "CDS_PHYS_NET_NAME" "TP_CPU1_RSVD_55"
					( Origin gPackager )
				)
				( objectStatus "TP_CPU1_RSVD_55" )
			)
			( signal "@baseboard_fab2_lib.baseboard_fab2(sch_1):tp_cpu1_rsvd_56"
				( attribute "CDS_PHYS_NET_NAME" "TP_CPU1_RSVD_56"
					( Origin gPackager )
				)
				( objectStatus "TP_CPU1_RSVD_56" )
			)
			( signal "@baseboard_fab2_lib.baseboard_fab2(sch_1):tp_cpu1_rsvd_57"
				( attribute "CDS_PHYS_NET_NAME" "TP_CPU1_RSVD_57"
					( Origin gPackager )
				)
				( objectStatus "TP_CPU1_RSVD_57" )
			)
			( signal "@baseboard_fab2_lib.baseboard_fab2(sch_1):tp_cpu1_rsvd_59"
				( attribute "CDS_PHYS_NET_NAME" "TP_CPU1_RSVD_59"
					( Origin gPackager )
				)
				( objectStatus "TP_CPU1_RSVD_59" )
			)
			( signal "@baseboard_fab2_lib.baseboard_fab2(sch_1):tp_cpu1_rsvd_6"
				( attribute "CDS_PHYS_NET_NAME" "TP_CPU1_RSVD_6"
					( Origin gPackager )
				)
				( objectStatus "TP_CPU1_RSVD_6" )
			)
			( signal "@baseboard_fab2_lib.baseboard_fab2(sch_1):tp_cpu1_rsvd_60"
				( attribute "CDS_PHYS_NET_NAME" "TP_CPU1_RSVD_60"
					( Origin gPackager )
				)
				( objectStatus "TP_CPU1_RSVD_60" )
			)
			( signal "@baseboard_fab2_lib.baseboard_fab2(sch_1):tp_cpu1_rsvd_61"
				( attribute "CDS_PHYS_NET_NAME" "TP_CPU1_RSVD_61"
					( Origin gPackager )
				)
				( objectStatus "TP_CPU1_RSVD_61" )
			)
			( signal "@baseboard_fab2_lib.baseboard_fab2(sch_1):tp_cpu1_rsvd_64"
				( attribute "CDS_PHYS_NET_NAME" "TP_CPU1_RSVD_64"
					( Origin gPackager )
				)
				( objectStatus "TP_CPU1_RSVD_64" )
			)
			( signal "@baseboard_fab2_lib.baseboard_fab2(sch_1):tp_cpu1_rsvd_66"
				( attribute "CDS_PHYS_NET_NAME" "TP_CPU1_RSVD_66"
					( Origin gPackager )
				)
				( objectStatus "TP_CPU1_RSVD_66" )
			)
			( signal "@baseboard_fab2_lib.baseboard_fab2(sch_1):tp_cpu1_rsvd_67"
				( attribute "CDS_PHYS_NET_NAME" "TP_CPU1_RSVD_67"
					( Origin gPackager )
				)
				( objectStatus "TP_CPU1_RSVD_67" )
			)
			( signal "@baseboard_fab2_lib.baseboard_fab2(sch_1):tp_cpu1_rsvd_69"
				( attribute "CDS_PHYS_NET_NAME" "TP_CPU1_RSVD_69"
					( Origin gPackager )
				)
				( objectStatus "TP_CPU1_RSVD_69" )
			)
			( signal "@baseboard_fab2_lib.baseboard_fab2(sch_1):tp_cpu1_rsvd_7"
				( attribute "CDS_PHYS_NET_NAME" "TP_CPU1_RSVD_7"
					( Origin gPackager )
				)
				( objectStatus "TP_CPU1_RSVD_7" )
			)
			( signal "@baseboard_fab2_lib.baseboard_fab2(sch_1):tp_cpu1_rsvd_70"
				( attribute "CDS_PHYS_NET_NAME" "TP_CPU1_RSVD_70"
					( Origin gPackager )
				)
				( objectStatus "TP_CPU1_RSVD_70" )
			)
			( signal "@baseboard_fab2_lib.baseboard_fab2(sch_1):tp_cpu1_rsvd_72"
				( attribute "CDS_PHYS_NET_NAME" "TP_CPU1_RSVD_72"
					( Origin gPackager )
				)
				( objectStatus "TP_CPU1_RSVD_72" )
			)
			( signal "@baseboard_fab2_lib.baseboard_fab2(sch_1):tp_cpu1_rsvd_73"
				( attribute "CDS_PHYS_NET_NAME" "TP_CPU1_RSVD_73"
					( Origin gPackager )
				)
				( objectStatus "TP_CPU1_RSVD_73" )
			)
			( signal "@baseboard_fab2_lib.baseboard_fab2(sch_1):tp_cpu1_rsvd_8"
				( attribute "CDS_PHYS_NET_NAME" "TP_CPU1_RSVD_8"
					( Origin gPackager )
				)
				( objectStatus "TP_CPU1_RSVD_8" )
			)
			( signal "@baseboard_fab2_lib.baseboard_fab2(sch_1):tp_cpu1_rsvd_9"
				( attribute "CDS_PHYS_NET_NAME" "TP_CPU1_RSVD_9"
					( Origin gPackager )
				)
				( objectStatus "TP_CPU1_RSVD_9" )
			)
			( signal "@baseboard_fab2_lib.baseboard_fab2(sch_1):vsense_pvccio_cpu1_skt_vrtn"
				( attribute "CDS_PHYS_NET_NAME" "VSENSE_PVCCIO_CPU1_SKT_VRTN"
					( Origin gPackager )
				)
				( objectStatus "VSENSE_PVCCIO_CPU1_SKT_VRTN" )
			)
			( signal "@baseboard_fab2_lib.baseboard_fab2(sch_1):vsense_pvccio_cpu1_skt_vsen"
				( attribute "CDS_PHYS_NET_NAME" "VSENSE_PVCCIO_CPU1_SKT_VSEN"
					( Origin gPackager )
				)
				( objectStatus "VSENSE_PVCCIO_CPU1_SKT_VSEN" )
			)
			( signal "@baseboard_fab2_lib.baseboard_fab2(sch_1):vsense_pvcciomcp_cpu1_skt_vrtn"
				( attribute "CDS_PHYS_NET_NAME" "VSENSE_PVCCIOMCP_CPU1_SKT_VRTN"
					( Origin gPackager )
				)
				( objectStatus "VSENSE_PVCCIOMCP_CPU1_SKT_VRTN" )
			)
			( signal "@baseboard_fab2_lib.baseboard_fab2(sch_1):vsense_pvcciomcp_cpu1_skt_vsen"
				( attribute "CDS_PHYS_NET_NAME" "VSENSE_PVCCIOMCP_CPU1_SKT_VSEN"
					( Origin gPackager )
				)
				( objectStatus "VSENSE_PVCCIOMCP_CPU1_SKT_VSEN" )
			)
			( signal "@baseboard_fab2_lib.baseboard_fab2(sch_1):vsense_pvccmcp_cpu1_skt_vrtn"
				( attribute "CDS_PHYS_NET_NAME" "VSENSE_PVCCMCP_CPU1_SKT_VRTN"
					( Origin gPackager )
				)
				( objectStatus "VSENSE_PVCCMCP_CPU1_SKT_VRTN" )
			)
			( signal "@baseboard_fab2_lib.baseboard_fab2(sch_1):vsense_pvccmcp_cpu1_skt_vsen"
				( attribute "CDS_PHYS_NET_NAME" "VSENSE_PVCCMCP_CPU1_SKT_VSEN"
					( Origin gPackager )
				)
				( objectStatus "VSENSE_PVCCMCP_CPU1_SKT_VSEN" )
			)
			( signal "@baseboard_fab2_lib.baseboard_fab2(sch_1):vsense_pvsa_cpu1_skt_vrtn"
				( attribute "CDS_PHYS_NET_NAME" "VSENSE_PVSA_CPU1_SKT_VRTN"
					( Origin gPackager )
				)
				( objectStatus "VSENSE_PVSA_CPU1_SKT_VRTN" )
			)
			( signal "@baseboard_fab2_lib.baseboard_fab2(sch_1):vsense_pvsa_cpu1_skt_vsen"
				( attribute "CDS_PHYS_NET_NAME" "VSENSE_PVSA_CPU1_SKT_VSEN"
					( Origin gPackager )
				)
				( objectStatus "VSENSE_PVSA_CPU1_SKT_VSEN" )
			)
			( signal "@baseboard_fab2_lib.baseboard_fab2(sch_1):fm_adr_complete_ghj_n"
				( attribute "CDS_PHYS_NET_NAME" "FM_ADR_COMPLETE_GHJ_N"
					( Origin gPackager )
				)
				( objectStatus "FM_ADR_COMPLETE_GHJ_N" )
			)
			( signal "@baseboard_fab2_lib.baseboard_fab2(sch_1):m_g_vref"
				( attribute "CDS_PHYS_NET_NAME" "M_G_VREF"
					( Origin gPackager )
				)
				( objectStatus "M_G_VREF" )
			)
			( signal "@baseboard_fab2_lib.baseboard_fab2(sch_1):p12v_nvdimm_ghj"
				( alias ( signalRef "@baseboard_fab2_lib.baseboard_fab2(sch_1):page77_p12v_nvdimm_ghj") )
				( alias ( signalRef "@baseboard_fab2_lib.baseboard_fab2(sch_1):page78_p12v_nvdimm_ghj") )
				( alias ( signalRef "@baseboard_fab2_lib.baseboard_fab2(sch_1):page79_p12v_nvdimm_ghj") )
				( alias ( signalRef "@baseboard_fab2_lib.baseboard_fab2(sch_1):page80_p12v_nvdimm_ghj") )
				( alias ( signalRef "@baseboard_fab2_lib.baseboard_fab2(sch_1):page81_p12v_nvdimm_ghj") )
				( alias ( signalRef "@baseboard_fab2_lib.baseboard_fab2(sch_1):page82_p12v_nvdimm_ghj") )
				( alias ( signalRef "@baseboard_fab2_lib.baseboard_fab2(sch_1):page197_p12v_nvdimm_ghj") )
				( attribute "VOLTAGE" "12.0"
					( Units "uVoltage" "V" 1.000000)
					( Status sAliasFlattened )
					( Origin gFrontEnd )
				)
				( attribute "CDS_PHYS_NET_NAME" "P12V_NVDIMM_GHJ"
					( Origin gPackager )
				)
				( objectStatus "P12V_NVDIMM_GHJ" )
			)
			( signal "@baseboard_fab2_lib.baseboard_fab2(sch_1):page77_p12v_nvdimm_ghj"
				( attribute "VOLTAGE" "12.0"
					( Units "uVoltage" "V" 1.000000)
					( Origin gFrontEnd )
				)
				( objectFlag fObjectAlias )
				( objectStatus "page77_p12v_nvdimm_ghj" )
			)
			( signal "@baseboard_fab2_lib.baseboard_fab2(sch_1):page78_p12v_nvdimm_ghj"
				( attribute "VOLTAGE" "12.0"
					( Units "uVoltage" "V" 1.000000)
					( Origin gFrontEnd )
				)
				( objectFlag fObjectAlias )
				( objectStatus "page78_p12v_nvdimm_ghj" )
			)
			( signal "@baseboard_fab2_lib.baseboard_fab2(sch_1):page79_p12v_nvdimm_ghj"
				( attribute "VOLTAGE" "12.0"
					( Units "uVoltage" "V" 1.000000)
					( Origin gFrontEnd )
				)
				( objectFlag fObjectAlias )
				( objectStatus "page79_p12v_nvdimm_ghj" )
			)
			( signal "@baseboard_fab2_lib.baseboard_fab2(sch_1):page80_p12v_nvdimm_ghj"
				( attribute "VOLTAGE" "12.0"
					( Units "uVoltage" "V" 1.000000)
					( Origin gFrontEnd )
				)
				( objectFlag fObjectAlias )
				( objectStatus "page80_p12v_nvdimm_ghj" )
			)
			( signal "@baseboard_fab2_lib.baseboard_fab2(sch_1):page81_p12v_nvdimm_ghj"
				( attribute "VOLTAGE" "12.0"
					( Units "uVoltage" "V" 1.000000)
					( Origin gFrontEnd )
				)
				( objectFlag fObjectAlias )
				( objectStatus "page81_p12v_nvdimm_ghj" )
			)
			( signal "@baseboard_fab2_lib.baseboard_fab2(sch_1):page82_p12v_nvdimm_ghj"
				( attribute "VOLTAGE" "12.0"
					( Units "uVoltage" "V" 1.000000)
					( Origin gFrontEnd )
				)
				( objectFlag fObjectAlias )
				( objectStatus "page82_p12v_nvdimm_ghj" )
			)
			( signal "@baseboard_fab2_lib.baseboard_fab2(sch_1):page197_p12v_nvdimm_ghj"
				( attribute "VOLTAGE" "12.0"
					( Units "uVoltage" "V" 1.000000)
					( Origin gFrontEnd )
				)
				( objectFlag fObjectAlias )
				( objectStatus "page197_p12v_nvdimm_ghj" )
			)
			( signal "@baseboard_fab2_lib.baseboard_fab2(sch_1):pvtt_ghj"
				( alias ( signalRef "@baseboard_fab2_lib.baseboard_fab2(sch_1):page77_pvtt_ghj") )
				( alias ( signalRef "@baseboard_fab2_lib.baseboard_fab2(sch_1):page78_pvtt_ghj") )
				( alias ( signalRef "@baseboard_fab2_lib.baseboard_fab2(sch_1):page79_pvtt_ghj") )
				( alias ( signalRef "@baseboard_fab2_lib.baseboard_fab2(sch_1):page80_pvtt_ghj") )
				( alias ( signalRef "@baseboard_fab2_lib.baseboard_fab2(sch_1):page81_pvtt_ghj") )
				( alias ( signalRef "@baseboard_fab2_lib.baseboard_fab2(sch_1):page82_pvtt_ghj") )
				( alias ( signalRef "@baseboard_fab2_lib.baseboard_fab2(sch_1):page229_pvtt_ghj") )
				( attribute "VOLTAGE" "0.6V"
					( Units "uVoltage" "V" 1.000000)
					( Status sAliasFlattened )
					( Origin gFrontEnd )
				)
				( attribute "CDS_PHYS_NET_NAME" "PVTT_GHJ"
					( Origin gPackager )
				)
				( objectStatus "PVTT_GHJ" )
			)
			( signal "@baseboard_fab2_lib.baseboard_fab2(sch_1):page77_pvtt_ghj"
				( attribute "VOLTAGE" "0.6V"
					( Units "uVoltage" "V" 1.000000)
					( Origin gFrontEnd )
				)
				( objectFlag fObjectAlias )
				( objectStatus "page77_pvtt_ghj" )
			)
			( signal "@baseboard_fab2_lib.baseboard_fab2(sch_1):page78_pvtt_ghj"
				( attribute "VOLTAGE" "0.6V"
					( Units "uVoltage" "V" 1.000000)
					( Origin gFrontEnd )
				)
				( objectFlag fObjectAlias )
				( objectStatus "page78_pvtt_ghj" )
			)
			( signal "@baseboard_fab2_lib.baseboard_fab2(sch_1):page79_pvtt_ghj"
				( attribute "VOLTAGE" "0.6V"
					( Units "uVoltage" "V" 1.000000)
					( Origin gFrontEnd )
				)
				( objectFlag fObjectAlias )
				( objectStatus "page79_pvtt_ghj" )
			)
			( signal "@baseboard_fab2_lib.baseboard_fab2(sch_1):page80_pvtt_ghj"
				( attribute "VOLTAGE" "0.6V"
					( Units "uVoltage" "V" 1.000000)
					( Origin gFrontEnd )
				)
				( objectFlag fObjectAlias )
				( objectStatus "page80_pvtt_ghj" )
			)
			( signal "@baseboard_fab2_lib.baseboard_fab2(sch_1):page81_pvtt_ghj"
				( attribute "VOLTAGE" "0.6V"
					( Units "uVoltage" "V" 1.000000)
					( Origin gFrontEnd )
				)
				( objectFlag fObjectAlias )
				( objectStatus "page81_pvtt_ghj" )
			)
			( signal "@baseboard_fab2_lib.baseboard_fab2(sch_1):page82_pvtt_ghj"
				( attribute "VOLTAGE" "0.6V"
					( Units "uVoltage" "V" 1.000000)
					( Origin gFrontEnd )
				)
				( objectFlag fObjectAlias )
				( objectStatus "page82_pvtt_ghj" )
			)
			( signal "@baseboard_fab2_lib.baseboard_fab2(sch_1):page229_pvtt_ghj"
				( attribute "VOLTAGE" "0.6V"
					( Units "uVoltage" "V" 1.000000)
					( Origin gFrontEnd )
				)
				( objectFlag fObjectAlias )
				( objectStatus "page229_pvtt_ghj" )
			)
			( signal "@baseboard_fab2_lib.baseboard_fab2(sch_1):smb_ddr_ghj_vpp_scl"
				( attribute "CDS_PHYS_NET_NAME" "SMB_DDR_GHJ_VPP_SCL"
					( Origin gPackager )
				)
				( objectStatus "SMB_DDR_GHJ_VPP_SCL" )
			)
			( signal "@baseboard_fab2_lib.baseboard_fab2(sch_1):smb_ddr_ghj_vpp_sda"
				( attribute "CDS_PHYS_NET_NAME" "SMB_DDR_GHJ_VPP_SDA"
					( Origin gPackager )
				)
				( objectStatus "SMB_DDR_GHJ_VPP_SDA" )
			)
			( signal "@baseboard_fab2_lib.baseboard_fab2(sch_1):tp_ch_g_dimm_g0_rfu_0"
				( attribute "CDS_PHYS_NET_NAME" "TP_CH_G_DIMM_G0_RFU_0"
					( Origin gPackager )
				)
				( objectStatus "TP_CH_G_DIMM_G0_RFU_0" )
			)
			( signal "@baseboard_fab2_lib.baseboard_fab2(sch_1):tp_ch_g_dimm_g0_rfu_1"
				( attribute "CDS_PHYS_NET_NAME" "TP_CH_G_DIMM_G0_RFU_1"
					( Origin gPackager )
				)
				( objectStatus "TP_CH_G_DIMM_G0_RFU_1" )
			)
			( signal "@baseboard_fab2_lib.baseboard_fab2(sch_1):tp_ch_g_dimm_g0_rfu_2"
				( attribute "CDS_PHYS_NET_NAME" "TP_CH_G_DIMM_G0_RFU_2"
					( Origin gPackager )
				)
				( objectStatus "TP_CH_G_DIMM_G0_RFU_2" )
			)
			( signal "@baseboard_fab2_lib.baseboard_fab2(sch_1):tp_ch_g_dimm0_rfu_0"
				( attribute "CDS_PHYS_NET_NAME" "TP_CH_G_DIMM0_RFU_0"
					( Origin gPackager )
				)
				( objectStatus "TP_CH_G_DIMM0_RFU_0" )
			)
			( signal "@baseboard_fab2_lib.baseboard_fab2(sch_1):tp_ch_g_dimm0_rfu_1"
				( attribute "CDS_PHYS_NET_NAME" "TP_CH_G_DIMM0_RFU_1"
					( Origin gPackager )
				)
				( objectStatus "TP_CH_G_DIMM0_RFU_1" )
			)
			( signal "@baseboard_fab2_lib.baseboard_fab2(sch_1):tp_ch_g_dimm0_rfu_2"
				( attribute "CDS_PHYS_NET_NAME" "TP_CH_G_DIMM0_RFU_2"
					( Origin gPackager )
				)
				( objectStatus "TP_CH_G_DIMM0_RFU_2" )
			)
			( signal "@baseboard_fab2_lib.baseboard_fab2(sch_1):m_h_vref"
				( attribute "CDS_PHYS_NET_NAME" "M_H_VREF"
					( Origin gPackager )
				)
				( objectStatus "M_H_VREF" )
			)
			( signal "@baseboard_fab2_lib.baseboard_fab2(sch_1):tp_ch_h_dimm_h0_rfu_0"
				( attribute "CDS_PHYS_NET_NAME" "TP_CH_H_DIMM_H0_RFU_0"
					( Origin gPackager )
				)
				( objectStatus "TP_CH_H_DIMM_H0_RFU_0" )
			)
			( signal "@baseboard_fab2_lib.baseboard_fab2(sch_1):tp_ch_h_dimm_h0_rfu_1"
				( attribute "CDS_PHYS_NET_NAME" "TP_CH_H_DIMM_H0_RFU_1"
					( Origin gPackager )
				)
				( objectStatus "TP_CH_H_DIMM_H0_RFU_1" )
			)
			( signal "@baseboard_fab2_lib.baseboard_fab2(sch_1):tp_ch_h_dimm_h0_rfu_2"
				( attribute "CDS_PHYS_NET_NAME" "TP_CH_H_DIMM_H0_RFU_2"
					( Origin gPackager )
				)
				( objectStatus "TP_CH_H_DIMM_H0_RFU_2" )
			)
			( signal "@baseboard_fab2_lib.baseboard_fab2(sch_1):tp_ch_h_dimm0_rfu_0"
				( attribute "CDS_PHYS_NET_NAME" "TP_CH_H_DIMM0_RFU_0"
					( Origin gPackager )
				)
				( objectStatus "TP_CH_H_DIMM0_RFU_0" )
			)
			( signal "@baseboard_fab2_lib.baseboard_fab2(sch_1):tp_ch_h_dimm0_rfu_1"
				( attribute "CDS_PHYS_NET_NAME" "TP_CH_H_DIMM0_RFU_1"
					( Origin gPackager )
				)
				( objectStatus "TP_CH_H_DIMM0_RFU_1" )
			)
			( signal "@baseboard_fab2_lib.baseboard_fab2(sch_1):tp_ch_h_dimm0_rfu_2"
				( attribute "CDS_PHYS_NET_NAME" "TP_CH_H_DIMM0_RFU_2"
					( Origin gPackager )
				)
				( objectStatus "TP_CH_H_DIMM0_RFU_2" )
			)
			( signal "@baseboard_fab2_lib.baseboard_fab2(sch_1):m_j_vref"
				( attribute "CDS_PHYS_NET_NAME" "M_J_VREF"
					( Origin gPackager )
				)
				( objectStatus "M_J_VREF" )
			)
			( signal "@baseboard_fab2_lib.baseboard_fab2(sch_1):tp_ch_j_dimm_j0_rfu_0"
				( attribute "CDS_PHYS_NET_NAME" "TP_CH_J_DIMM_J0_RFU_0"
					( Origin gPackager )
				)
				( objectStatus "TP_CH_J_DIMM_J0_RFU_0" )
			)
			( signal "@baseboard_fab2_lib.baseboard_fab2(sch_1):tp_ch_j_dimm_j0_rfu_1"
				( attribute "CDS_PHYS_NET_NAME" "TP_CH_J_DIMM_J0_RFU_1"
					( Origin gPackager )
				)
				( objectStatus "TP_CH_J_DIMM_J0_RFU_1" )
			)
			( signal "@baseboard_fab2_lib.baseboard_fab2(sch_1):tp_ch_j_dimm_j0_rfu_2"
				( attribute "CDS_PHYS_NET_NAME" "TP_CH_J_DIMM_J0_RFU_2"
					( Origin gPackager )
				)
				( objectStatus "TP_CH_J_DIMM_J0_RFU_2" )
			)
			( signal "@baseboard_fab2_lib.baseboard_fab2(sch_1):tp_ch_j_dimm_j1_rfu_0"
				( attribute "CDS_PHYS_NET_NAME" "TP_CH_J_DIMM_J1_RFU_0"
					( Origin gPackager )
				)
				( objectStatus "TP_CH_J_DIMM_J1_RFU_0" )
			)
			( signal "@baseboard_fab2_lib.baseboard_fab2(sch_1):tp_ch_j_dimm_j1_rfu_1"
				( attribute "CDS_PHYS_NET_NAME" "TP_CH_J_DIMM_J1_RFU_1"
					( Origin gPackager )
				)
				( objectStatus "TP_CH_J_DIMM_J1_RFU_1" )
			)
			( signal "@baseboard_fab2_lib.baseboard_fab2(sch_1):tp_ch_j_dimm_j1_rfu_2"
				( attribute "CDS_PHYS_NET_NAME" "TP_CH_J_DIMM_J1_RFU_2"
					( Origin gPackager )
				)
				( objectStatus "TP_CH_J_DIMM_J1_RFU_2" )
			)
			( signal "@baseboard_fab2_lib.baseboard_fab2(sch_1):fm_adr_complete_klm_n"
				( attribute "CDS_PHYS_NET_NAME" "FM_ADR_COMPLETE_KLM_N"
					( Origin gPackager )
				)
				( objectStatus "FM_ADR_COMPLETE_KLM_N" )
			)
			( signal "@baseboard_fab2_lib.baseboard_fab2(sch_1):m_k_vref"
				( attribute "CDS_PHYS_NET_NAME" "M_K_VREF"
					( Origin gPackager )
				)
				( objectStatus "M_K_VREF" )
			)
			( signal "@baseboard_fab2_lib.baseboard_fab2(sch_1):p12v_nvdimm_klm"
				( alias ( signalRef "@baseboard_fab2_lib.baseboard_fab2(sch_1):page83_p12v_nvdimm_klm") )
				( alias ( signalRef "@baseboard_fab2_lib.baseboard_fab2(sch_1):page84_p12v_nvdimm_klm") )
				( alias ( signalRef "@baseboard_fab2_lib.baseboard_fab2(sch_1):page85_p12v_nvdimm_klm") )
				( alias ( signalRef "@baseboard_fab2_lib.baseboard_fab2(sch_1):page86_p12v_nvdimm_klm") )
				( alias ( signalRef "@baseboard_fab2_lib.baseboard_fab2(sch_1):page87_p12v_nvdimm_klm") )
				( alias ( signalRef "@baseboard_fab2_lib.baseboard_fab2(sch_1):page88_p12v_nvdimm_klm") )
				( alias ( signalRef "@baseboard_fab2_lib.baseboard_fab2(sch_1):page197_p12v_nvdimm_klm") )
				( attribute "VOLTAGE" "12.0"
					( Units "uVoltage" "V" 1.000000)
					( Status sAliasFlattened )
					( Origin gFrontEnd )
				)
				( attribute "CDS_PHYS_NET_NAME" "P12V_NVDIMM_KLM"
					( Origin gPackager )
				)
				( objectStatus "P12V_NVDIMM_KLM" )
			)
			( signal "@baseboard_fab2_lib.baseboard_fab2(sch_1):page83_p12v_nvdimm_klm"
				( attribute "VOLTAGE" "12.0"
					( Units "uVoltage" "V" 1.000000)
					( Origin gFrontEnd )
				)
				( objectFlag fObjectAlias )
				( objectStatus "page83_p12v_nvdimm_klm" )
			)
			( signal "@baseboard_fab2_lib.baseboard_fab2(sch_1):page84_p12v_nvdimm_klm"
				( attribute "VOLTAGE" "12.0"
					( Units "uVoltage" "V" 1.000000)
					( Origin gFrontEnd )
				)
				( objectFlag fObjectAlias )
				( objectStatus "page84_p12v_nvdimm_klm" )
			)
			( signal "@baseboard_fab2_lib.baseboard_fab2(sch_1):page85_p12v_nvdimm_klm"
				( attribute "VOLTAGE" "12.0"
					( Units "uVoltage" "V" 1.000000)
					( Origin gFrontEnd )
				)
				( objectFlag fObjectAlias )
				( objectStatus "page85_p12v_nvdimm_klm" )
			)
			( signal "@baseboard_fab2_lib.baseboard_fab2(sch_1):page86_p12v_nvdimm_klm"
				( attribute "VOLTAGE" "12.0"
					( Units "uVoltage" "V" 1.000000)
					( Origin gFrontEnd )
				)
				( objectFlag fObjectAlias )
				( objectStatus "page86_p12v_nvdimm_klm" )
			)
			( signal "@baseboard_fab2_lib.baseboard_fab2(sch_1):page87_p12v_nvdimm_klm"
				( attribute "VOLTAGE" "12.0"
					( Units "uVoltage" "V" 1.000000)
					( Origin gFrontEnd )
				)
				( objectFlag fObjectAlias )
				( objectStatus "page87_p12v_nvdimm_klm" )
			)
			( signal "@baseboard_fab2_lib.baseboard_fab2(sch_1):page88_p12v_nvdimm_klm"
				( attribute "VOLTAGE" "12.0"
					( Units "uVoltage" "V" 1.000000)
					( Origin gFrontEnd )
				)
				( objectFlag fObjectAlias )
				( objectStatus "page88_p12v_nvdimm_klm" )
			)
			( signal "@baseboard_fab2_lib.baseboard_fab2(sch_1):page197_p12v_nvdimm_klm"
				( attribute "VOLTAGE" "12.0"
					( Units "uVoltage" "V" 1.000000)
					( Origin gFrontEnd )
				)
				( objectFlag fObjectAlias )
				( objectStatus "page197_p12v_nvdimm_klm" )
			)
			( signal "@baseboard_fab2_lib.baseboard_fab2(sch_1):pvpp_klm"
				( alias ( signalRef "@baseboard_fab2_lib.baseboard_fab2(sch_1):page83_pvpp_klm") )
				( alias ( signalRef "@baseboard_fab2_lib.baseboard_fab2(sch_1):page84_pvpp_klm") )
				( alias ( signalRef "@baseboard_fab2_lib.baseboard_fab2(sch_1):page85_pvpp_klm") )
				( alias ( signalRef "@baseboard_fab2_lib.baseboard_fab2(sch_1):page86_pvpp_klm") )
				( alias ( signalRef "@baseboard_fab2_lib.baseboard_fab2(sch_1):page87_pvpp_klm") )
				( alias ( signalRef "@baseboard_fab2_lib.baseboard_fab2(sch_1):page88_pvpp_klm") )
				( alias ( signalRef "@baseboard_fab2_lib.baseboard_fab2(sch_1):page99_pvpp_klm") )
				( alias ( signalRef "@baseboard_fab2_lib.baseboard_fab2(sch_1):page192_pvpp_klm") )
				( alias ( signalRef "@baseboard_fab2_lib.baseboard_fab2(sch_1):page234_pvpp_klm") )
				( attribute "VOLTAGE" "2.5V"
					( Units "uVoltage" "V" 1.000000)
					( Status sAliasFlattened )
					( Origin gFrontEnd )
				)
				( attribute "CDS_PHYS_NET_NAME" "PVPP_KLM"
					( Origin gPackager )
				)
				( objectStatus "PVPP_KLM" )
			)
			( signal "@baseboard_fab2_lib.baseboard_fab2(sch_1):page83_pvpp_klm"
				( attribute "VOLTAGE" "2.5V"
					( Units "uVoltage" "V" 1.000000)
					( Origin gFrontEnd )
				)
				( objectFlag fObjectAlias )
				( objectStatus "page83_pvpp_klm" )
			)
			( signal "@baseboard_fab2_lib.baseboard_fab2(sch_1):page84_pvpp_klm"
				( attribute "VOLTAGE" "2.5V"
					( Units "uVoltage" "V" 1.000000)
					( Origin gFrontEnd )
				)
				( objectFlag fObjectAlias )
				( objectStatus "page84_pvpp_klm" )
			)
			( signal "@baseboard_fab2_lib.baseboard_fab2(sch_1):page85_pvpp_klm"
				( attribute "VOLTAGE" "2.5V"
					( Units "uVoltage" "V" 1.000000)
					( Origin gFrontEnd )
				)
				( objectFlag fObjectAlias )
				( objectStatus "page85_pvpp_klm" )
			)
			( signal "@baseboard_fab2_lib.baseboard_fab2(sch_1):page86_pvpp_klm"
				( attribute "VOLTAGE" "2.5V"
					( Units "uVoltage" "V" 1.000000)
					( Origin gFrontEnd )
				)
				( objectFlag fObjectAlias )
				( objectStatus "page86_pvpp_klm" )
			)
			( signal "@baseboard_fab2_lib.baseboard_fab2(sch_1):page87_pvpp_klm"
				( attribute "VOLTAGE" "2.5V"
					( Units "uVoltage" "V" 1.000000)
					( Origin gFrontEnd )
				)
				( objectFlag fObjectAlias )
				( objectStatus "page87_pvpp_klm" )
			)
			( signal "@baseboard_fab2_lib.baseboard_fab2(sch_1):page88_pvpp_klm"
				( attribute "VOLTAGE" "2.5V"
					( Units "uVoltage" "V" 1.000000)
					( Origin gFrontEnd )
				)
				( objectFlag fObjectAlias )
				( objectStatus "page88_pvpp_klm" )
			)
			( signal "@baseboard_fab2_lib.baseboard_fab2(sch_1):page99_pvpp_klm"
				( attribute "VOLTAGE" "2.5V"
					( Units "uVoltage" "V" 1.000000)
					( Origin gFrontEnd )
				)
				( objectFlag fObjectAlias )
				( objectStatus "page99_pvpp_klm" )
			)
			( signal "@baseboard_fab2_lib.baseboard_fab2(sch_1):page192_pvpp_klm"
				( attribute "VOLTAGE" "2.5V"
					( Units "uVoltage" "V" 1.000000)
					( Origin gFrontEnd )
				)
				( objectFlag fObjectAlias )
				( objectStatus "page192_pvpp_klm" )
			)
			( signal "@baseboard_fab2_lib.baseboard_fab2(sch_1):page234_pvpp_klm"
				( attribute "VOLTAGE" "2.5V"
					( Units "uVoltage" "V" 1.000000)
					( Origin gFrontEnd )
				)
				( objectFlag fObjectAlias )
				( objectStatus "page234_pvpp_klm" )
			)
			( signal "@baseboard_fab2_lib.baseboard_fab2(sch_1):pvtt_klm"
				( alias ( signalRef "@baseboard_fab2_lib.baseboard_fab2(sch_1):page83_pvtt_klm") )
				( alias ( signalRef "@baseboard_fab2_lib.baseboard_fab2(sch_1):page84_pvtt_klm") )
				( alias ( signalRef "@baseboard_fab2_lib.baseboard_fab2(sch_1):page85_pvtt_klm") )
				( alias ( signalRef "@baseboard_fab2_lib.baseboard_fab2(sch_1):page86_pvtt_klm") )
				( alias ( signalRef "@baseboard_fab2_lib.baseboard_fab2(sch_1):page87_pvtt_klm") )
				( alias ( signalRef "@baseboard_fab2_lib.baseboard_fab2(sch_1):page88_pvtt_klm") )
				( alias ( signalRef "@baseboard_fab2_lib.baseboard_fab2(sch_1):page230_pvtt_klm") )
				( attribute "VOLTAGE" "0.6V"
					( Units "uVoltage" "V" 1.000000)
					( Status sAliasFlattened )
					( Origin gFrontEnd )
				)
				( attribute "CDS_PHYS_NET_NAME" "PVTT_KLM"
					( Origin gPackager )
				)
				( objectStatus "PVTT_KLM" )
			)
			( signal "@baseboard_fab2_lib.baseboard_fab2(sch_1):page83_pvtt_klm"
				( attribute "VOLTAGE" "0.6V"
					( Units "uVoltage" "V" 1.000000)
					( Origin gFrontEnd )
				)
				( objectFlag fObjectAlias )
				( objectStatus "page83_pvtt_klm" )
			)
			( signal "@baseboard_fab2_lib.baseboard_fab2(sch_1):page84_pvtt_klm"
				( attribute "VOLTAGE" "0.6V"
					( Units "uVoltage" "V" 1.000000)
					( Origin gFrontEnd )
				)
				( objectFlag fObjectAlias )
				( objectStatus "page84_pvtt_klm" )
			)
			( signal "@baseboard_fab2_lib.baseboard_fab2(sch_1):page85_pvtt_klm"
				( attribute "VOLTAGE" "0.6V"
					( Units "uVoltage" "V" 1.000000)
					( Origin gFrontEnd )
				)
				( objectFlag fObjectAlias )
				( objectStatus "page85_pvtt_klm" )
			)
			( signal "@baseboard_fab2_lib.baseboard_fab2(sch_1):page86_pvtt_klm"
				( attribute "VOLTAGE" "0.6V"
					( Units "uVoltage" "V" 1.000000)
					( Origin gFrontEnd )
				)
				( objectFlag fObjectAlias )
				( objectStatus "page86_pvtt_klm" )
			)
			( signal "@baseboard_fab2_lib.baseboard_fab2(sch_1):page87_pvtt_klm"
				( attribute "VOLTAGE" "0.6V"
					( Units "uVoltage" "V" 1.000000)
					( Origin gFrontEnd )
				)
				( objectFlag fObjectAlias )
				( objectStatus "page87_pvtt_klm" )
			)
			( signal "@baseboard_fab2_lib.baseboard_fab2(sch_1):page88_pvtt_klm"
				( attribute "VOLTAGE" "0.6V"
					( Units "uVoltage" "V" 1.000000)
					( Origin gFrontEnd )
				)
				( objectFlag fObjectAlias )
				( objectStatus "page88_pvtt_klm" )
			)
			( signal "@baseboard_fab2_lib.baseboard_fab2(sch_1):page230_pvtt_klm"
				( attribute "VOLTAGE" "0.6V"
					( Units "uVoltage" "V" 1.000000)
					( Origin gFrontEnd )
				)
				( objectFlag fObjectAlias )
				( objectStatus "page230_pvtt_klm" )
			)
			( signal "@baseboard_fab2_lib.baseboard_fab2(sch_1):smb_ddr_klm_vpp_scl"
				( attribute "CDS_PHYS_NET_NAME" "SMB_DDR_KLM_VPP_SCL"
					( Origin gPackager )
				)
				( objectStatus "SMB_DDR_KLM_VPP_SCL" )
			)
			( signal "@baseboard_fab2_lib.baseboard_fab2(sch_1):smb_ddr_klm_vpp_sda"
				( attribute "CDS_PHYS_NET_NAME" "SMB_DDR_KLM_VPP_SDA"
					( Origin gPackager )
				)
				( objectStatus "SMB_DDR_KLM_VPP_SDA" )
			)
			( signal "@baseboard_fab2_lib.baseboard_fab2(sch_1):tp_ch_k_dimm_k0_rfu_0"
				( attribute "CDS_PHYS_NET_NAME" "TP_CH_K_DIMM_K0_RFU_0"
					( Origin gPackager )
				)
				( objectStatus "TP_CH_K_DIMM_K0_RFU_0" )
			)
			( signal "@baseboard_fab2_lib.baseboard_fab2(sch_1):tp_ch_k_dimm_k0_rfu_1"
				( attribute "CDS_PHYS_NET_NAME" "TP_CH_K_DIMM_K0_RFU_1"
					( Origin gPackager )
				)
				( objectStatus "TP_CH_K_DIMM_K0_RFU_1" )
			)
			( signal "@baseboard_fab2_lib.baseboard_fab2(sch_1):tp_ch_k_dimm_k0_rfu_2"
				( attribute "CDS_PHYS_NET_NAME" "TP_CH_K_DIMM_K0_RFU_2"
					( Origin gPackager )
				)
				( objectStatus "TP_CH_K_DIMM_K0_RFU_2" )
			)
			( signal "@baseboard_fab2_lib.baseboard_fab2(sch_1):tp_ch_k_dimm0_rfu_0"
				( attribute "CDS_PHYS_NET_NAME" "TP_CH_K_DIMM0_RFU_0"
					( Origin gPackager )
				)
				( objectStatus "TP_CH_K_DIMM0_RFU_0" )
			)
			( signal "@baseboard_fab2_lib.baseboard_fab2(sch_1):tp_ch_k_dimm0_rfu_1"
				( attribute "CDS_PHYS_NET_NAME" "TP_CH_K_DIMM0_RFU_1"
					( Origin gPackager )
				)
				( objectStatus "TP_CH_K_DIMM0_RFU_1" )
			)
			( signal "@baseboard_fab2_lib.baseboard_fab2(sch_1):tp_ch_k_dimm0_rfu_2"
				( attribute "CDS_PHYS_NET_NAME" "TP_CH_K_DIMM0_RFU_2"
					( Origin gPackager )
				)
				( objectStatus "TP_CH_K_DIMM0_RFU_2" )
			)
			( signal "@baseboard_fab2_lib.baseboard_fab2(sch_1):m_l_vref"
				( attribute "CDS_PHYS_NET_NAME" "M_L_VREF"
					( Origin gPackager )
				)
				( objectStatus "M_L_VREF" )
			)
			( signal "@baseboard_fab2_lib.baseboard_fab2(sch_1):tp_ch_l_dimm_l0_rfu_0"
				( attribute "CDS_PHYS_NET_NAME" "TP_CH_L_DIMM_L0_RFU_0"
					( Origin gPackager )
				)
				( objectStatus "TP_CH_L_DIMM_L0_RFU_0" )
			)
			( signal "@baseboard_fab2_lib.baseboard_fab2(sch_1):tp_ch_l_dimm_l0_rfu_1"
				( attribute "CDS_PHYS_NET_NAME" "TP_CH_L_DIMM_L0_RFU_1"
					( Origin gPackager )
				)
				( objectStatus "TP_CH_L_DIMM_L0_RFU_1" )
			)
			( signal "@baseboard_fab2_lib.baseboard_fab2(sch_1):tp_ch_l_dimm_l0_rfu_2"
				( attribute "CDS_PHYS_NET_NAME" "TP_CH_L_DIMM_L0_RFU_2"
					( Origin gPackager )
				)
				( objectStatus "TP_CH_L_DIMM_L0_RFU_2" )
			)
			( signal "@baseboard_fab2_lib.baseboard_fab2(sch_1):tp_ch_l_dimm0_rfu_0"
				( attribute "CDS_PHYS_NET_NAME" "TP_CH_L_DIMM0_RFU_0"
					( Origin gPackager )
				)
				( objectStatus "TP_CH_L_DIMM0_RFU_0" )
			)
			( signal "@baseboard_fab2_lib.baseboard_fab2(sch_1):tp_ch_l_dimm0_rfu_1"
				( attribute "CDS_PHYS_NET_NAME" "TP_CH_L_DIMM0_RFU_1"
					( Origin gPackager )
				)
				( objectStatus "TP_CH_L_DIMM0_RFU_1" )
			)
			( signal "@baseboard_fab2_lib.baseboard_fab2(sch_1):tp_ch_l_dimm0_rfu_2"
				( attribute "CDS_PHYS_NET_NAME" "TP_CH_L_DIMM0_RFU_2"
					( Origin gPackager )
				)
				( objectStatus "TP_CH_L_DIMM0_RFU_2" )
			)
			( signal "@baseboard_fab2_lib.baseboard_fab2(sch_1):m_m_vref"
				( attribute "CDS_PHYS_NET_NAME" "M_M_VREF"
					( Origin gPackager )
				)
				( objectStatus "M_M_VREF" )
			)
			( signal "@baseboard_fab2_lib.baseboard_fab2(sch_1):tp_ch_m_dimm_m0_rfu_0"
				( attribute "CDS_PHYS_NET_NAME" "TP_CH_M_DIMM_M0_RFU_0"
					( Origin gPackager )
				)
				( objectStatus "TP_CH_M_DIMM_M0_RFU_0" )
			)
			( signal "@baseboard_fab2_lib.baseboard_fab2(sch_1):tp_ch_m_dimm_m0_rfu_1"
				( attribute "CDS_PHYS_NET_NAME" "TP_CH_M_DIMM_M0_RFU_1"
					( Origin gPackager )
				)
				( objectStatus "TP_CH_M_DIMM_M0_RFU_1" )
			)
			( signal "@baseboard_fab2_lib.baseboard_fab2(sch_1):tp_ch_m_dimm_m0_rfu_2"
				( attribute "CDS_PHYS_NET_NAME" "TP_CH_M_DIMM_M0_RFU_2"
					( Origin gPackager )
				)
				( objectStatus "TP_CH_M_DIMM_M0_RFU_2" )
			)
			( signal "@baseboard_fab2_lib.baseboard_fab2(sch_1):tp_ch_m_dimm_m1_rfu_0"
				( attribute "CDS_PHYS_NET_NAME" "TP_CH_M_DIMM_M1_RFU_0"
					( Origin gPackager )
				)
				( objectStatus "TP_CH_M_DIMM_M1_RFU_0" )
			)
			( signal "@baseboard_fab2_lib.baseboard_fab2(sch_1):tp_ch_m_dimm_m1_rfu_1"
				( attribute "CDS_PHYS_NET_NAME" "TP_CH_M_DIMM_M1_RFU_1"
					( Origin gPackager )
				)
				( objectStatus "TP_CH_M_DIMM_M1_RFU_1" )
			)
			( signal "@baseboard_fab2_lib.baseboard_fab2(sch_1):tp_ch_m_dimm_m1_rfu_2"
				( attribute "CDS_PHYS_NET_NAME" "TP_CH_M_DIMM_M1_RFU_2"
					( Origin gPackager )
				)
				( objectStatus "TP_CH_M_DIMM_M1_RFU_2" )
			)
			( signal "@baseboard_fab2_lib.baseboard_fab2(sch_1):fm_adr_complete"
				( attribute "CDS_PHYS_NET_NAME" "FM_ADR_COMPLETE"
					( Origin gPackager )
				)
				( objectStatus "FM_ADR_COMPLETE" )
			)
			( signal "@baseboard_fab2_lib.baseboard_fab2(sch_1):fm_adr_complete_dly"
				( attribute "CDS_PHYS_NET_NAME" "FM_ADR_COMPLETE_DLY"
					( Origin gPackager )
				)
				( objectStatus "FM_ADR_COMPLETE_DLY" )
			)
			( signal "@baseboard_fab2_lib.baseboard_fab2(sch_1):fm_adr_complete_r"
				( attribute "CDS_PHYS_NET_NAME" "FM_ADR_COMPLETE_R"
					( Origin gPackager )
				)
				( objectStatus "FM_ADR_COMPLETE_R" )
			)
			( signal "@baseboard_fab2_lib.baseboard_fab2(sch_1):fm_adr_smi_gpio_n"
				( attribute "CDS_PHYS_NET_NAME" "FM_ADR_SMI_GPIO_N"
					( Origin gPackager )
				)
				( objectStatus "FM_ADR_SMI_GPIO_N" )
			)
			( signal "@baseboard_fab2_lib.baseboard_fab2(sch_1):irq_dimm_save_lvt3"
				( attribute "CDS_PHYS_NET_NAME" "IRQ_DIMM_SAVE_LVT3"
					( Origin gPackager )
				)
				( objectStatus "IRQ_DIMM_SAVE_LVT3" )
			)
			( signal "@baseboard_fab2_lib.baseboard_fab2(sch_1):irq_dimm_save_lvt3_n"
				( alias ( signalRef "@baseboard_fab2_lib.baseboard_fab2(sch_1):page144_irq_dimm_save_lvt3_n") )
				( attribute "CDS_PHYS_NET_NAME" "IRQ_DIMM_SAVE_LVT3_N"
					( Origin gPackager )
				)
				( attribute "PHYS_NET_NAME" "IRQ_DIMM_SAVE_LVT3_N"
					( Origin gPackager )
				)
				( objectStatus "IRQ_DIMM_SAVE_LVT3_N" )
			)
			( signal "@baseboard_fab2_lib.baseboard_fab2(sch_1):page144_fm_bios_mrc_debug_msg_dis_n"
				( attribute "CDS_PHYS_NET_NAME" "FM_BIOS_MRC_DEBUG_MSG_DIS_N"
					( Origin gPackager )
				)
				( attribute "PHYS_NET_NAME" "FM_BIOS_MRC_DEBUG_MSG_DIS_N"
					( Origin gFrontEnd )
				)
				( objectFlag fObjectAlias )
				( objectStatus "page144_fm_bios_mrc_debug_msg_dis_n" )
			)
			( signal "@baseboard_fab2_lib.baseboard_fab2(sch_1):fm_bmc_sys_throttle_r_n"
				( attribute "CDS_PHYS_NET_NAME" "FM_BMC_SYS_THROTTLE_R_N"
					( Origin gPackager )
				)
				( objectStatus "FM_BMC_SYS_THROTTLE_R_N" )
			)
			( signal "@baseboard_fab2_lib.baseboard_fab2(sch_1):spi_bmc_bt_cs1_n"
				( attribute "CDS_PHYS_NET_NAME" "SPI_BMC_BT_CS1_N"
					( Origin gPackager )
				)
				( objectStatus "SPI_BMC_BT_CS1_N" )
			)
			( signal "@baseboard_fab2_lib.baseboard_fab2(sch_1):irq_dimm_save_n"
				( attribute "CDS_PHYS_NET_NAME" "IRQ_DIMM_SAVE_N"
					( Origin gPackager )
				)
				( objectStatus "IRQ_DIMM_SAVE_N" )
			)
			( signal "@baseboard_fab2_lib.baseboard_fab2(sch_1):irq_dimm_save_r_n"
				( attribute "CDS_PHYS_NET_NAME" "IRQ_DIMM_SAVE_R_N"
					( Origin gPackager )
				)
				( objectStatus "IRQ_DIMM_SAVE_R_N" )
			)
			( signal "@baseboard_fab2_lib.baseboard_fab2(sch_1):p3v3"
				( alias ( signalRef "@baseboard_fab2_lib.baseboard_fab2(sch_1):page91_p3v3") )
				( alias ( signalRef "@baseboard_fab2_lib.baseboard_fab2(sch_1):page92_p3v3") )
				( alias ( signalRef "@baseboard_fab2_lib.baseboard_fab2(sch_1):page93_p3v3") )
				( alias ( signalRef "@baseboard_fab2_lib.baseboard_fab2(sch_1):page94_p3v3") )
				( alias ( signalRef "@baseboard_fab2_lib.baseboard_fab2(sch_1):page95_p3v3") )
				( alias ( signalRef "@baseboard_fab2_lib.baseboard_fab2(sch_1):page102_p3v3") )
				( alias ( signalRef "@baseboard_fab2_lib.baseboard_fab2(sch_1):page104_p3v3") )
				( alias ( signalRef "@baseboard_fab2_lib.baseboard_fab2(sch_1):page108_p3v3") )
				( alias ( signalRef "@baseboard_fab2_lib.baseboard_fab2(sch_1):page111_p3v3") )
				( alias ( signalRef "@baseboard_fab2_lib.baseboard_fab2(sch_1):page152_p3v3") )
				( alias ( signalRef "@baseboard_fab2_lib.baseboard_fab2(sch_1):page157_p3v3") )
				( alias ( signalRef "@baseboard_fab2_lib.baseboard_fab2(sch_1):page169_p3v3") )
				( alias ( signalRef "@baseboard_fab2_lib.baseboard_fab2(sch_1):page173_p3v3") )
				( alias ( signalRef "@baseboard_fab2_lib.baseboard_fab2(sch_1):page174_p3v3") )
				( alias ( signalRef "@baseboard_fab2_lib.baseboard_fab2(sch_1):page177_p3v3") )
				( alias ( signalRef "@baseboard_fab2_lib.baseboard_fab2(sch_1):page185_p3v3") )
				( alias ( signalRef "@baseboard_fab2_lib.baseboard_fab2(sch_1):page186_p3v3") )
				( alias ( signalRef "@baseboard_fab2_lib.baseboard_fab2(sch_1):page193_p3v3") )
				( alias ( signalRef "@baseboard_fab2_lib.baseboard_fab2(sch_1):page194_p3v3") )
				( alias ( signalRef "@baseboard_fab2_lib.baseboard_fab2(sch_1):page196_p3v3") )
				( alias ( signalRef "@baseboard_fab2_lib.baseboard_fab2(sch_1):page198_p3v3") )
				( alias ( signalRef "@baseboard_fab2_lib.baseboard_fab2(sch_1):page221_p3v3") )
				( alias ( signalRef "@baseboard_fab2_lib.baseboard_fab2(sch_1):page222_p3v3") )
				( alias ( signalRef "@baseboard_fab2_lib.baseboard_fab2(sch_1):page229_p3v3") )
				( alias ( signalRef "@baseboard_fab2_lib.baseboard_fab2(sch_1):page230_p3v3") )
				( attribute "VOLTAGE" "3.3V"
					( Units "uVoltage" "V" 1.000000)
					( Status sAliasFlattened )
					( Status sAliasConflict )
					( Origin gFrontEnd )
				)
				( attribute "CDS_PHYS_NET_NAME" "P3V3"
					( Origin gPackager )
				)
				( objectStatus "P3V3" )
			)
			( signal "@baseboard_fab2_lib.baseboard_fab2(sch_1):page91_p3v3"
				( attribute "VOLTAGE" "3.3V"
					( Units "uVoltage" "V" 1.000000)
					( Origin gFrontEnd )
				)
				( objectFlag fObjectAlias )
				( objectStatus "page91_p3v3" )
			)
			( signal "@baseboard_fab2_lib.baseboard_fab2(sch_1):page92_p3v3"
				( attribute "VOLTAGE" "3.3V"
					( Units "uVoltage" "V" 1.000000)
					( Origin gFrontEnd )
				)
				( objectFlag fObjectAlias )
				( objectStatus "page92_p3v3" )
			)
			( signal "@baseboard_fab2_lib.baseboard_fab2(sch_1):page93_p3v3"
				( attribute "VOLTAGE" "3.3V"
					( Units "uVoltage" "V" 1.000000)
					( Origin gFrontEnd )
				)
				( objectFlag fObjectAlias )
				( objectStatus "page93_p3v3" )
			)
			( signal "@baseboard_fab2_lib.baseboard_fab2(sch_1):page94_p3v3"
				( attribute "VOLTAGE" "+3.3"
					( Units "uVoltage" "V" 1.000000)
					( Origin gFrontEnd )
				)
				( objectFlag fObjectAlias )
				( objectStatus "page94_p3v3" )
			)
			( signal "@baseboard_fab2_lib.baseboard_fab2(sch_1):page95_p3v3"
				( attribute "VOLTAGE" "3.3V"
					( Units "uVoltage" "V" 1.000000)
					( Origin gFrontEnd )
				)
				( objectFlag fObjectAlias )
				( objectStatus "page95_p3v3" )
			)
			( signal "@baseboard_fab2_lib.baseboard_fab2(sch_1):page102_p3v3"
				( attribute "VOLTAGE" "3.3V"
					( Units "uVoltage" "V" 1.000000)
					( Origin gFrontEnd )
				)
				( objectFlag fObjectAlias )
				( objectStatus "page102_p3v3" )
			)
			( signal "@baseboard_fab2_lib.baseboard_fab2(sch_1):page104_p3v3"
				( attribute "VOLTAGE" "3.3V"
					( Units "uVoltage" "V" 1.000000)
					( Origin gFrontEnd )
				)
				( objectFlag fObjectAlias )
				( objectStatus "page104_p3v3" )
			)
			( signal "@baseboard_fab2_lib.baseboard_fab2(sch_1):page108_p3v3"
				( attribute "VOLTAGE" "3.3V"
					( Units "uVoltage" "V" 1.000000)
					( Origin gFrontEnd )
				)
				( objectFlag fObjectAlias )
				( objectStatus "page108_p3v3" )
			)
			( signal "@baseboard_fab2_lib.baseboard_fab2(sch_1):page111_p3v3"
				( attribute "VOLTAGE" "3.3V"
					( Units "uVoltage" "V" 1.000000)
					( Origin gFrontEnd )
				)
				( objectFlag fObjectAlias )
				( objectStatus "page111_p3v3" )
			)
			( signal "@baseboard_fab2_lib.baseboard_fab2(sch_1):page152_p3v3"
				( attribute "VOLTAGE" "3.3V"
					( Units "uVoltage" "V" 1.000000)
					( Origin gFrontEnd )
				)
				( objectFlag fObjectAlias )
				( objectStatus "page152_p3v3" )
			)
			( signal "@baseboard_fab2_lib.baseboard_fab2(sch_1):page157_p3v3"
				( attribute "VOLTAGE" "3.3V"
					( Units "uVoltage" "V" 1.000000)
					( Origin gFrontEnd )
				)
				( objectFlag fObjectAlias )
				( objectStatus "page157_p3v3" )
			)
			( signal "@baseboard_fab2_lib.baseboard_fab2(sch_1):page169_p3v3"
				( attribute "VOLTAGE" "3.3V"
					( Units "uVoltage" "V" 1.000000)
					( Origin gFrontEnd )
				)
				( objectFlag fObjectAlias )
				( objectStatus "page169_p3v3" )
			)
			( signal "@baseboard_fab2_lib.baseboard_fab2(sch_1):page173_p3v3"
				( attribute "VOLTAGE" "3.3V"
					( Units "uVoltage" "V" 1.000000)
					( Origin gFrontEnd )
				)
				( objectFlag fObjectAlias )
				( objectStatus "page173_p3v3" )
			)
			( signal "@baseboard_fab2_lib.baseboard_fab2(sch_1):page174_p3v3"
				( attribute "VOLTAGE" "3.3V"
					( Units "uVoltage" "V" 1.000000)
					( Origin gFrontEnd )
				)
				( objectFlag fObjectAlias )
				( objectStatus "page174_p3v3" )
			)
			( signal "@baseboard_fab2_lib.baseboard_fab2(sch_1):page177_p3v3"
				( attribute "VOLTAGE" "+3.3"
					( Units "uVoltage" "V" 1.000000)
					( Origin gFrontEnd )
				)
				( objectFlag fObjectAlias )
				( objectStatus "page177_p3v3" )
			)
			( signal "@baseboard_fab2_lib.baseboard_fab2(sch_1):page185_p3v3"
				( attribute "VOLTAGE" "3.3V"
					( Units "uVoltage" "V" 1.000000)
					( Origin gFrontEnd )
				)
				( objectFlag fObjectAlias )
				( objectStatus "page185_p3v3" )
			)
			( signal "@baseboard_fab2_lib.baseboard_fab2(sch_1):page186_p3v3"
				( attribute "VOLTAGE" "+3.3"
					( Units "uVoltage" "V" 1.000000)
					( Origin gFrontEnd )
				)
				( objectFlag fObjectAlias )
				( objectStatus "page186_p3v3" )
			)
			( signal "@baseboard_fab2_lib.baseboard_fab2(sch_1):page193_p3v3"
				( attribute "VOLTAGE" "+3.3V"
					( Units "uVoltage" "V" 1.000000)
					( Origin gFrontEnd )
				)
				( objectFlag fObjectAlias )
				( objectStatus "page193_p3v3" )
			)
			( signal "@baseboard_fab2_lib.baseboard_fab2(sch_1):page194_p3v3"
				( attribute "VOLTAGE" "+3.3V"
					( Units "uVoltage" "V" 1.000000)
					( Origin gFrontEnd )
				)
				( objectFlag fObjectAlias )
				( objectStatus "page194_p3v3" )
			)
			( signal "@baseboard_fab2_lib.baseboard_fab2(sch_1):page196_p3v3"
				( attribute "VOLTAGE" "3.3V"
					( Units "uVoltage" "V" 1.000000)
					( Origin gFrontEnd )
				)
				( objectFlag fObjectAlias )
				( objectStatus "page196_p3v3" )
			)
			( signal "@baseboard_fab2_lib.baseboard_fab2(sch_1):page198_p3v3"
				( attribute "VOLTAGE" "+3.3V"
					( Units "uVoltage" "V" 1.000000)
					( Origin gFrontEnd )
				)
				( objectFlag fObjectAlias )
				( objectStatus "page198_p3v3" )
			)
			( signal "@baseboard_fab2_lib.baseboard_fab2(sch_1):page221_p3v3"
				( attribute "VOLTAGE" "3.3V"
					( Units "uVoltage" "V" 1.000000)
					( Origin gFrontEnd )
				)
				( objectFlag fObjectAlias )
				( objectStatus "page221_p3v3" )
			)
			( signal "@baseboard_fab2_lib.baseboard_fab2(sch_1):page222_p3v3"
				( attribute "VOLTAGE" "3.3V"
					( Units "uVoltage" "V" 1.000000)
					( Origin gFrontEnd )
				)
				( objectFlag fObjectAlias )
				( objectStatus "page222_p3v3" )
			)
			( signal "@baseboard_fab2_lib.baseboard_fab2(sch_1):page229_p3v3"
				( attribute "VOLTAGE" "3.3V"
					( Units "uVoltage" "V" 1.000000)
					( Origin gFrontEnd )
				)
				( objectFlag fObjectAlias )
				( objectStatus "page229_p3v3" )
			)
			( signal "@baseboard_fab2_lib.baseboard_fab2(sch_1):page230_p3v3"
				( attribute "VOLTAGE" "3.3V"
					( Units "uVoltage" "V" 1.000000)
					( Origin gFrontEnd )
				)
				( objectFlag fObjectAlias )
				( objectStatus "page230_p3v3" )
			)
			( signal "@baseboard_fab2_lib.baseboard_fab2(sch_1):pwrgd_pvpp_abc"
				( attribute "CDS_PHYS_NET_NAME" "PWRGD_PVPP_ABC"
					( Origin gPackager )
				)
				( objectStatus "PWRGD_PVPP_ABC" )
			)
			( signal "@baseboard_fab2_lib.baseboard_fab2(sch_1):smb_ocp_fru_stby_lvc3_scl"
				( attribute "CDS_PHYS_NET_NAME" "SMB_OCP_FRU_STBY_LVC3_SCL"
					( Origin gPackager )
				)
				( objectStatus "SMB_OCP_FRU_STBY_LVC3_SCL" )
			)
			( signal "@baseboard_fab2_lib.baseboard_fab2(sch_1):smb_ocp_fru_stby_lvc3_sda"
				( attribute "CDS_PHYS_NET_NAME" "SMB_OCP_FRU_STBY_LVC3_SDA"
					( Origin gPackager )
				)
				( objectStatus "SMB_OCP_FRU_STBY_LVC3_SDA" )
			)
			( signal "@baseboard_fab2_lib.baseboard_fab2(sch_1):tp_hfi_io_conn0_rsvd_17"
				( attribute "CDS_PHYS_NET_NAME" "TP_HFI_IO_CONN0_RSVD_17"
					( Origin gPackager )
				)
				( objectStatus "TP_HFI_IO_CONN0_RSVD_17" )
			)
			( signal "@baseboard_fab2_lib.baseboard_fab2(sch_1):fm_cpu0_fivr_fault_lvt3"
				( attribute "CDS_PHYS_NET_NAME" "FM_CPU0_FIVR_FAULT_LVT3"
					( Origin gPackager )
				)
				( objectStatus "FM_CPU0_FIVR_FAULT_LVT3" )
			)
			( signal "@baseboard_fab2_lib.baseboard_fab2(sch_1):fm_cpu0_fivr_fault_r_lvt3"
				( attribute "CDS_PHYS_NET_NAME" "FM_CPU0_FIVR_FAULT_R_LVT3"
					( Origin gPackager )
				)
				( objectStatus "FM_CPU0_FIVR_FAULT_R_LVT3" )
			)
			( signal "@baseboard_fab2_lib.baseboard_fab2(sch_1):fm_cpu0_thermtrip_lvt3_n"
				( attribute "CDS_PHYS_NET_NAME" "FM_CPU0_THERMTRIP_LVT3_N"
					( Origin gPackager )
				)
				( objectStatus "FM_CPU0_THERMTRIP_LVT3_N" )
			)
			( signal "@baseboard_fab2_lib.baseboard_fab2(sch_1):fm_cpu0_thermtrip_lvt3_r_n"
				( attribute "CDS_PHYS_NET_NAME" "FM_CPU0_THERMTRIP_LVT3_R_N"
					( Origin gPackager )
				)
				( objectStatus "FM_CPU0_THERMTRIP_LVT3_R_N" )
			)
			( signal "@baseboard_fab2_lib.baseboard_fab2(sch_1):fm_cpu1_fivr_fault_lvt3"
				( attribute "CDS_PHYS_NET_NAME" "FM_CPU1_FIVR_FAULT_LVT3"
					( Origin gPackager )
				)
				( objectStatus "FM_CPU1_FIVR_FAULT_LVT3" )
			)
			( signal "@baseboard_fab2_lib.baseboard_fab2(sch_1):fm_cpu1_fivr_fault_r_lvt3"
				( attribute "CDS_PHYS_NET_NAME" "FM_CPU1_FIVR_FAULT_R_LVT3"
					( Origin gPackager )
				)
				( objectStatus "FM_CPU1_FIVR_FAULT_R_LVT3" )
			)
			( signal "@baseboard_fab2_lib.baseboard_fab2(sch_1):fm_cpu1_thermtrip_lvt3_n"
				( attribute "CDS_PHYS_NET_NAME" "FM_CPU1_THERMTRIP_LVT3_N"
					( Origin gPackager )
				)
				( objectStatus "FM_CPU1_THERMTRIP_LVT3_N" )
			)
			( signal "@baseboard_fab2_lib.baseboard_fab2(sch_1):fm_cpu1_thermtrip_lvt3_r_n"
				( attribute "CDS_PHYS_NET_NAME" "FM_CPU1_THERMTRIP_LVT3_R_N"
					( Origin gPackager )
				)
				( objectStatus "FM_CPU1_THERMTRIP_LVT3_R_N" )
			)
			( signal "@baseboard_fab2_lib.baseboard_fab2(sch_1):fm_cpu_caterr_lvt3_n"
				( attribute "CDS_PHYS_NET_NAME" "FM_CPU_CATERR_LVT3_N"
					( Origin gPackager )
				)
				( attribute "PHYS_NET_NAME" "FM_CPU_CATERR_LVT3_N"
					( Origin gPackager )
				)
				( objectStatus "FM_CPU_CATERR_LVT3_N" )
			)
			( signal "@baseboard_fab2_lib.baseboard_fab2(sch_1):fm_cpu_caterr_lvt3_r2_n"
				( attribute "CDS_PHYS_NET_NAME" "FM_CPU_CATERR_LVT3_R2_N"
					( Origin gPackager )
				)
				( objectStatus "FM_CPU_CATERR_LVT3_R2_N" )
			)
			( signal "@baseboard_fab2_lib.baseboard_fab2(sch_1):fm_cpu_err2_lvt3_n"
				( attribute "CDS_PHYS_NET_NAME" "FM_CPU_ERR2_LVT3_N"
					( Origin gPackager )
				)
				( attribute "PHYS_NET_NAME" "FM_CPU_ERR2_LVT3_N"
					( Origin gPackager )
				)
				( objectStatus "FM_CPU_ERR2_LVT3_N" )
			)
			( signal "@baseboard_fab2_lib.baseboard_fab2(sch_1):fm_cpu_err2_lvt3_r_n"
				( attribute "CDS_PHYS_NET_NAME" "FM_CPU_ERR2_LVT3_R_N"
					( Origin gPackager )
				)
				( objectStatus "FM_CPU_ERR2_LVT3_R_N" )
			)
			( signal "@baseboard_fab2_lib.baseboard_fab2(sch_1):fm_cpu_msmi_lvt3_n"
				( attribute "CDS_PHYS_NET_NAME" "FM_CPU_MSMI_LVT3_N"
					( Origin gPackager )
				)
				( attribute "PHYS_NET_NAME" "FM_CPU_MSMI_LVT3_N"
					( Origin gPackager )
				)
				( objectStatus "FM_CPU_MSMI_LVT3_N" )
			)
			( signal "@baseboard_fab2_lib.baseboard_fab2(sch_1):fm_cpu_msmi_lvt3_r_n"
				( attribute "CDS_PHYS_NET_NAME" "FM_CPU_MSMI_LVT3_R_N"
					( Origin gPackager )
				)
				( objectStatus "FM_CPU_MSMI_LVT3_R_N" )
			)
			( signal "@baseboard_fab2_lib.baseboard_fab2(sch_1):h_cpu_caterr_g_n"
				( attribute "CDS_PHYS_NET_NAME" "H_CPU_CATERR_G_N"
					( Origin gPackager )
				)
				( objectStatus "H_CPU_CATERR_G_N" )
			)
			( signal "@baseboard_fab2_lib.baseboard_fab2(sch_1):h_cpu_err2_g_r_n"
				( attribute "CDS_PHYS_NET_NAME" "H_CPU_ERR2_G_R_N"
					( Origin gPackager )
				)
				( objectStatus "H_CPU_ERR2_G_R_N" )
			)
			( signal "@baseboard_fab2_lib.baseboard_fab2(sch_1):h_cpu_err2_gtl_n"
				( attribute "CDS_PHYS_NET_NAME" "H_CPU_ERR2_GTL_N"
					( Origin gPackager )
				)
				( objectStatus "H_CPU_ERR2_GTL_N" )
			)
			( signal "@baseboard_fab2_lib.baseboard_fab2(sch_1):h_cpu_msmi_g_n"
				( attribute "CDS_PHYS_NET_NAME" "H_CPU_MSMI_G_N"
					( Origin gPackager )
				)
				( objectStatus "H_CPU_MSMI_G_N" )
			)
			( signal "@baseboard_fab2_lib.baseboard_fab2(sch_1):p0v7_gtl2104_vref_0"
				( alias ( signalRef "@baseboard_fab2_lib.baseboard_fab2(sch_1):page92_p0v7_gtl2104_vref_0") )
				( attribute "VOLTAGE" "+0.7 V"
					( Units "uVoltage" "V" 1.000000)
					( Status sAliasFlattened )
					( Origin gFrontEnd )
				)
				( attribute "CDS_PHYS_NET_NAME" "P0V7_GTL2104_VREF_0"
					( Origin gPackager )
				)
				( objectStatus "P0V7_GTL2104_VREF_0" )
			)
			( signal "@baseboard_fab2_lib.baseboard_fab2(sch_1):page92_p0v7_gtl2104_vref_0"
				( attribute "VOLTAGE" "+0.7 V"
					( Units "uVoltage" "V" 1.000000)
					( Origin gFrontEnd )
				)
				( objectFlag fObjectAlias )
				( objectStatus "page92_p0v7_gtl2104_vref_0" )
			)
			( signal "@baseboard_fab2_lib.baseboard_fab2(sch_1):p0v7_gtl2104_vref_1"
				( alias ( signalRef "@baseboard_fab2_lib.baseboard_fab2(sch_1):page92_p0v7_gtl2104_vref_1") )
				( attribute "VOLTAGE" "+0.7 V"
					( Units "uVoltage" "V" 1.000000)
					( Status sAliasFlattened )
					( Origin gFrontEnd )
				)
				( attribute "CDS_PHYS_NET_NAME" "P0V7_GTL2104_VREF_1"
					( Origin gPackager )
				)
				( objectStatus "P0V7_GTL2104_VREF_1" )
			)
			( signal "@baseboard_fab2_lib.baseboard_fab2(sch_1):page92_p0v7_gtl2104_vref_1"
				( attribute "VOLTAGE" "+0.7 V"
					( Units "uVoltage" "V" 1.000000)
					( Origin gFrontEnd )
				)
				( objectFlag fObjectAlias )
				( objectStatus "page92_p0v7_gtl2104_vref_1" )
			)
			( signal "@baseboard_fab2_lib.baseboard_fab2(sch_1):pd_gtl2104_dir_0"
				( attribute "CDS_PHYS_NET_NAME" "PD_GTL2104_DIR_0"
					( Origin gPackager )
				)
				( objectStatus "PD_GTL2104_DIR_0" )
			)
			( signal "@baseboard_fab2_lib.baseboard_fab2(sch_1):pd_gtl2104_dir_1"
				( attribute "CDS_PHYS_NET_NAME" "PD_GTL2104_DIR_1"
					( Origin gPackager )
				)
				( objectStatus "PD_GTL2104_DIR_1" )
			)
			( signal "@baseboard_fab2_lib.baseboard_fab2(sch_1):pwrgd_cpupwrgd"
				( attribute "CDS_PHYS_NET_NAME" "PWRGD_CPUPWRGD"
					( Origin gPackager )
				)
				( objectStatus "PWRGD_CPUPWRGD" )
			)
			( signal "@baseboard_fab2_lib.baseboard_fab2(sch_1):pwrgd_cpupwrgd_gtl"
				( attribute "CDS_PHYS_NET_NAME" "PWRGD_CPUPWRGD_GTL"
					( Origin gPackager )
				)
				( objectStatus "PWRGD_CPUPWRGD_GTL" )
			)
			( signal "@baseboard_fab2_lib.baseboard_fab2(sch_1):pwrgd_cpupwrgd_r1"
				( attribute "CDS_PHYS_NET_NAME" "PWRGD_CPUPWRGD_R1"
					( Origin gPackager )
				)
				( objectStatus "PWRGD_CPUPWRGD_R1" )
			)
			( signal "@baseboard_fab2_lib.baseboard_fab2(sch_1):fm_cpu0_prochot_lvt3_bmc_n"
				( attribute "CDS_PHYS_NET_NAME" "FM_CPU0_PROCHOT_LVT3_BMC_N"
					( Origin gPackager )
				)
				( attribute "PHYS_NET_NAME" "FM_CPU0_PROCHOT_LVT3_BMC_N"
					( Origin gPackager )
				)
				( objectStatus "FM_CPU0_PROCHOT_LVT3_BMC_N" )
			)
			( signal "@baseboard_fab2_lib.baseboard_fab2(sch_1):fm_cpu0_prochot_lvt3_k_n"
				( attribute "CDS_PHYS_NET_NAME" "FM_CPU0_PROCHOT_LVT3_K_N"
					( Origin gPackager )
				)
				( objectStatus "FM_CPU0_PROCHOT_LVT3_K_N" )
			)
			( signal "@baseboard_fab2_lib.baseboard_fab2(sch_1):fm_cpu0_prochot_lvt3_n"
				( attribute "CDS_PHYS_NET_NAME" "FM_CPU0_PROCHOT_LVT3_N"
					( Origin gPackager )
				)
				( objectStatus "FM_CPU0_PROCHOT_LVT3_N" )
			)
			( signal "@baseboard_fab2_lib.baseboard_fab2(sch_1):fm_cpu0_prochot_lvt3_r_n"
				( attribute "CDS_PHYS_NET_NAME" "FM_CPU0_PROCHOT_LVT3_R_N"
					( Origin gPackager )
				)
				( objectStatus "FM_CPU0_PROCHOT_LVT3_R_N" )
			)
			( signal "@baseboard_fab2_lib.baseboard_fab2(sch_1):fm_cpu0_prochot_pch_n"
				( attribute "CDS_PHYS_NET_NAME" "FM_CPU0_PROCHOT_PCH_N"
					( Origin gPackager )
				)
				( objectStatus "FM_CPU0_PROCHOT_PCH_N" )
			)
			( signal "@baseboard_fab2_lib.baseboard_fab2(sch_1):fm_cpu1_prochot_lvt3_bmc_n"
				( attribute "CDS_PHYS_NET_NAME" "FM_CPU1_PROCHOT_LVT3_BMC_N"
					( Origin gPackager )
				)
				( attribute "PHYS_NET_NAME" "FM_CPU1_PROCHOT_LVT3_BMC_N"
					( Origin gPackager )
				)
				( objectStatus "FM_CPU1_PROCHOT_LVT3_BMC_N" )
			)
			( signal "@baseboard_fab2_lib.baseboard_fab2(sch_1):fm_cpu1_prochot_lvt3_k_n"
				( attribute "CDS_PHYS_NET_NAME" "FM_CPU1_PROCHOT_LVT3_K_N"
					( Origin gPackager )
				)
				( objectStatus "FM_CPU1_PROCHOT_LVT3_K_N" )
			)
			( signal "@baseboard_fab2_lib.baseboard_fab2(sch_1):fm_cpu1_prochot_lvt3_n"
				( attribute "CDS_PHYS_NET_NAME" "FM_CPU1_PROCHOT_LVT3_N"
					( Origin gPackager )
				)
				( objectStatus "FM_CPU1_PROCHOT_LVT3_N" )
			)
			( signal "@baseboard_fab2_lib.baseboard_fab2(sch_1):fm_cpu1_prochot_lvt3_r_n"
				( attribute "CDS_PHYS_NET_NAME" "FM_CPU1_PROCHOT_LVT3_R_N"
					( Origin gPackager )
				)
				( objectStatus "FM_CPU1_PROCHOT_LVT3_R_N" )
			)
			( signal "@baseboard_fab2_lib.baseboard_fab2(sch_1):fm_cpu1_prochot_pch_n"
				( attribute "CDS_PHYS_NET_NAME" "FM_CPU1_PROCHOT_PCH_N"
					( Origin gPackager )
				)
				( objectStatus "FM_CPU1_PROCHOT_PCH_N" )
			)
			( signal "@baseboard_fab2_lib.baseboard_fab2(sch_1):fm_cpu_err0_lvt3_bmc_n"
				( attribute "CDS_PHYS_NET_NAME" "FM_CPU_ERR0_LVT3_BMC_N"
					( Origin gPackager )
				)
				( attribute "PHYS_NET_NAME" "FM_CPU_ERR0_LVT3_BMC_N"
					( Origin gPackager )
				)
				( objectStatus "FM_CPU_ERR0_LVT3_BMC_N" )
			)
			( signal "@baseboard_fab2_lib.baseboard_fab2(sch_1):fm_cpu_err0_lvt3_k_n"
				( attribute "CDS_PHYS_NET_NAME" "FM_CPU_ERR0_LVT3_K_N"
					( Origin gPackager )
				)
				( objectStatus "FM_CPU_ERR0_LVT3_K_N" )
			)
			( signal "@baseboard_fab2_lib.baseboard_fab2(sch_1):fm_cpu_err0_lvt3_n"
				( attribute "CDS_PHYS_NET_NAME" "FM_CPU_ERR0_LVT3_N"
					( Origin gPackager )
				)
				( objectStatus "FM_CPU_ERR0_LVT3_N" )
			)
			( signal "@baseboard_fab2_lib.baseboard_fab2(sch_1):fm_cpu_err0_lvt3_r_n"
				( attribute "CDS_PHYS_NET_NAME" "FM_CPU_ERR0_LVT3_R_N"
					( Origin gPackager )
				)
				( objectStatus "FM_CPU_ERR0_LVT3_R_N" )
			)
			( signal "@baseboard_fab2_lib.baseboard_fab2(sch_1):fm_cpu_err0_pch_n"
				( attribute "CDS_PHYS_NET_NAME" "FM_CPU_ERR0_PCH_N"
					( Origin gPackager )
				)
				( objectStatus "FM_CPU_ERR0_PCH_N" )
			)
			( signal "@baseboard_fab2_lib.baseboard_fab2(sch_1):fm_cpu_err1_lvt3_bmc_n"
				( attribute "CDS_PHYS_NET_NAME" "FM_CPU_ERR1_LVT3_BMC_N"
					( Origin gPackager )
				)
				( attribute "PHYS_NET_NAME" "FM_CPU_ERR1_LVT3_BMC_N"
					( Origin gPackager )
				)
				( objectStatus "FM_CPU_ERR1_LVT3_BMC_N" )
			)
			( signal "@baseboard_fab2_lib.baseboard_fab2(sch_1):fm_cpu_err1_lvt3_k_n"
				( attribute "CDS_PHYS_NET_NAME" "FM_CPU_ERR1_LVT3_K_N"
					( Origin gPackager )
				)
				( objectStatus "FM_CPU_ERR1_LVT3_K_N" )
			)
			( signal "@baseboard_fab2_lib.baseboard_fab2(sch_1):fm_cpu_err1_lvt3_n"
				( attribute "CDS_PHYS_NET_NAME" "FM_CPU_ERR1_LVT3_N"
					( Origin gPackager )
				)
				( objectStatus "FM_CPU_ERR1_LVT3_N" )
			)
			( signal "@baseboard_fab2_lib.baseboard_fab2(sch_1):fm_cpu_err1_lvt3_r_n"
				( attribute "CDS_PHYS_NET_NAME" "FM_CPU_ERR1_LVT3_R_N"
					( Origin gPackager )
				)
				( objectStatus "FM_CPU_ERR1_LVT3_R_N" )
			)
			( signal "@baseboard_fab2_lib.baseboard_fab2(sch_1):fm_cpu_err1_pch_n"
				( attribute "CDS_PHYS_NET_NAME" "FM_CPU_ERR1_PCH_N"
					( Origin gPackager )
				)
				( objectStatus "FM_CPU_ERR1_PCH_N" )
			)
			( signal "@baseboard_fab2_lib.baseboard_fab2(sch_1):h_cpu0_prochot_g_pch_n"
				( attribute "CDS_PHYS_NET_NAME" "H_CPU0_PROCHOT_G_PCH_N"
					( Origin gPackager )
				)
				( objectStatus "H_CPU0_PROCHOT_G_PCH_N" )
			)
			( signal "@baseboard_fab2_lib.baseboard_fab2(sch_1):h_cpu0_prochot_g_r_n"
				( attribute "CDS_PHYS_NET_NAME" "H_CPU0_PROCHOT_G_R_N"
					( Origin gPackager )
				)
				( objectStatus "H_CPU0_PROCHOT_G_R_N" )
			)
			( signal "@baseboard_fab2_lib.baseboard_fab2(sch_1):h_cpu1_prochot_g_pch_n"
				( attribute "CDS_PHYS_NET_NAME" "H_CPU1_PROCHOT_G_PCH_N"
					( Origin gPackager )
				)
				( objectStatus "H_CPU1_PROCHOT_G_PCH_N" )
			)
			( signal "@baseboard_fab2_lib.baseboard_fab2(sch_1):h_cpu1_prochot_g_r_n"
				( attribute "CDS_PHYS_NET_NAME" "H_CPU1_PROCHOT_G_R_N"
					( Origin gPackager )
				)
				( objectStatus "H_CPU1_PROCHOT_G_R_N" )
			)
			( signal "@baseboard_fab2_lib.baseboard_fab2(sch_1):h_cpu_err0_gtl_n"
				( attribute "CDS_PHYS_NET_NAME" "H_CPU_ERR0_GTL_N"
					( Origin gPackager )
				)
				( objectStatus "H_CPU_ERR0_GTL_N" )
			)
			( signal "@baseboard_fab2_lib.baseboard_fab2(sch_1):h_cpu_err0_gtl_r_n"
				( attribute "CDS_PHYS_NET_NAME" "H_CPU_ERR0_GTL_R_N"
					( Origin gPackager )
				)
				( objectStatus "H_CPU_ERR0_GTL_R_N" )
			)
			( signal "@baseboard_fab2_lib.baseboard_fab2(sch_1):h_cpu_err0_pch_n"
				( attribute "CDS_PHYS_NET_NAME" "H_CPU_ERR0_PCH_N"
					( Origin gPackager )
				)
				( objectStatus "H_CPU_ERR0_PCH_N" )
			)
			( signal "@baseboard_fab2_lib.baseboard_fab2(sch_1):h_cpu_err1_gtl_n"
				( attribute "CDS_PHYS_NET_NAME" "H_CPU_ERR1_GTL_N"
					( Origin gPackager )
				)
				( objectStatus "H_CPU_ERR1_GTL_N" )
			)
			( signal "@baseboard_fab2_lib.baseboard_fab2(sch_1):h_cpu_err1_gtl_r_n"
				( attribute "CDS_PHYS_NET_NAME" "H_CPU_ERR1_GTL_R_N"
					( Origin gPackager )
				)
				( objectStatus "H_CPU_ERR1_GTL_R_N" )
			)
			( signal "@baseboard_fab2_lib.baseboard_fab2(sch_1):h_cpu_err1_pch_n"
				( attribute "CDS_PHYS_NET_NAME" "H_CPU_ERR1_PCH_N"
					( Origin gPackager )
				)
				( objectStatus "H_CPU_ERR1_PCH_N" )
			)
			( signal "@baseboard_fab2_lib.baseboard_fab2(sch_1):p0v7_gtl2104_5_vref"
				( alias ( signalRef "@baseboard_fab2_lib.baseboard_fab2(sch_1):page93_p0v7_gtl2104_5_vref") )
				( attribute "VOLTAGE" "0.734"
					( Units "uVoltage" "V" 1.000000)
					( Status sAliasFlattened )
					( Origin gFrontEnd )
				)
				( attribute "CDS_PHYS_NET_NAME" "P0V7_GTL2104_5_VREF"
					( Origin gPackager )
				)
				( objectStatus "P0V7_GTL2104_5_VREF" )
			)
			( signal "@baseboard_fab2_lib.baseboard_fab2(sch_1):page93_p0v7_gtl2104_5_vref"
				( attribute "VOLTAGE" "0.734"
					( Units "uVoltage" "V" 1.000000)
					( Origin gFrontEnd )
				)
				( objectFlag fObjectAlias )
				( objectStatus "page93_p0v7_gtl2104_5_vref" )
			)
			( signal "@baseboard_fab2_lib.baseboard_fab2(sch_1):pd_gtl2104_4_dir"
				( attribute "CDS_PHYS_NET_NAME" "PD_GTL2104_4_DIR"
					( Origin gPackager )
				)
				( objectStatus "PD_GTL2104_4_DIR" )
			)
			( signal "@baseboard_fab2_lib.baseboard_fab2(sch_1):fm_dimm_event_fet"
				( attribute "CDS_PHYS_NET_NAME" "FM_DIMM_EVENT_FET"
					( Origin gPackager )
				)
				( objectStatus "FM_DIMM_EVENT_FET" )
			)
			( signal "@baseboard_fab2_lib.baseboard_fab2(sch_1):fm_mem_therm_event_lvt3_n"
				( attribute "CDS_PHYS_NET_NAME" "FM_MEM_THERM_EVENT_LVT3_N"
					( Origin gPackager )
				)
				( objectStatus "FM_MEM_THERM_EVENT_LVT3_N" )
			)
			( signal "@baseboard_fab2_lib.baseboard_fab2(sch_1):h_cpu0_memabc_memhot"
				( attribute "CDS_PHYS_NET_NAME" "H_CPU0_MEMABC_MEMHOT"
					( Origin gPackager )
				)
				( objectStatus "H_CPU0_MEMABC_MEMHOT" )
			)
			( signal "@baseboard_fab2_lib.baseboard_fab2(sch_1):h_cpu0_memdef_memhot"
				( attribute "CDS_PHYS_NET_NAME" "H_CPU0_MEMDEF_MEMHOT"
					( Origin gPackager )
				)
				( objectStatus "H_CPU0_MEMDEF_MEMHOT" )
			)
			( signal "@baseboard_fab2_lib.baseboard_fab2(sch_1):h_cpu1_memghj_memhot"
				( attribute "CDS_PHYS_NET_NAME" "H_CPU1_MEMGHJ_MEMHOT"
					( Origin gPackager )
				)
				( objectStatus "H_CPU1_MEMGHJ_MEMHOT" )
			)
			( signal "@baseboard_fab2_lib.baseboard_fab2(sch_1):h_cpu1_memklm_memhot"
				( attribute "CDS_PHYS_NET_NAME" "H_CPU1_MEMKLM_MEMHOT"
					( Origin gPackager )
				)
				( objectStatus "H_CPU1_MEMKLM_MEMHOT" )
			)
			( signal "@baseboard_fab2_lib.baseboard_fab2(sch_1):irq_pvddq_abc_vrhot_lvt3_n"
				( attribute "CDS_PHYS_NET_NAME" "IRQ_PVDDQ_ABC_VRHOT_LVT3_N"
					( Origin gPackager )
				)
				( attribute "PHYS_NET_NAME" "IRQ_PVDDQ_ABC_VRHOT_LVT3_N"
					( Origin gPackager )
				)
				( objectStatus "IRQ_PVDDQ_ABC_VRHOT_LVT3_N" )
			)
			( signal "@baseboard_fab2_lib.baseboard_fab2(sch_1):irq_pvddq_def_vrhot_lvt3_n"
				( attribute "CDS_PHYS_NET_NAME" "IRQ_PVDDQ_DEF_VRHOT_LVT3_N"
					( Origin gPackager )
				)
				( attribute "PHYS_NET_NAME" "IRQ_PVDDQ_DEF_VRHOT_LVT3_N"
					( Origin gPackager )
				)
				( objectStatus "IRQ_PVDDQ_DEF_VRHOT_LVT3_N" )
			)
			( signal "@baseboard_fab2_lib.baseboard_fab2(sch_1):fm_bmc_nmi_n_r"
				( attribute "CDS_PHYS_NET_NAME" "FM_BMC_NMI_N_R"
					( Origin gPackager )
				)
				( objectStatus "FM_BMC_NMI_N_R" )
			)
			( signal "@baseboard_fab2_lib.baseboard_fab2(sch_1):irq_pvddq_ghj_vrhot_lvt3_n"
				( attribute "CDS_PHYS_NET_NAME" "IRQ_PVDDQ_GHJ_VRHOT_LVT3_N"
					( Origin gPackager )
				)
				( attribute "PHYS_NET_NAME" "IRQ_PVDDQ_GHJ_VRHOT_LVT3_N"
					( Origin gPackager )
				)
				( objectStatus "IRQ_PVDDQ_GHJ_VRHOT_LVT3_N" )
			)
			( signal "@baseboard_fab2_lib.baseboard_fab2(sch_1):irq_pvddq_klm_vrhot_lvt3_n"
				( attribute "CDS_PHYS_NET_NAME" "IRQ_PVDDQ_KLM_VRHOT_LVT3_N"
					( Origin gPackager )
				)
				( attribute "PHYS_NET_NAME" "IRQ_PVDDQ_KLM_VRHOT_LVT3_N"
					( Origin gPackager )
				)
				( objectStatus "IRQ_PVDDQ_KLM_VRHOT_LVT3_N" )
			)
			( signal "@baseboard_fab2_lib.baseboard_fab2(sch_1):page148_p3v3_usb2a_alg"
				( objectFlag fObjectAlias )
				( objectStatus "page148_p3v3_usb2a_alg" )
			)
			( signal "@baseboard_fab2_lib.baseboard_fab2(sch_1):fm_pvccin_cpu0_pwr_in_alert_n"
				( attribute "CDS_PHYS_NET_NAME" "FM_PVCCIN_CPU0_PWR_IN_ALERT_N"
					( Origin gPackager )
				)
				( objectStatus "FM_PVCCIN_CPU0_PWR_IN_ALERT_N" )
			)
			( signal "@baseboard_fab2_lib.baseboard_fab2(sch_1):fm_pvccin_cpu1_pwr_in_alert_n"
				( attribute "CDS_PHYS_NET_NAME" "FM_PVCCIN_CPU1_PWR_IN_ALERT_N"
					( Origin gPackager )
				)
				( objectStatus "FM_PVCCIN_CPU1_PWR_IN_ALERT_N" )
			)
			( signal "@baseboard_fab2_lib.baseboard_fab2(sch_1):fm_pwrbrk_n"
				( attribute "CDS_PHYS_NET_NAME" "FM_PWRBRK_N"
					( Origin gPackager )
				)
				( objectStatus "FM_PWRBRK_N" )
			)
			( signal "@baseboard_fab2_lib.baseboard_fab2(sch_1):fm_sys_throttle_lvc3"
				( attribute "CDS_PHYS_NET_NAME" "FM_SYS_THROTTLE_LVC3"
					( Origin gPackager )
				)
				( objectStatus "FM_SYS_THROTTLE_LVC3" )
			)
			( signal "@baseboard_fab2_lib.baseboard_fab2(sch_1):fm_throttle_n"
				( attribute "CDS_PHYS_NET_NAME" "FM_THROTTLE_N"
					( Origin gPackager )
				)
				( attribute "PHYS_NET_NAME" "FM_THROTTLE_N"
					( Origin gPackager )
				)
				( objectStatus "FM_THROTTLE_N" )
			)
			( signal "@baseboard_fab2_lib.baseboard_fab2(sch_1):fm_throttle_r_n"
				( attribute "CDS_PHYS_NET_NAME" "FM_THROTTLE_R_N"
					( Origin gPackager )
				)
				( objectStatus "FM_THROTTLE_R_N" )
			)
			( signal "@baseboard_fab2_lib.baseboard_fab2(sch_1):irq_cpu0_prochot_g_n"
				( attribute "CDS_PHYS_NET_NAME" "IRQ_CPU0_PROCHOT_G_N"
					( Origin gPackager )
				)
				( objectStatus "IRQ_CPU0_PROCHOT_G_N" )
			)
			( signal "@baseboard_fab2_lib.baseboard_fab2(sch_1):irq_cpu0_vrhot"
				( attribute "CDS_PHYS_NET_NAME" "IRQ_CPU0_VRHOT"
					( Origin gPackager )
				)
				( objectStatus "IRQ_CPU0_VRHOT" )
			)
			( signal "@baseboard_fab2_lib.baseboard_fab2(sch_1):irq_cpu1_prochot_g_n"
				( attribute "CDS_PHYS_NET_NAME" "IRQ_CPU1_PROCHOT_G_N"
					( Origin gPackager )
				)
				( objectStatus "IRQ_CPU1_PROCHOT_G_N" )
			)
			( signal "@baseboard_fab2_lib.baseboard_fab2(sch_1):irq_cpu1_vrhot"
				( attribute "CDS_PHYS_NET_NAME" "IRQ_CPU1_VRHOT"
					( Origin gPackager )
				)
				( objectStatus "IRQ_CPU1_VRHOT" )
			)
			( signal "@baseboard_fab2_lib.baseboard_fab2(sch_1):irq_pvccin_cpu0_vrhot_lvc3_n"
				( attribute "CDS_PHYS_NET_NAME" "IRQ_PVCCIN_CPU0_VRHOT_LVC3_N"
					( Origin gPackager )
				)
				( attribute "PHYS_NET_NAME" "IRQ_PVCCIN_CPU0_VRHOT_LVC3_N"
					( Origin gPackager )
				)
				( objectStatus "IRQ_PVCCIN_CPU0_VRHOT_LVC3_N" )
			)
			( signal "@baseboard_fab2_lib.baseboard_fab2(sch_1):irq_pvccin_cpu1_vrhot_lvc3_n"
				( attribute "CDS_PHYS_NET_NAME" "IRQ_PVCCIN_CPU1_VRHOT_LVC3_N"
					( Origin gPackager )
				)
				( attribute "PHYS_NET_NAME" "IRQ_PVCCIN_CPU1_VRHOT_LVC3_N"
					( Origin gPackager )
				)
				( objectStatus "IRQ_PVCCIN_CPU1_VRHOT_LVC3_N" )
			)
			( signal "@baseboard_fab2_lib.baseboard_fab2(sch_1):pd_gtl2014_1_vref"
				( attribute "CDS_PHYS_NET_NAME" "PD_GTL2014_1_VREF"
					( Origin gPackager )
				)
				( objectStatus "PD_GTL2014_1_VREF" )
			)
			( signal "@baseboard_fab2_lib.baseboard_fab2(sch_1):pd_gtl2014_2_vref"
				( attribute "CDS_PHYS_NET_NAME" "PD_GTL2014_2_VREF"
					( Origin gPackager )
				)
				( objectStatus "PD_GTL2014_2_VREF" )
			)
			( signal "@baseboard_fab2_lib.baseboard_fab2(sch_1):pu_gtl2014_1_dir"
				( attribute "CDS_PHYS_NET_NAME" "PU_GTL2014_1_DIR"
					( Origin gPackager )
				)
				( objectStatus "PU_GTL2014_1_DIR" )
			)
			( signal "@baseboard_fab2_lib.baseboard_fab2(sch_1):pu_gtl2014_2_dir"
				( attribute "CDS_PHYS_NET_NAME" "PU_GTL2014_2_DIR"
					( Origin gPackager )
				)
				( objectStatus "PU_GTL2014_2_DIR" )
			)
			( signal "@baseboard_fab2_lib.baseboard_fab2(sch_1):pwrgd_cpu0_lvc3"
				( attribute "CDS_PHYS_NET_NAME" "PWRGD_CPU0_LVC3"
					( Origin gPackager )
				)
				( objectStatus "PWRGD_CPU0_LVC3" )
			)
			( signal "@baseboard_fab2_lib.baseboard_fab2(sch_1):pwrgd_cpu1_lvc3"
				( attribute "CDS_PHYS_NET_NAME" "PWRGD_CPU1_LVC3"
					( Origin gPackager )
				)
				( objectStatus "PWRGD_CPU1_LVC3" )
			)
			( signal "@baseboard_fab2_lib.baseboard_fab2(sch_1):pwrgd_drampwrgd"
				( attribute "CDS_PHYS_NET_NAME" "PWRGD_DRAMPWRGD"
					( Origin gPackager )
				)
				( objectStatus "PWRGD_DRAMPWRGD" )
			)
			( signal "@baseboard_fab2_lib.baseboard_fab2(sch_1):rst_cpu0_lvc3_n"
				( attribute "CDS_PHYS_NET_NAME" "RST_CPU0_LVC3_N"
					( Origin gPackager )
				)
				( objectStatus "RST_CPU0_LVC3_N" )
			)
			( signal "@baseboard_fab2_lib.baseboard_fab2(sch_1):rst_cpu1_lvc3_n"
				( attribute "CDS_PHYS_NET_NAME" "RST_CPU1_LVC3_N"
					( Origin gPackager )
				)
				( objectStatus "RST_CPU1_LVC3_N" )
			)
			( signal "@baseboard_fab2_lib.baseboard_fab2(sch_1):smb_ddr_abc_scl_g"
				( attribute "CDS_PHYS_NET_NAME" "SMB_DDR_ABC_SCL_G"
					( Origin gPackager )
				)
				( objectStatus "SMB_DDR_ABC_SCL_G" )
			)
			( signal "@baseboard_fab2_lib.baseboard_fab2(sch_1):smb_ddr_abc_sda_g"
				( attribute "CDS_PHYS_NET_NAME" "SMB_DDR_ABC_SDA_G"
					( Origin gPackager )
				)
				( objectStatus "SMB_DDR_ABC_SDA_G" )
			)
			( signal "@baseboard_fab2_lib.baseboard_fab2(sch_1):smb_ddr_abc_vpp_scl_r"
				( attribute "CDS_PHYS_NET_NAME" "SMB_DDR_ABC_VPP_SCL_R"
					( Origin gPackager )
				)
				( objectStatus "SMB_DDR_ABC_VPP_SCL_R" )
			)
			( signal "@baseboard_fab2_lib.baseboard_fab2(sch_1):smb_ddr_abc_vpp_sda_r"
				( attribute "CDS_PHYS_NET_NAME" "SMB_DDR_ABC_VPP_SDA_R"
					( Origin gPackager )
				)
				( objectStatus "SMB_DDR_ABC_VPP_SDA_R" )
			)
			( signal "@baseboard_fab2_lib.baseboard_fab2(sch_1):smb_ddr_def_scl_g"
				( attribute "CDS_PHYS_NET_NAME" "SMB_DDR_DEF_SCL_G"
					( Origin gPackager )
				)
				( objectStatus "SMB_DDR_DEF_SCL_G" )
			)
			( signal "@baseboard_fab2_lib.baseboard_fab2(sch_1):smb_ddr_def_sda_g"
				( attribute "CDS_PHYS_NET_NAME" "SMB_DDR_DEF_SDA_G"
					( Origin gPackager )
				)
				( objectStatus "SMB_DDR_DEF_SDA_G" )
			)
			( signal "@baseboard_fab2_lib.baseboard_fab2(sch_1):smb_ddr_def_vpp_scl_r"
				( attribute "CDS_PHYS_NET_NAME" "SMB_DDR_DEF_VPP_SCL_R"
					( Origin gPackager )
				)
				( objectStatus "SMB_DDR_DEF_VPP_SCL_R" )
			)
			( signal "@baseboard_fab2_lib.baseboard_fab2(sch_1):smb_ddr_def_vpp_sda_r"
				( attribute "CDS_PHYS_NET_NAME" "SMB_DDR_DEF_VPP_SDA_R"
					( Origin gPackager )
				)
				( objectStatus "SMB_DDR_DEF_VPP_SDA_R" )
			)
			( signal "@baseboard_fab2_lib.baseboard_fab2(sch_1):smb_ddr_ghj_scl_g"
				( attribute "CDS_PHYS_NET_NAME" "SMB_DDR_GHJ_SCL_G"
					( Origin gPackager )
				)
				( objectStatus "SMB_DDR_GHJ_SCL_G" )
			)
			( signal "@baseboard_fab2_lib.baseboard_fab2(sch_1):smb_ddr_ghj_sda_g"
				( attribute "CDS_PHYS_NET_NAME" "SMB_DDR_GHJ_SDA_G"
					( Origin gPackager )
				)
				( objectStatus "SMB_DDR_GHJ_SDA_G" )
			)
			( signal "@baseboard_fab2_lib.baseboard_fab2(sch_1):smb_ddr_ghj_vpp_scl_r"
				( attribute "CDS_PHYS_NET_NAME" "SMB_DDR_GHJ_VPP_SCL_R"
					( Origin gPackager )
				)
				( objectStatus "SMB_DDR_GHJ_VPP_SCL_R" )
			)
			( signal "@baseboard_fab2_lib.baseboard_fab2(sch_1):smb_ddr_ghj_vpp_sda_r"
				( attribute "CDS_PHYS_NET_NAME" "SMB_DDR_GHJ_VPP_SDA_R"
					( Origin gPackager )
				)
				( objectStatus "SMB_DDR_GHJ_VPP_SDA_R" )
			)
			( signal "@baseboard_fab2_lib.baseboard_fab2(sch_1):smb_ddr_klm_scl_g"
				( attribute "CDS_PHYS_NET_NAME" "SMB_DDR_KLM_SCL_G"
					( Origin gPackager )
				)
				( objectStatus "SMB_DDR_KLM_SCL_G" )
			)
			( signal "@baseboard_fab2_lib.baseboard_fab2(sch_1):smb_ddr_klm_sda_g"
				( attribute "CDS_PHYS_NET_NAME" "SMB_DDR_KLM_SDA_G"
					( Origin gPackager )
				)
				( objectStatus "SMB_DDR_KLM_SDA_G" )
			)
			( signal "@baseboard_fab2_lib.baseboard_fab2(sch_1):smb_ddr_klm_vpp_scl_r"
				( attribute "CDS_PHYS_NET_NAME" "SMB_DDR_KLM_VPP_SCL_R"
					( Origin gPackager )
				)
				( objectStatus "SMB_DDR_KLM_VPP_SCL_R" )
			)
			( signal "@baseboard_fab2_lib.baseboard_fab2(sch_1):smb_ddr_klm_vpp_sda_r"
				( attribute "CDS_PHYS_NET_NAME" "SMB_DDR_KLM_VPP_SDA_R"
					( Origin gPackager )
				)
				( objectStatus "SMB_DDR_KLM_VPP_SDA_R" )
			)
			( signal "@baseboard_fab2_lib.baseboard_fab2(sch_1):tp_smb_ddr_abc_en"
				( attribute "CDS_PHYS_NET_NAME" "TP_SMB_DDR_ABC_EN"
					( Origin gPackager )
				)
				( objectStatus "TP_SMB_DDR_ABC_EN" )
			)
			( signal "@baseboard_fab2_lib.baseboard_fab2(sch_1):tp_smb_ddr_def_en"
				( attribute "CDS_PHYS_NET_NAME" "TP_SMB_DDR_DEF_EN"
					( Origin gPackager )
				)
				( objectStatus "TP_SMB_DDR_DEF_EN" )
			)
			( signal "@baseboard_fab2_lib.baseboard_fab2(sch_1):tp_smb_ddr_ghj_en"
				( attribute "CDS_PHYS_NET_NAME" "TP_SMB_DDR_GHJ_EN"
					( Origin gPackager )
				)
				( objectStatus "TP_SMB_DDR_GHJ_EN" )
			)
			( signal "@baseboard_fab2_lib.baseboard_fab2(sch_1):tp_smb_ddr_klm_en"
				( attribute "CDS_PHYS_NET_NAME" "TP_SMB_DDR_KLM_EN"
					( Origin gPackager )
				)
				( objectStatus "TP_SMB_DDR_KLM_EN" )
			)
			( signal "@baseboard_fab2_lib.baseboard_fab2(sch_1):a_comp_ckmng"
				( attribute "CDS_PHYS_NET_NAME" "A_COMP_CKMNG"
					( Origin gPackager )
				)
				( objectStatus "A_COMP_CKMNG" )
			)
			( signal "@baseboard_fab2_lib.baseboard_fab2(sch_1):clk_25m_bmc"
				( attribute "CDS_PHYS_NET_NAME" "CLK_25M_BMC"
					( Origin gPackager )
				)
				( objectStatus "CLK_25M_BMC" )
			)
			( signal "@baseboard_fab2_lib.baseboard_fab2(sch_1):clk_25m_bmc_r"
				( attribute "CDS_PHYS_NET_NAME" "CLK_25M_BMC_R"
					( Origin gPackager )
				)
				( objectStatus "CLK_25M_BMC_R" )
			)
			( signal "@baseboard_fab2_lib.baseboard_fab2(sch_1):clk_25m_cpld"
				( attribute "CDS_PHYS_NET_NAME" "CLK_25M_CPLD"
					( Origin gPackager )
				)
				( objectStatus "CLK_25M_CPLD" )
			)
			( signal "@baseboard_fab2_lib.baseboard_fab2(sch_1):clk_25m_cpld_r"
				( attribute "CDS_PHYS_NET_NAME" "CLK_25M_CPLD_R"
					( Origin gPackager )
				)
				( objectStatus "CLK_25M_CPLD_R" )
			)
			( signal "@baseboard_fab2_lib.baseboard_fab2(sch_1):clk_32k_susclk_pld"
				( attribute "CDS_PHYS_NET_NAME" "CLK_32K_SUSCLK_PLD"
					( Origin gPackager )
				)
				( objectStatus "CLK_32K_SUSCLK_PLD" )
			)
			( signal "@baseboard_fab2_lib.baseboard_fab2(sch_1):clk_32k_susclk_pld_r"
				( attribute "CDS_PHYS_NET_NAME" "CLK_32K_SUSCLK_PLD_R"
					( Origin gPackager )
				)
				( objectStatus "CLK_32K_SUSCLK_PLD_R" )
			)
			( signal "@baseboard_fab2_lib.baseboard_fab2(sch_1):clk_50m_ckmng_bmc_1"
				( attribute "CDS_PHYS_NET_NAME" "CLK_50M_CKMNG_BMC_1"
					( Origin gPackager )
				)
				( attribute "PHYS_NET_NAME" "CLK_50M_CKMNG_BMC_1"
					( Origin gPackager )
				)
				( objectStatus "CLK_50M_CKMNG_BMC_1" )
			)
			( signal "@baseboard_fab2_lib.baseboard_fab2(sch_1):clk_50m_ckmng_bmc_1_r"
				( attribute "CDS_PHYS_NET_NAME" "CLK_50M_CKMNG_BMC_1_R"
					( Origin gPackager )
				)
				( objectStatus "CLK_50M_CKMNG_BMC_1_R" )
			)
			( signal "@baseboard_fab2_lib.baseboard_fab2(sch_1):clk_50m_ckmng_bmc_2"
				( attribute "CDS_PHYS_NET_NAME" "CLK_50M_CKMNG_BMC_2"
					( Origin gPackager )
				)
				( attribute "PHYS_NET_NAME" "CLK_50M_CKMNG_BMC_2"
					( Origin gPackager )
				)
				( objectStatus "CLK_50M_CKMNG_BMC_2" )
			)
			( signal "@baseboard_fab2_lib.baseboard_fab2(sch_1):clk_50m_ckmng_bmc_2_r"
				( attribute "CDS_PHYS_NET_NAME" "CLK_50M_CKMNG_BMC_2_R"
					( Origin gPackager )
				)
				( objectStatus "CLK_50M_CKMNG_BMC_2_R" )
			)
			( signal "@baseboard_fab2_lib.baseboard_fab2(sch_1):clk_50m_ckmng_ocp"
				( attribute "CDS_PHYS_NET_NAME" "CLK_50M_CKMNG_OCP"
					( Origin gPackager )
				)
				( objectStatus "CLK_50M_CKMNG_OCP" )
			)
			( signal "@baseboard_fab2_lib.baseboard_fab2(sch_1):clk_50m_ckmng_ocp_r"
				( attribute "CDS_PHYS_NET_NAME" "CLK_50M_CKMNG_OCP_R"
					( Origin gPackager )
				)
				( objectStatus "CLK_50M_CKMNG_OCP_R" )
			)
			( signal "@baseboard_fab2_lib.baseboard_fab2(sch_1):clk_50m_ckmng_pch_10gbe"
				( attribute "CDS_PHYS_NET_NAME" "CLK_50M_CKMNG_PCH_10GBE"
					( Origin gPackager )
				)
				( objectStatus "CLK_50M_CKMNG_PCH_10GBE" )
			)
			( signal "@baseboard_fab2_lib.baseboard_fab2(sch_1):clk_50m_ckmng_pch_10gbe_r"
				( attribute "CDS_PHYS_NET_NAME" "CLK_50M_CKMNG_PCH_10GBE_R"
					( Origin gPackager )
				)
				( objectStatus "CLK_50M_CKMNG_PCH_10GBE_R" )
			)
			( signal "@baseboard_fab2_lib.baseboard_fab2(sch_1):clk_50m_ckmng_sprvlle"
				( attribute "CDS_PHYS_NET_NAME" "CLK_50M_CKMNG_SPRVLLE"
					( Origin gPackager )
				)
				( objectStatus "CLK_50M_CKMNG_SPRVLLE" )
			)
			( signal "@baseboard_fab2_lib.baseboard_fab2(sch_1):clk_50m_ckmng_sprvlle_r"
				( attribute "CDS_PHYS_NET_NAME" "CLK_50M_CKMNG_SPRVLLE_R"
					( Origin gPackager )
				)
				( objectStatus "CLK_50M_CKMNG_SPRVLLE_R" )
			)
			( signal "@baseboard_fab2_lib.baseboard_fab2(sch_1):p3v3_stby_mng"
				( alias ( signalRef "@baseboard_fab2_lib.baseboard_fab2(sch_1):page101_p3v3_stby_mng") )
				( attribute "VOLTAGE" "5"
					( Units "uVoltage" "V" 1.000000)
					( Status sAliasFlattened )
					( Origin gFrontEnd )
				)
				( attribute "CDS_PHYS_NET_NAME" "P3V3_STBY_MNG"
					( Origin gPackager )
				)
				( objectStatus "P3V3_STBY_MNG" )
			)
			( signal "@baseboard_fab2_lib.baseboard_fab2(sch_1):page101_p3v3_stby_mng"
				( attribute "VOLTAGE" "5"
					( Units "uVoltage" "V" 1.000000)
					( Origin gFrontEnd )
				)
				( objectFlag fObjectAlias )
				( objectStatus "page101_p3v3_stby_mng" )
			)
			( signal "@baseboard_fab2_lib.baseboard_fab2(sch_1):p3v3_stby_mng_cpu"
				( alias ( signalRef "@baseboard_fab2_lib.baseboard_fab2(sch_1):page101_p3v3_stby_mng_cpu") )
				( attribute "VOLTAGE" "3.3"
					( Units "uVoltage" "V" 1.000000)
					( Status sAliasFlattened )
					( Origin gFrontEnd )
				)
				( attribute "CDS_PHYS_NET_NAME" "P3V3_STBY_MNG_CPU"
					( Origin gPackager )
				)
				( objectStatus "P3V3_STBY_MNG_CPU" )
			)
			( signal "@baseboard_fab2_lib.baseboard_fab2(sch_1):page101_p3v3_stby_mng_cpu"
				( attribute "VOLTAGE" "3.3"
					( Units "uVoltage" "V" 1.000000)
					( Origin gFrontEnd )
				)
				( objectFlag fObjectAlias )
				( objectStatus "page101_p3v3_stby_mng_cpu" )
			)
			( signal "@baseboard_fab2_lib.baseboard_fab2(sch_1):p3v3_stby_mng_rgmii"
				( alias ( signalRef "@baseboard_fab2_lib.baseboard_fab2(sch_1):page101_p3v3_stby_mng_rgmii") )
				( attribute "VOLTAGE" "3.3"
					( Units "uVoltage" "V" 1.000000)
					( Status sAliasFlattened )
					( Origin gFrontEnd )
				)
				( attribute "CDS_PHYS_NET_NAME" "P3V3_STBY_MNG_RGMII"
					( Origin gPackager )
				)
				( objectStatus "P3V3_STBY_MNG_RGMII" )
			)
			( signal "@baseboard_fab2_lib.baseboard_fab2(sch_1):page101_p3v3_stby_mng_rgmii"
				( attribute "VOLTAGE" "3.3"
					( Units "uVoltage" "V" 1.000000)
					( Origin gFrontEnd )
				)
				( objectFlag fObjectAlias )
				( objectStatus "page101_p3v3_stby_mng_rgmii" )
			)
			( signal "@baseboard_fab2_lib.baseboard_fab2(sch_1):p3v3_stby_mng_rmii"
				( alias ( signalRef "@baseboard_fab2_lib.baseboard_fab2(sch_1):page101_p3v3_stby_mng_rmii") )
				( attribute "VOLTAGE" "3.3"
					( Units "uVoltage" "V" 1.000000)
					( Status sAliasFlattened )
					( Origin gFrontEnd )
				)
				( attribute "CDS_PHYS_NET_NAME" "P3V3_STBY_MNG_RMII"
					( Origin gPackager )
				)
				( objectStatus "P3V3_STBY_MNG_RMII" )
			)
			( signal "@baseboard_fab2_lib.baseboard_fab2(sch_1):page101_p3v3_stby_mng_rmii"
				( attribute "VOLTAGE" "3.3"
					( Units "uVoltage" "V" 1.000000)
					( Origin gFrontEnd )
				)
				( objectFlag fObjectAlias )
				( objectStatus "page101_p3v3_stby_mng_rmii" )
			)
			( signal "@baseboard_fab2_lib.baseboard_fab2(sch_1):pd_ckmng_oe"
				( attribute "CDS_PHYS_NET_NAME" "PD_CKMNG_OE"
					( Origin gPackager )
				)
				( objectStatus "PD_CKMNG_OE" )
			)
			( signal "@baseboard_fab2_lib.baseboard_fab2(sch_1):pwrgd_p3v3_stby"
				( attribute "CDS_PHYS_NET_NAME" "PWRGD_P3V3_STBY"
					( Origin gPackager )
				)
				( objectStatus "PWRGD_P3V3_STBY" )
			)
			( signal "@baseboard_fab2_lib.baseboard_fab2(sch_1):smb_host_stby_lvc3_scl"
				( attribute "CDS_PHYS_NET_NAME" "SMB_HOST_STBY_LVC3_SCL"
					( Origin gPackager )
				)
				( objectStatus "SMB_HOST_STBY_LVC3_SCL" )
			)
			( signal "@baseboard_fab2_lib.baseboard_fab2(sch_1):smb_host_stby_lvc3_sda"
				( attribute "CDS_PHYS_NET_NAME" "SMB_HOST_STBY_LVC3_SDA"
					( Origin gPackager )
				)
				( objectStatus "SMB_HOST_STBY_LVC3_SDA" )
			)
			( signal "@baseboard_fab2_lib.baseboard_fab2(sch_1):tp_33p_33m_smbadr"
				( attribute "CDS_PHYS_NET_NAME" "TP_33P_33M_SMBADR"
					( Origin gPackager )
				)
				( objectStatus "TP_33P_33M_SMBADR" )
			)
			( signal "@baseboard_fab2_lib.baseboard_fab2(sch_1):tp_clk5_50m_ckmng"
				( attribute "CDS_PHYS_NET_NAME" "TP_CLK5_50M_CKMNG"
					( Origin gPackager )
				)
				( objectStatus "TP_CLK5_50M_CKMNG" )
			)
			( signal "@baseboard_fab2_lib.baseboard_fab2(sch_1):tp_clk_100m_r_dn"
				( attribute "CDS_PHYS_NET_NAME" "TP_CLK_100M_R_DN"
					( Origin gPackager )
				)
				( objectStatus "TP_CLK_100M_R_DN" )
			)
			( signal "@baseboard_fab2_lib.baseboard_fab2(sch_1):tp_clk_100m_r_dp"
				( attribute "CDS_PHYS_NET_NAME" "TP_CLK_100M_R_DP"
					( Origin gPackager )
				)
				( objectStatus "TP_CLK_100M_R_DP" )
			)
			( signal "@baseboard_fab2_lib.baseboard_fab2(sch_1):tp_clk_125m"
				( attribute "CDS_PHYS_NET_NAME" "TP_CLK_125M"
					( Origin gPackager )
				)
				( objectStatus "TP_CLK_125M" )
			)
			( signal "@baseboard_fab2_lib.baseboard_fab2(sch_1):tp_clk_125m_bmca"
				( attribute "CDS_PHYS_NET_NAME" "TP_CLK_125M_BMCA"
					( Origin gPackager )
				)
				( objectStatus "TP_CLK_125M_BMCA" )
			)
			( signal "@baseboard_fab2_lib.baseboard_fab2(sch_1):tp_clk_96m_ckmng_n"
				( attribute "CDS_PHYS_NET_NAME" "TP_CLK_96M_CKMNG_N"
					( Origin gPackager )
				)
				( objectStatus "TP_CLK_96M_CKMNG_N" )
			)
			( signal "@baseboard_fab2_lib.baseboard_fab2(sch_1):tp_clk_96m_ckmng_p"
				( attribute "CDS_PHYS_NET_NAME" "TP_CLK_96M_CKMNG_P"
					( Origin gPackager )
				)
				( objectStatus "TP_CLK_96M_CKMNG_P" )
			)
			( signal "@baseboard_fab2_lib.baseboard_fab2(sch_1):xtal_ck_mng_in"
				( attribute "CDS_PHYS_NET_NAME" "XTAL_CK_MNG_IN"
					( Origin gPackager )
				)
				( objectStatus "XTAL_CK_MNG_IN" )
			)
			( signal "@baseboard_fab2_lib.baseboard_fab2(sch_1):xtal_ck_mng_out"
				( attribute "CDS_PHYS_NET_NAME" "XTAL_CK_MNG_OUT"
					( Origin gPackager )
				)
				( objectStatus "XTAL_CK_MNG_OUT" )
			)
			( signal "@baseboard_fab2_lib.baseboard_fab2(sch_1):clk_100m_cpu0_bclk0_r_dn"
				( attribute "CDS_PHYS_NET_NAME" "CLK_100M_CPU0_BCLK0_R_DN"
					( Origin gPackager )
				)
				( objectStatus "CLK_100M_CPU0_BCLK0_R_DN" )
			)
			( signal "@baseboard_fab2_lib.baseboard_fab2(sch_1):clk_100m_cpu0_bclk0_r_dp"
				( attribute "CDS_PHYS_NET_NAME" "CLK_100M_CPU0_BCLK0_R_DP"
					( Origin gPackager )
				)
				( objectStatus "CLK_100M_CPU0_BCLK0_R_DP" )
			)
			( signal "@baseboard_fab2_lib.baseboard_fab2(sch_1):clk_100m_cpu0_bclk1_r_dn"
				( attribute "CDS_PHYS_NET_NAME" "CLK_100M_CPU0_BCLK1_R_DN"
					( Origin gPackager )
				)
				( objectStatus "CLK_100M_CPU0_BCLK1_R_DN" )
			)
			( signal "@baseboard_fab2_lib.baseboard_fab2(sch_1):clk_100m_cpu0_bclk1_r_dp"
				( attribute "CDS_PHYS_NET_NAME" "CLK_100M_CPU0_BCLK1_R_DP"
					( Origin gPackager )
				)
				( objectStatus "CLK_100M_CPU0_BCLK1_R_DP" )
			)
			( signal "@baseboard_fab2_lib.baseboard_fab2(sch_1):clk_100m_cpu0_bclk2_r_dn"
				( attribute "CDS_PHYS_NET_NAME" "CLK_100M_CPU0_BCLK2_R_DN"
					( Origin gPackager )
				)
				( objectStatus "CLK_100M_CPU0_BCLK2_R_DN" )
			)
			( signal "@baseboard_fab2_lib.baseboard_fab2(sch_1):clk_100m_cpu0_bclk2_r_dp"
				( attribute "CDS_PHYS_NET_NAME" "CLK_100M_CPU0_BCLK2_R_DP"
					( Origin gPackager )
				)
				( objectStatus "CLK_100M_CPU0_BCLK2_R_DP" )
			)
			( signal "@baseboard_fab2_lib.baseboard_fab2(sch_1):clk_100m_cpu0_pe_refclk_r_dn"
				( attribute "CDS_PHYS_NET_NAME" "CLK_100M_CPU0_PE_REFCLK_R_DN"
					( Origin gPackager )
				)
				( objectStatus "CLK_100M_CPU0_PE_REFCLK_R_DN" )
			)
			( signal "@baseboard_fab2_lib.baseboard_fab2(sch_1):clk_100m_cpu0_pe_refclk_r_dp"
				( attribute "CDS_PHYS_NET_NAME" "CLK_100M_CPU0_PE_REFCLK_R_DP"
					( Origin gPackager )
				)
				( objectStatus "CLK_100M_CPU0_PE_REFCLK_R_DP" )
			)
			( signal "@baseboard_fab2_lib.baseboard_fab2(sch_1):clk_100m_cpu0_rc_refclk0_r_dn"
				( attribute "CDS_PHYS_NET_NAME" "CLK_100M_CPU0_RC_REFCLK0_R_DN"
					( Origin gPackager )
				)
				( objectStatus "CLK_100M_CPU0_RC_REFCLK0_R_DN" )
			)
			( signal "@baseboard_fab2_lib.baseboard_fab2(sch_1):clk_100m_cpu0_rc_refclk0_r_dp"
				( attribute "CDS_PHYS_NET_NAME" "CLK_100M_CPU0_RC_REFCLK0_R_DP"
					( Origin gPackager )
				)
				( objectStatus "CLK_100M_CPU0_RC_REFCLK0_R_DP" )
			)
			( signal "@baseboard_fab2_lib.baseboard_fab2(sch_1):clk_100m_cpu0_rc_refclk1_r_dn"
				( attribute "CDS_PHYS_NET_NAME" "CLK_100M_CPU0_RC_REFCLK1_R_DN"
					( Origin gPackager )
				)
				( objectStatus "CLK_100M_CPU0_RC_REFCLK1_R_DN" )
			)
			( signal "@baseboard_fab2_lib.baseboard_fab2(sch_1):clk_100m_cpu0_rc_refclk1_r_dp"
				( attribute "CDS_PHYS_NET_NAME" "CLK_100M_CPU0_RC_REFCLK1_R_DP"
					( Origin gPackager )
				)
				( objectStatus "CLK_100M_CPU0_RC_REFCLK1_R_DP" )
			)
			( signal "@baseboard_fab2_lib.baseboard_fab2(sch_1):clk_100m_cpu1_bclk0_r_dn"
				( attribute "CDS_PHYS_NET_NAME" "CLK_100M_CPU1_BCLK0_R_DN"
					( Origin gPackager )
				)
				( objectStatus "CLK_100M_CPU1_BCLK0_R_DN" )
			)
			( signal "@baseboard_fab2_lib.baseboard_fab2(sch_1):clk_100m_cpu1_bclk0_r_dp"
				( attribute "CDS_PHYS_NET_NAME" "CLK_100M_CPU1_BCLK0_R_DP"
					( Origin gPackager )
				)
				( objectStatus "CLK_100M_CPU1_BCLK0_R_DP" )
			)
			( signal "@baseboard_fab2_lib.baseboard_fab2(sch_1):clk_100m_cpu1_bclk1_r_dn"
				( attribute "CDS_PHYS_NET_NAME" "CLK_100M_CPU1_BCLK1_R_DN"
					( Origin gPackager )
				)
				( objectStatus "CLK_100M_CPU1_BCLK1_R_DN" )
			)
			( signal "@baseboard_fab2_lib.baseboard_fab2(sch_1):clk_100m_cpu1_bclk1_r_dp"
				( attribute "CDS_PHYS_NET_NAME" "CLK_100M_CPU1_BCLK1_R_DP"
					( Origin gPackager )
				)
				( objectStatus "CLK_100M_CPU1_BCLK1_R_DP" )
			)
			( signal "@baseboard_fab2_lib.baseboard_fab2(sch_1):clk_100m_cpu1_bclk2_r_dn"
				( attribute "CDS_PHYS_NET_NAME" "CLK_100M_CPU1_BCLK2_R_DN"
					( Origin gPackager )
				)
				( objectStatus "CLK_100M_CPU1_BCLK2_R_DN" )
			)
			( signal "@baseboard_fab2_lib.baseboard_fab2(sch_1):clk_100m_cpu1_bclk2_r_dp"
				( attribute "CDS_PHYS_NET_NAME" "CLK_100M_CPU1_BCLK2_R_DP"
					( Origin gPackager )
				)
				( objectStatus "CLK_100M_CPU1_BCLK2_R_DP" )
			)
			( signal "@baseboard_fab2_lib.baseboard_fab2(sch_1):clk_100m_cpu1_pe_refclk_r_dn"
				( attribute "CDS_PHYS_NET_NAME" "CLK_100M_CPU1_PE_REFCLK_R_DN"
					( Origin gPackager )
				)
				( objectStatus "CLK_100M_CPU1_PE_REFCLK_R_DN" )
			)
			( signal "@baseboard_fab2_lib.baseboard_fab2(sch_1):clk_100m_cpu1_pe_refclk_r_dp"
				( attribute "CDS_PHYS_NET_NAME" "CLK_100M_CPU1_PE_REFCLK_R_DP"
					( Origin gPackager )
				)
				( objectStatus "CLK_100M_CPU1_PE_REFCLK_R_DP" )
			)
			( signal "@baseboard_fab2_lib.baseboard_fab2(sch_1):clk_100m_cpu1_rc_refclk0_r_dn"
				( attribute "CDS_PHYS_NET_NAME" "CLK_100M_CPU1_RC_REFCLK0_R_DN"
					( Origin gPackager )
				)
				( objectStatus "CLK_100M_CPU1_RC_REFCLK0_R_DN" )
			)
			( signal "@baseboard_fab2_lib.baseboard_fab2(sch_1):clk_100m_cpu1_rc_refclk0_r_dp"
				( attribute "CDS_PHYS_NET_NAME" "CLK_100M_CPU1_RC_REFCLK0_R_DP"
					( Origin gPackager )
				)
				( objectStatus "CLK_100M_CPU1_RC_REFCLK0_R_DP" )
			)
			( signal "@baseboard_fab2_lib.baseboard_fab2(sch_1):clk_100m_cpu1_rc_refclk1_r_dn"
				( attribute "CDS_PHYS_NET_NAME" "CLK_100M_CPU1_RC_REFCLK1_R_DN"
					( Origin gPackager )
				)
				( objectStatus "CLK_100M_CPU1_RC_REFCLK1_R_DN" )
			)
			( signal "@baseboard_fab2_lib.baseboard_fab2(sch_1):clk_100m_cpu1_rc_refclk1_r_dp"
				( attribute "CDS_PHYS_NET_NAME" "CLK_100M_CPU1_RC_REFCLK1_R_DP"
					( Origin gPackager )
				)
				( objectStatus "CLK_100M_CPU1_RC_REFCLK1_R_DP" )
			)
			( signal "@baseboard_fab2_lib.baseboard_fab2(sch_1):clk_100m_db1200_dn"
				( attribute "CDS_PHYS_NET_NAME" "CLK_100M_DB1200_DN"
					( Origin gPackager )
				)
				( objectStatus "CLK_100M_DB1200_DN" )
			)
			( signal "@baseboard_fab2_lib.baseboard_fab2(sch_1):clk_100m_db1200_dp"
				( attribute "CDS_PHYS_NET_NAME" "CLK_100M_DB1200_DP"
					( Origin gPackager )
				)
				( objectStatus "CLK_100M_DB1200_DP" )
			)
			( signal "@baseboard_fab2_lib.baseboard_fab2(sch_1):fm_100m_n"
				( attribute "CDS_PHYS_NET_NAME" "FM_100M_N"
					( Origin gPackager )
				)
				( objectStatus "FM_100M_N" )
			)
			( signal "@baseboard_fab2_lib.baseboard_fab2(sch_1):fm_cpu0_mcp_clk_en_n"
				( attribute "CDS_PHYS_NET_NAME" "FM_CPU0_MCP_CLK_EN_N"
					( Origin gPackager )
				)
				( objectStatus "FM_CPU0_MCP_CLK_EN_N" )
			)
			( signal "@baseboard_fab2_lib.baseboard_fab2(sch_1):fm_cpu1_mcp_clk_en_n"
				( attribute "CDS_PHYS_NET_NAME" "FM_CPU1_MCP_CLK_EN_N"
					( Origin gPackager )
				)
				( objectStatus "FM_CPU1_MCP_CLK_EN_N" )
			)
			( signal "@baseboard_fab2_lib.baseboard_fab2(sch_1):fm_db1200_pwrgd"
				( attribute "CDS_PHYS_NET_NAME" "FM_DB1200_PWRGD"
					( Origin gPackager )
				)
				( objectStatus "FM_DB1200_PWRGD" )
			)
			( signal "@baseboard_fab2_lib.baseboard_fab2(sch_1):fm_db1200_smb_sa0"
				( attribute "CDS_PHYS_NET_NAME" "FM_DB1200_SMB_SA0"
					( Origin gPackager )
				)
				( objectStatus "FM_DB1200_SMB_SA0" )
			)
			( signal "@baseboard_fab2_lib.baseboard_fab2(sch_1):fm_db1200_smb_sa1"
				( attribute "CDS_PHYS_NET_NAME" "FM_DB1200_SMB_SA1"
					( Origin gPackager )
				)
				( objectStatus "FM_DB1200_SMB_SA1" )
			)
			( signal "@baseboard_fab2_lib.baseboard_fab2(sch_1):fm_db1200zl_bclks_en_n"
				( attribute "CDS_PHYS_NET_NAME" "FM_DB1200ZL_BCLKS_EN_N"
					( Origin gPackager )
				)
				( objectStatus "FM_DB1200ZL_BCLKS_EN_N" )
			)
			( signal "@baseboard_fab2_lib.baseboard_fab2(sch_1):fm_hbw_bypass_lowbw_n"
				( attribute "CDS_PHYS_NET_NAME" "FM_HBW_BYPASS_LOWBW_N"
					( Origin gPackager )
				)
				( objectStatus "FM_HBW_BYPASS_LOWBW_N" )
			)
			( signal "@baseboard_fab2_lib.baseboard_fab2(sch_1):nc_db1200zl(0)"
				( attribute "CDS_PHYS_NET_NAME" "NC_DB1200ZL<0>"
					( Origin gPackager )
				)
				( attribute "PNN" "NC_DB1200ZL<0>"
					( Origin gPackager )
				)
				( objectStatus "NC_DB1200ZL<0>" )
			)
			( signal "@baseboard_fab2_lib.baseboard_fab2(sch_1):nc_db1200zl(1)"
				( attribute "CDS_PHYS_NET_NAME" "NC_DB1200ZL<1>"
					( Origin gPackager )
				)
				( attribute "PNN" "NC_DB1200ZL<1>"
					( Origin gPackager )
				)
				( objectStatus "NC_DB1200ZL<1>" )
			)
			( signal "@baseboard_fab2_lib.baseboard_fab2(sch_1):nc_db1200zl(2)"
				( attribute "CDS_PHYS_NET_NAME" "NC_DB1200ZL<2>"
					( Origin gPackager )
				)
				( attribute "PNN" "NC_DB1200ZL<2>"
					( Origin gPackager )
				)
				( objectStatus "NC_DB1200ZL<2>" )
			)
			( signal "@baseboard_fab2_lib.baseboard_fab2(sch_1):p3v3_db1200"
				( alias ( signalRef "@baseboard_fab2_lib.baseboard_fab2(sch_1):page102_p3v3_db1200") )
				( attribute "VOLTAGE" "5"
					( Units "uVoltage" "V" 1.000000)
					( Status sAliasFlattened )
					( Origin gFrontEnd )
				)
				( attribute "CDS_PHYS_NET_NAME" "P3V3_DB1200"
					( Origin gPackager )
				)
				( objectStatus "P3V3_DB1200" )
			)
			( signal "@baseboard_fab2_lib.baseboard_fab2(sch_1):page102_p3v3_db1200"
				( attribute "VOLTAGE" "5"
					( Units "uVoltage" "V" 1.000000)
					( Origin gFrontEnd )
				)
				( objectFlag fObjectAlias )
				( objectStatus "page102_p3v3_db1200" )
			)
			( signal "@baseboard_fab2_lib.baseboard_fab2(sch_1):p3v3_db1200_a"
				( alias ( signalRef "@baseboard_fab2_lib.baseboard_fab2(sch_1):page102_p3v3_db1200_a") )
				( attribute "VOLTAGE" "+3.3V"
					( Units "uVoltage" "V" 1.000000)
					( Status sAliasFlattened )
					( Origin gFrontEnd )
				)
				( attribute "CDS_PHYS_NET_NAME" "P3V3_DB1200_A"
					( Origin gPackager )
				)
				( objectStatus "P3V3_DB1200_A" )
			)
			( signal "@baseboard_fab2_lib.baseboard_fab2(sch_1):page102_p3v3_db1200_a"
				( attribute "VOLTAGE" "+3.3V"
					( Units "uVoltage" "V" 1.000000)
					( Origin gFrontEnd )
				)
				( objectFlag fObjectAlias )
				( objectStatus "page102_p3v3_db1200_a" )
			)
			( signal "@baseboard_fab2_lib.baseboard_fab2(sch_1):p3v3_db1200_r"
				( alias ( signalRef "@baseboard_fab2_lib.baseboard_fab2(sch_1):page102_p3v3_db1200_r") )
				( attribute "VOLTAGE" "+3.3V"
					( Units "uVoltage" "V" 1.000000)
					( Status sAliasFlattened )
					( Origin gFrontEnd )
				)
				( attribute "CDS_PHYS_NET_NAME" "P3V3_DB1200_R"
					( Origin gPackager )
				)
				( objectStatus "P3V3_DB1200_R" )
			)
			( signal "@baseboard_fab2_lib.baseboard_fab2(sch_1):page102_p3v3_db1200_r"
				( attribute "VOLTAGE" "+3.3V"
					( Units "uVoltage" "V" 1.000000)
					( Origin gFrontEnd )
				)
				( objectFlag fObjectAlias )
				( objectStatus "page102_p3v3_db1200_r" )
			)
			( signal "@baseboard_fab2_lib.baseboard_fab2(sch_1):smb_host_stby_lvc3_scl_r2"
				( attribute "CDS_PHYS_NET_NAME" "SMB_HOST_STBY_LVC3_SCL_R2"
					( Origin gPackager )
				)
				( objectStatus "SMB_HOST_STBY_LVC3_SCL_R2" )
			)
			( signal "@baseboard_fab2_lib.baseboard_fab2(sch_1):smb_host_stby_lvc3_sda_r2"
				( attribute "CDS_PHYS_NET_NAME" "SMB_HOST_STBY_LVC3_SDA_R2"
					( Origin gPackager )
				)
				( objectStatus "SMB_HOST_STBY_LVC3_SDA_R2" )
			)
			( signal "@baseboard_fab2_lib.baseboard_fab2(sch_1):clk_156m_osc_brd_cpu0_dn"
				( attribute "CDS_PHYS_NET_NAME" "CLK_156M_OSC_BRD_CPU0_DN"
					( Origin gPackager )
				)
				( objectStatus "CLK_156M_OSC_BRD_CPU0_DN" )
			)
			( signal "@baseboard_fab2_lib.baseboard_fab2(sch_1):clk_156m_osc_brd_cpu0_dp"
				( attribute "CDS_PHYS_NET_NAME" "CLK_156M_OSC_BRD_CPU0_DP"
					( Origin gPackager )
				)
				( objectStatus "CLK_156M_OSC_BRD_CPU0_DP" )
			)
			( signal "@baseboard_fab2_lib.baseboard_fab2(sch_1):clk_156m_osc_brd_cpu1_dn"
				( attribute "CDS_PHYS_NET_NAME" "CLK_156M_OSC_BRD_CPU1_DN"
					( Origin gPackager )
				)
				( objectStatus "CLK_156M_OSC_BRD_CPU1_DN" )
			)
			( signal "@baseboard_fab2_lib.baseboard_fab2(sch_1):clk_156m_osc_brd_cpu1_dp"
				( attribute "CDS_PHYS_NET_NAME" "CLK_156M_OSC_BRD_CPU1_DP"
					( Origin gPackager )
				)
				( objectStatus "CLK_156M_OSC_BRD_CPU1_DP" )
			)
			( signal "@baseboard_fab2_lib.baseboard_fab2(sch_1):clk_322m_156m_cpu0_osc_vrm_dn"
				( attribute "CDS_PHYS_NET_NAME" "CLK_322M_156M_CPU0_OSC_VRM_DN"
					( Origin gPackager )
				)
				( objectStatus "CLK_322M_156M_CPU0_OSC_VRM_DN" )
			)
			( signal "@baseboard_fab2_lib.baseboard_fab2(sch_1):clk_322m_156m_cpu0_osc_vrm_dp"
				( attribute "CDS_PHYS_NET_NAME" "CLK_322M_156M_CPU0_OSC_VRM_DP"
					( Origin gPackager )
				)
				( objectStatus "CLK_322M_156M_CPU0_OSC_VRM_DP" )
			)
			( signal "@baseboard_fab2_lib.baseboard_fab2(sch_1):clk_322m_156m_cpu1_osc_vrm_dn"
				( attribute "CDS_PHYS_NET_NAME" "CLK_322M_156M_CPU1_OSC_VRM_DN"
					( Origin gPackager )
				)
				( objectStatus "CLK_322M_156M_CPU1_OSC_VRM_DN" )
			)
			( signal "@baseboard_fab2_lib.baseboard_fab2(sch_1):clk_322m_156m_cpu1_osc_vrm_dp"
				( attribute "CDS_PHYS_NET_NAME" "CLK_322M_156M_CPU1_OSC_VRM_DP"
					( Origin gPackager )
				)
				( objectStatus "CLK_322M_156M_CPU1_OSC_VRM_DP" )
			)
			( signal "@baseboard_fab2_lib.baseboard_fab2(sch_1):fm_156m_cpu0_brd_osc_en"
				( attribute "CDS_PHYS_NET_NAME" "FM_156M_CPU0_BRD_OSC_EN"
					( Origin gPackager )
				)
				( objectStatus "FM_156M_CPU0_BRD_OSC_EN" )
			)
			( signal "@baseboard_fab2_lib.baseboard_fab2(sch_1):fm_156m_cpu1_brd_osc_en"
				( attribute "CDS_PHYS_NET_NAME" "FM_156M_CPU1_BRD_OSC_EN"
					( Origin gPackager )
				)
				( objectStatus "FM_156M_CPU1_BRD_OSC_EN" )
			)
			( signal "@baseboard_fab2_lib.baseboard_fab2(sch_1):fm_cpu0_stl_brd_osc_en"
				( attribute "CDS_PHYS_NET_NAME" "FM_CPU0_STL_BRD_OSC_EN"
					( Origin gPackager )
				)
				( objectStatus "FM_CPU0_STL_BRD_OSC_EN" )
			)
			( signal "@baseboard_fab2_lib.baseboard_fab2(sch_1):fm_cpu0_vrm_322m_156m_osc_en"
				( attribute "CDS_PHYS_NET_NAME" "FM_CPU0_VRM_322M_156M_OSC_EN"
					( Origin gPackager )
				)
				( objectStatus "FM_CPU0_VRM_322M_156M_OSC_EN" )
			)
			( signal "@baseboard_fab2_lib.baseboard_fab2(sch_1):fm_cpu0_vrm_osc_en"
				( attribute "CDS_PHYS_NET_NAME" "FM_CPU0_VRM_OSC_EN"
					( Origin gPackager )
				)
				( objectStatus "FM_CPU0_VRM_OSC_EN" )
			)
			( signal "@baseboard_fab2_lib.baseboard_fab2(sch_1):fm_cpu1_stl_brd_osc_en"
				( attribute "CDS_PHYS_NET_NAME" "FM_CPU1_STL_BRD_OSC_EN"
					( Origin gPackager )
				)
				( objectStatus "FM_CPU1_STL_BRD_OSC_EN" )
			)
			( signal "@baseboard_fab2_lib.baseboard_fab2(sch_1):fm_cpu1_vrm_322m_156m_osc_en"
				( attribute "CDS_PHYS_NET_NAME" "FM_CPU1_VRM_322M_156M_OSC_EN"
					( Origin gPackager )
				)
				( objectStatus "FM_CPU1_VRM_322M_156M_OSC_EN" )
			)
			( signal "@baseboard_fab2_lib.baseboard_fab2(sch_1):fm_cpu1_vrm_osc_en"
				( attribute "CDS_PHYS_NET_NAME" "FM_CPU1_VRM_OSC_EN"
					( Origin gPackager )
				)
				( objectStatus "FM_CPU1_VRM_OSC_EN" )
			)
			( signal "@baseboard_fab2_lib.baseboard_fab2(sch_1):nc_clk_156m_cpu0_osc"
				( attribute "CDS_PHYS_NET_NAME" "NC_CLK_156M_CPU0_OSC"
					( Origin gPackager )
				)
				( objectStatus "NC_CLK_156M_CPU0_OSC" )
			)
			( signal "@baseboard_fab2_lib.baseboard_fab2(sch_1):nc_clk_156m_cpu1_osc"
				( attribute "CDS_PHYS_NET_NAME" "NC_CLK_156M_CPU1_OSC"
					( Origin gPackager )
				)
				( objectStatus "NC_CLK_156M_CPU1_OSC" )
			)
			( signal "@baseboard_fab2_lib.baseboard_fab2(sch_1):p3e_cpu0_pe1_pch_c_txn(8)"
				( attribute "CDS_PHYS_NET_NAME" "P3E_CPU0_PE1_PCH_C_TXN<8>"
					( Origin gPackager )
				)
				( attribute "PNN" "P3E_CPU0_PE1_PCH_C_TXN<8>"
					( Origin gPackager )
				)
				( objectStatus "P3E_CPU0_PE1_PCH_C_TXN<8>" )
			)
			( signal "@baseboard_fab2_lib.baseboard_fab2(sch_1):p3e_cpu0_pe1_pch_c_txn(9)"
				( attribute "CDS_PHYS_NET_NAME" "P3E_CPU0_PE1_PCH_C_TXN<9>"
					( Origin gPackager )
				)
				( attribute "PNN" "P3E_CPU0_PE1_PCH_C_TXN<9>"
					( Origin gPackager )
				)
				( objectStatus "P3E_CPU0_PE1_PCH_C_TXN<9>" )
			)
			( signal "@baseboard_fab2_lib.baseboard_fab2(sch_1):p3e_cpu0_pe1_pch_c_txn(10)"
				( attribute "CDS_PHYS_NET_NAME" "P3E_CPU0_PE1_PCH_C_TXN<10>"
					( Origin gPackager )
				)
				( attribute "PNN" "P3E_CPU0_PE1_PCH_C_TXN<10>"
					( Origin gPackager )
				)
				( objectStatus "P3E_CPU0_PE1_PCH_C_TXN<10>" )
			)
			( signal "@baseboard_fab2_lib.baseboard_fab2(sch_1):p3e_cpu0_pe1_pch_c_txn(11)"
				( attribute "CDS_PHYS_NET_NAME" "P3E_CPU0_PE1_PCH_C_TXN<11>"
					( Origin gPackager )
				)
				( attribute "PNN" "P3E_CPU0_PE1_PCH_C_TXN<11>"
					( Origin gPackager )
				)
				( objectStatus "P3E_CPU0_PE1_PCH_C_TXN<11>" )
			)
			( signal "@baseboard_fab2_lib.baseboard_fab2(sch_1):p3e_cpu0_pe1_pch_c_txn(12)"
				( attribute "CDS_PHYS_NET_NAME" "P3E_CPU0_PE1_PCH_C_TXN<12>"
					( Origin gPackager )
				)
				( attribute "PNN" "P3E_CPU0_PE1_PCH_C_TXN<12>"
					( Origin gPackager )
				)
				( objectStatus "P3E_CPU0_PE1_PCH_C_TXN<12>" )
			)
			( signal "@baseboard_fab2_lib.baseboard_fab2(sch_1):p3e_cpu0_pe1_pch_c_txn(13)"
				( attribute "CDS_PHYS_NET_NAME" "P3E_CPU0_PE1_PCH_C_TXN<13>"
					( Origin gPackager )
				)
				( attribute "PNN" "P3E_CPU0_PE1_PCH_C_TXN<13>"
					( Origin gPackager )
				)
				( objectStatus "P3E_CPU0_PE1_PCH_C_TXN<13>" )
			)
			( signal "@baseboard_fab2_lib.baseboard_fab2(sch_1):p3e_cpu0_pe1_pch_c_txn(14)"
				( attribute "CDS_PHYS_NET_NAME" "P3E_CPU0_PE1_PCH_C_TXN<14>"
					( Origin gPackager )
				)
				( attribute "PNN" "P3E_CPU0_PE1_PCH_C_TXN<14>"
					( Origin gPackager )
				)
				( objectStatus "P3E_CPU0_PE1_PCH_C_TXN<14>" )
			)
			( signal "@baseboard_fab2_lib.baseboard_fab2(sch_1):p3e_cpu0_pe1_pch_c_txn(15)"
				( attribute "CDS_PHYS_NET_NAME" "P3E_CPU0_PE1_PCH_C_TXN<15>"
					( Origin gPackager )
				)
				( attribute "PNN" "P3E_CPU0_PE1_PCH_C_TXN<15>"
					( Origin gPackager )
				)
				( objectStatus "P3E_CPU0_PE1_PCH_C_TXN<15>" )
			)
			( signal "@baseboard_fab2_lib.baseboard_fab2(sch_1):p3e_cpu0_pe1_pch_c_txp(8)"
				( attribute "CDS_PHYS_NET_NAME" "P3E_CPU0_PE1_PCH_C_TXP<8>"
					( Origin gPackager )
				)
				( attribute "PNN" "P3E_CPU0_PE1_PCH_C_TXP<8>"
					( Origin gPackager )
				)
				( objectStatus "P3E_CPU0_PE1_PCH_C_TXP<8>" )
			)
			( signal "@baseboard_fab2_lib.baseboard_fab2(sch_1):p3e_cpu0_pe1_pch_c_txp(9)"
				( attribute "CDS_PHYS_NET_NAME" "P3E_CPU0_PE1_PCH_C_TXP<9>"
					( Origin gPackager )
				)
				( attribute "PNN" "P3E_CPU0_PE1_PCH_C_TXP<9>"
					( Origin gPackager )
				)
				( objectStatus "P3E_CPU0_PE1_PCH_C_TXP<9>" )
			)
			( signal "@baseboard_fab2_lib.baseboard_fab2(sch_1):p3e_cpu0_pe1_pch_c_txp(10)"
				( attribute "CDS_PHYS_NET_NAME" "P3E_CPU0_PE1_PCH_C_TXP<10>"
					( Origin gPackager )
				)
				( attribute "PNN" "P3E_CPU0_PE1_PCH_C_TXP<10>"
					( Origin gPackager )
				)
				( objectStatus "P3E_CPU0_PE1_PCH_C_TXP<10>" )
			)
			( signal "@baseboard_fab2_lib.baseboard_fab2(sch_1):p3e_cpu0_pe1_pch_c_txp(11)"
				( attribute "CDS_PHYS_NET_NAME" "P3E_CPU0_PE1_PCH_C_TXP<11>"
					( Origin gPackager )
				)
				( attribute "PNN" "P3E_CPU0_PE1_PCH_C_TXP<11>"
					( Origin gPackager )
				)
				( objectStatus "P3E_CPU0_PE1_PCH_C_TXP<11>" )
			)
			( signal "@baseboard_fab2_lib.baseboard_fab2(sch_1):p3e_cpu0_pe1_pch_c_txp(12)"
				( attribute "CDS_PHYS_NET_NAME" "P3E_CPU0_PE1_PCH_C_TXP<12>"
					( Origin gPackager )
				)
				( attribute "PNN" "P3E_CPU0_PE1_PCH_C_TXP<12>"
					( Origin gPackager )
				)
				( objectStatus "P3E_CPU0_PE1_PCH_C_TXP<12>" )
			)
			( signal "@baseboard_fab2_lib.baseboard_fab2(sch_1):p3e_cpu0_pe1_pch_c_txp(13)"
				( attribute "CDS_PHYS_NET_NAME" "P3E_CPU0_PE1_PCH_C_TXP<13>"
					( Origin gPackager )
				)
				( attribute "PNN" "P3E_CPU0_PE1_PCH_C_TXP<13>"
					( Origin gPackager )
				)
				( objectStatus "P3E_CPU0_PE1_PCH_C_TXP<13>" )
			)
			( signal "@baseboard_fab2_lib.baseboard_fab2(sch_1):p3e_cpu0_pe1_pch_c_txp(14)"
				( attribute "CDS_PHYS_NET_NAME" "P3E_CPU0_PE1_PCH_C_TXP<14>"
					( Origin gPackager )
				)
				( attribute "PNN" "P3E_CPU0_PE1_PCH_C_TXP<14>"
					( Origin gPackager )
				)
				( objectStatus "P3E_CPU0_PE1_PCH_C_TXP<14>" )
			)
			( signal "@baseboard_fab2_lib.baseboard_fab2(sch_1):p3e_cpu0_pe1_pch_c_txp(15)"
				( attribute "CDS_PHYS_NET_NAME" "P3E_CPU0_PE1_PCH_C_TXP<15>"
					( Origin gPackager )
				)
				( attribute "PNN" "P3E_CPU0_PE1_PCH_C_TXP<15>"
					( Origin gPackager )
				)
				( objectStatus "P3E_CPU0_PE1_PCH_C_TXP<15>" )
			)
			( signal "@baseboard_fab2_lib.baseboard_fab2(sch_1):p3e_cpu0_pe1_pch_r_rxn(8)"
				( attribute "CDS_PHYS_NET_NAME" "P3E_CPU0_PE1_PCH_R_RXN<8>"
					( Origin gPackager )
				)
				( attribute "PNN" "P3E_CPU0_PE1_PCH_R_RXN<8>"
					( Origin gPackager )
				)
				( objectStatus "P3E_CPU0_PE1_PCH_R_RXN<8>" )
			)
			( signal "@baseboard_fab2_lib.baseboard_fab2(sch_1):p3e_cpu0_pe1_pch_r_rxn(9)"
				( attribute "CDS_PHYS_NET_NAME" "P3E_CPU0_PE1_PCH_R_RXN<9>"
					( Origin gPackager )
				)
				( attribute "PNN" "P3E_CPU0_PE1_PCH_R_RXN<9>"
					( Origin gPackager )
				)
				( objectStatus "P3E_CPU0_PE1_PCH_R_RXN<9>" )
			)
			( signal "@baseboard_fab2_lib.baseboard_fab2(sch_1):p3e_cpu0_pe1_pch_r_rxn(10)"
				( attribute "CDS_PHYS_NET_NAME" "P3E_CPU0_PE1_PCH_R_RXN<10>"
					( Origin gPackager )
				)
				( attribute "PNN" "P3E_CPU0_PE1_PCH_R_RXN<10>"
					( Origin gPackager )
				)
				( objectStatus "P3E_CPU0_PE1_PCH_R_RXN<10>" )
			)
			( signal "@baseboard_fab2_lib.baseboard_fab2(sch_1):p3e_cpu0_pe1_pch_r_rxn(11)"
				( attribute "CDS_PHYS_NET_NAME" "P3E_CPU0_PE1_PCH_R_RXN<11>"
					( Origin gPackager )
				)
				( attribute "PNN" "P3E_CPU0_PE1_PCH_R_RXN<11>"
					( Origin gPackager )
				)
				( objectStatus "P3E_CPU0_PE1_PCH_R_RXN<11>" )
			)
			( signal "@baseboard_fab2_lib.baseboard_fab2(sch_1):p3e_cpu0_pe1_pch_r_rxn(12)"
				( attribute "CDS_PHYS_NET_NAME" "P3E_CPU0_PE1_PCH_R_RXN<12>"
					( Origin gPackager )
				)
				( attribute "PNN" "P3E_CPU0_PE1_PCH_R_RXN<12>"
					( Origin gPackager )
				)
				( objectStatus "P3E_CPU0_PE1_PCH_R_RXN<12>" )
			)
			( signal "@baseboard_fab2_lib.baseboard_fab2(sch_1):p3e_cpu0_pe1_pch_r_rxn(13)"
				( attribute "CDS_PHYS_NET_NAME" "P3E_CPU0_PE1_PCH_R_RXN<13>"
					( Origin gPackager )
				)
				( attribute "PNN" "P3E_CPU0_PE1_PCH_R_RXN<13>"
					( Origin gPackager )
				)
				( objectStatus "P3E_CPU0_PE1_PCH_R_RXN<13>" )
			)
			( signal "@baseboard_fab2_lib.baseboard_fab2(sch_1):p3e_cpu0_pe1_pch_r_rxn(14)"
				( attribute "CDS_PHYS_NET_NAME" "P3E_CPU0_PE1_PCH_R_RXN<14>"
					( Origin gPackager )
				)
				( attribute "PNN" "P3E_CPU0_PE1_PCH_R_RXN<14>"
					( Origin gPackager )
				)
				( objectStatus "P3E_CPU0_PE1_PCH_R_RXN<14>" )
			)
			( signal "@baseboard_fab2_lib.baseboard_fab2(sch_1):p3e_cpu0_pe1_pch_r_rxn(15)"
				( attribute "CDS_PHYS_NET_NAME" "P3E_CPU0_PE1_PCH_R_RXN<15>"
					( Origin gPackager )
				)
				( attribute "PNN" "P3E_CPU0_PE1_PCH_R_RXN<15>"
					( Origin gPackager )
				)
				( objectStatus "P3E_CPU0_PE1_PCH_R_RXN<15>" )
			)
			( signal "@baseboard_fab2_lib.baseboard_fab2(sch_1):p3e_cpu0_pe1_pch_r_rxp(8)"
				( attribute "CDS_PHYS_NET_NAME" "P3E_CPU0_PE1_PCH_R_RXP<8>"
					( Origin gPackager )
				)
				( attribute "PNN" "P3E_CPU0_PE1_PCH_R_RXP<8>"
					( Origin gPackager )
				)
				( objectStatus "P3E_CPU0_PE1_PCH_R_RXP<8>" )
			)
			( signal "@baseboard_fab2_lib.baseboard_fab2(sch_1):p3e_cpu0_pe1_pch_r_rxp(9)"
				( attribute "CDS_PHYS_NET_NAME" "P3E_CPU0_PE1_PCH_R_RXP<9>"
					( Origin gPackager )
				)
				( attribute "PNN" "P3E_CPU0_PE1_PCH_R_RXP<9>"
					( Origin gPackager )
				)
				( objectStatus "P3E_CPU0_PE1_PCH_R_RXP<9>" )
			)
			( signal "@baseboard_fab2_lib.baseboard_fab2(sch_1):p3e_cpu0_pe1_pch_r_rxp(10)"
				( attribute "CDS_PHYS_NET_NAME" "P3E_CPU0_PE1_PCH_R_RXP<10>"
					( Origin gPackager )
				)
				( attribute "PNN" "P3E_CPU0_PE1_PCH_R_RXP<10>"
					( Origin gPackager )
				)
				( objectStatus "P3E_CPU0_PE1_PCH_R_RXP<10>" )
			)
			( signal "@baseboard_fab2_lib.baseboard_fab2(sch_1):p3e_cpu0_pe1_pch_r_rxp(11)"
				( attribute "CDS_PHYS_NET_NAME" "P3E_CPU0_PE1_PCH_R_RXP<11>"
					( Origin gPackager )
				)
				( attribute "PNN" "P3E_CPU0_PE1_PCH_R_RXP<11>"
					( Origin gPackager )
				)
				( objectStatus "P3E_CPU0_PE1_PCH_R_RXP<11>" )
			)
			( signal "@baseboard_fab2_lib.baseboard_fab2(sch_1):p3e_cpu0_pe1_pch_r_rxp(12)"
				( attribute "CDS_PHYS_NET_NAME" "P3E_CPU0_PE1_PCH_R_RXP<12>"
					( Origin gPackager )
				)
				( attribute "PNN" "P3E_CPU0_PE1_PCH_R_RXP<12>"
					( Origin gPackager )
				)
				( objectStatus "P3E_CPU0_PE1_PCH_R_RXP<12>" )
			)
			( signal "@baseboard_fab2_lib.baseboard_fab2(sch_1):p3e_cpu0_pe1_pch_r_rxp(13)"
				( attribute "CDS_PHYS_NET_NAME" "P3E_CPU0_PE1_PCH_R_RXP<13>"
					( Origin gPackager )
				)
				( attribute "PNN" "P3E_CPU0_PE1_PCH_R_RXP<13>"
					( Origin gPackager )
				)
				( objectStatus "P3E_CPU0_PE1_PCH_R_RXP<13>" )
			)
			( signal "@baseboard_fab2_lib.baseboard_fab2(sch_1):p3e_cpu0_pe1_pch_r_rxp(14)"
				( attribute "CDS_PHYS_NET_NAME" "P3E_CPU0_PE1_PCH_R_RXP<14>"
					( Origin gPackager )
				)
				( attribute "PNN" "P3E_CPU0_PE1_PCH_R_RXP<14>"
					( Origin gPackager )
				)
				( objectStatus "P3E_CPU0_PE1_PCH_R_RXP<14>" )
			)
			( signal "@baseboard_fab2_lib.baseboard_fab2(sch_1):p3e_cpu0_pe1_pch_r_rxp(15)"
				( attribute "CDS_PHYS_NET_NAME" "P3E_CPU0_PE1_PCH_R_RXP<15>"
					( Origin gPackager )
				)
				( attribute "PNN" "P3E_CPU0_PE1_PCH_R_RXP<15>"
					( Origin gPackager )
				)
				( objectStatus "P3E_CPU0_PE1_PCH_R_RXP<15>" )
			)
			( signal "@baseboard_fab2_lib.baseboard_fab2(sch_1):p3e_cpu0_pe2_ss_c_txn(0)"
				( attribute "CDS_PHYS_NET_NAME" "P3E_CPU0_PE2_SS_C_TXN<0>"
					( Origin gPackager )
				)
				( attribute "PNN" "P3E_CPU0_PE2_SS_C_TXN<0>"
					( Origin gPackager )
				)
				( objectStatus "P3E_CPU0_PE2_SS_C_TXN<0>" )
			)
			( signal "@baseboard_fab2_lib.baseboard_fab2(sch_1):p3e_cpu0_pe2_ss_c_txn(1)"
				( attribute "CDS_PHYS_NET_NAME" "P3E_CPU0_PE2_SS_C_TXN<1>"
					( Origin gPackager )
				)
				( attribute "PNN" "P3E_CPU0_PE2_SS_C_TXN<1>"
					( Origin gPackager )
				)
				( objectStatus "P3E_CPU0_PE2_SS_C_TXN<1>" )
			)
			( signal "@baseboard_fab2_lib.baseboard_fab2(sch_1):p3e_cpu0_pe2_ss_c_txn(2)"
				( attribute "CDS_PHYS_NET_NAME" "P3E_CPU0_PE2_SS_C_TXN<2>"
					( Origin gPackager )
				)
				( attribute "PNN" "P3E_CPU0_PE2_SS_C_TXN<2>"
					( Origin gPackager )
				)
				( objectStatus "P3E_CPU0_PE2_SS_C_TXN<2>" )
			)
			( signal "@baseboard_fab2_lib.baseboard_fab2(sch_1):p3e_cpu0_pe2_ss_c_txn(3)"
				( attribute "CDS_PHYS_NET_NAME" "P3E_CPU0_PE2_SS_C_TXN<3>"
					( Origin gPackager )
				)
				( attribute "PNN" "P3E_CPU0_PE2_SS_C_TXN<3>"
					( Origin gPackager )
				)
				( objectStatus "P3E_CPU0_PE2_SS_C_TXN<3>" )
			)
			( signal "@baseboard_fab2_lib.baseboard_fab2(sch_1):p3e_cpu0_pe2_ss_c_txn(4)"
				( attribute "CDS_PHYS_NET_NAME" "P3E_CPU0_PE2_SS_C_TXN<4>"
					( Origin gPackager )
				)
				( attribute "PNN" "P3E_CPU0_PE2_SS_C_TXN<4>"
					( Origin gPackager )
				)
				( objectStatus "P3E_CPU0_PE2_SS_C_TXN<4>" )
			)
			( signal "@baseboard_fab2_lib.baseboard_fab2(sch_1):p3e_cpu0_pe2_ss_c_txn(5)"
				( attribute "CDS_PHYS_NET_NAME" "P3E_CPU0_PE2_SS_C_TXN<5>"
					( Origin gPackager )
				)
				( attribute "PNN" "P3E_CPU0_PE2_SS_C_TXN<5>"
					( Origin gPackager )
				)
				( objectStatus "P3E_CPU0_PE2_SS_C_TXN<5>" )
			)
			( signal "@baseboard_fab2_lib.baseboard_fab2(sch_1):p3e_cpu0_pe2_ss_c_txn(6)"
				( attribute "CDS_PHYS_NET_NAME" "P3E_CPU0_PE2_SS_C_TXN<6>"
					( Origin gPackager )
				)
				( attribute "PNN" "P3E_CPU0_PE2_SS_C_TXN<6>"
					( Origin gPackager )
				)
				( objectStatus "P3E_CPU0_PE2_SS_C_TXN<6>" )
			)
			( signal "@baseboard_fab2_lib.baseboard_fab2(sch_1):p3e_cpu0_pe2_ss_c_txn(7)"
				( attribute "CDS_PHYS_NET_NAME" "P3E_CPU0_PE2_SS_C_TXN<7>"
					( Origin gPackager )
				)
				( attribute "PNN" "P3E_CPU0_PE2_SS_C_TXN<7>"
					( Origin gPackager )
				)
				( objectStatus "P3E_CPU0_PE2_SS_C_TXN<7>" )
			)
			( signal "@baseboard_fab2_lib.baseboard_fab2(sch_1):p3e_cpu0_pe2_ss_c_txn(8)"
				( attribute "CDS_PHYS_NET_NAME" "P3E_CPU0_PE2_SS_C_TXN<8>"
					( Origin gPackager )
				)
				( attribute "PNN" "P3E_CPU0_PE2_SS_C_TXN<8>"
					( Origin gPackager )
				)
				( objectStatus "P3E_CPU0_PE2_SS_C_TXN<8>" )
			)
			( signal "@baseboard_fab2_lib.baseboard_fab2(sch_1):p3e_cpu0_pe2_ss_c_txn(9)"
				( attribute "CDS_PHYS_NET_NAME" "P3E_CPU0_PE2_SS_C_TXN<9>"
					( Origin gPackager )
				)
				( attribute "PNN" "P3E_CPU0_PE2_SS_C_TXN<9>"
					( Origin gPackager )
				)
				( objectStatus "P3E_CPU0_PE2_SS_C_TXN<9>" )
			)
			( signal "@baseboard_fab2_lib.baseboard_fab2(sch_1):p3e_cpu0_pe2_ss_c_txn(10)"
				( attribute "CDS_PHYS_NET_NAME" "P3E_CPU0_PE2_SS_C_TXN<10>"
					( Origin gPackager )
				)
				( attribute "PNN" "P3E_CPU0_PE2_SS_C_TXN<10>"
					( Origin gPackager )
				)
				( objectStatus "P3E_CPU0_PE2_SS_C_TXN<10>" )
			)
			( signal "@baseboard_fab2_lib.baseboard_fab2(sch_1):p3e_cpu0_pe2_ss_c_txn(11)"
				( attribute "CDS_PHYS_NET_NAME" "P3E_CPU0_PE2_SS_C_TXN<11>"
					( Origin gPackager )
				)
				( attribute "PNN" "P3E_CPU0_PE2_SS_C_TXN<11>"
					( Origin gPackager )
				)
				( objectStatus "P3E_CPU0_PE2_SS_C_TXN<11>" )
			)
			( signal "@baseboard_fab2_lib.baseboard_fab2(sch_1):p3e_cpu0_pe2_ss_c_txn(12)"
				( attribute "CDS_PHYS_NET_NAME" "P3E_CPU0_PE2_SS_C_TXN<12>"
					( Origin gPackager )
				)
				( attribute "PNN" "P3E_CPU0_PE2_SS_C_TXN<12>"
					( Origin gPackager )
				)
				( objectStatus "P3E_CPU0_PE2_SS_C_TXN<12>" )
			)
			( signal "@baseboard_fab2_lib.baseboard_fab2(sch_1):p3e_cpu0_pe2_ss_c_txn(13)"
				( attribute "CDS_PHYS_NET_NAME" "P3E_CPU0_PE2_SS_C_TXN<13>"
					( Origin gPackager )
				)
				( attribute "PNN" "P3E_CPU0_PE2_SS_C_TXN<13>"
					( Origin gPackager )
				)
				( objectStatus "P3E_CPU0_PE2_SS_C_TXN<13>" )
			)
			( signal "@baseboard_fab2_lib.baseboard_fab2(sch_1):p3e_cpu0_pe2_ss_c_txn(14)"
				( attribute "CDS_PHYS_NET_NAME" "P3E_CPU0_PE2_SS_C_TXN<14>"
					( Origin gPackager )
				)
				( attribute "PNN" "P3E_CPU0_PE2_SS_C_TXN<14>"
					( Origin gPackager )
				)
				( objectStatus "P3E_CPU0_PE2_SS_C_TXN<14>" )
			)
			( signal "@baseboard_fab2_lib.baseboard_fab2(sch_1):p3e_cpu0_pe2_ss_c_txn(15)"
				( attribute "CDS_PHYS_NET_NAME" "P3E_CPU0_PE2_SS_C_TXN<15>"
					( Origin gPackager )
				)
				( attribute "PNN" "P3E_CPU0_PE2_SS_C_TXN<15>"
					( Origin gPackager )
				)
				( objectStatus "P3E_CPU0_PE2_SS_C_TXN<15>" )
			)
			( signal "@baseboard_fab2_lib.baseboard_fab2(sch_1):p3e_cpu0_pe2_ss_c_txp(0)"
				( attribute "CDS_PHYS_NET_NAME" "P3E_CPU0_PE2_SS_C_TXP<0>"
					( Origin gPackager )
				)
				( attribute "PNN" "P3E_CPU0_PE2_SS_C_TXP<0>"
					( Origin gPackager )
				)
				( objectStatus "P3E_CPU0_PE2_SS_C_TXP<0>" )
			)
			( signal "@baseboard_fab2_lib.baseboard_fab2(sch_1):p3e_cpu0_pe2_ss_c_txp(1)"
				( attribute "CDS_PHYS_NET_NAME" "P3E_CPU0_PE2_SS_C_TXP<1>"
					( Origin gPackager )
				)
				( attribute "PNN" "P3E_CPU0_PE2_SS_C_TXP<1>"
					( Origin gPackager )
				)
				( objectStatus "P3E_CPU0_PE2_SS_C_TXP<1>" )
			)
			( signal "@baseboard_fab2_lib.baseboard_fab2(sch_1):p3e_cpu0_pe2_ss_c_txp(2)"
				( attribute "CDS_PHYS_NET_NAME" "P3E_CPU0_PE2_SS_C_TXP<2>"
					( Origin gPackager )
				)
				( attribute "PNN" "P3E_CPU0_PE2_SS_C_TXP<2>"
					( Origin gPackager )
				)
				( objectStatus "P3E_CPU0_PE2_SS_C_TXP<2>" )
			)
			( signal "@baseboard_fab2_lib.baseboard_fab2(sch_1):p3e_cpu0_pe2_ss_c_txp(3)"
				( attribute "CDS_PHYS_NET_NAME" "P3E_CPU0_PE2_SS_C_TXP<3>"
					( Origin gPackager )
				)
				( attribute "PNN" "P3E_CPU0_PE2_SS_C_TXP<3>"
					( Origin gPackager )
				)
				( objectStatus "P3E_CPU0_PE2_SS_C_TXP<3>" )
			)
			( signal "@baseboard_fab2_lib.baseboard_fab2(sch_1):p3e_cpu0_pe2_ss_c_txp(4)"
				( attribute "CDS_PHYS_NET_NAME" "P3E_CPU0_PE2_SS_C_TXP<4>"
					( Origin gPackager )
				)
				( attribute "PNN" "P3E_CPU0_PE2_SS_C_TXP<4>"
					( Origin gPackager )
				)
				( objectStatus "P3E_CPU0_PE2_SS_C_TXP<4>" )
			)
			( signal "@baseboard_fab2_lib.baseboard_fab2(sch_1):p3e_cpu0_pe2_ss_c_txp(5)"
				( attribute "CDS_PHYS_NET_NAME" "P3E_CPU0_PE2_SS_C_TXP<5>"
					( Origin gPackager )
				)
				( attribute "PNN" "P3E_CPU0_PE2_SS_C_TXP<5>"
					( Origin gPackager )
				)
				( objectStatus "P3E_CPU0_PE2_SS_C_TXP<5>" )
			)
			( signal "@baseboard_fab2_lib.baseboard_fab2(sch_1):p3e_cpu0_pe2_ss_c_txp(6)"
				( attribute "CDS_PHYS_NET_NAME" "P3E_CPU0_PE2_SS_C_TXP<6>"
					( Origin gPackager )
				)
				( attribute "PNN" "P3E_CPU0_PE2_SS_C_TXP<6>"
					( Origin gPackager )
				)
				( objectStatus "P3E_CPU0_PE2_SS_C_TXP<6>" )
			)
			( signal "@baseboard_fab2_lib.baseboard_fab2(sch_1):p3e_cpu0_pe2_ss_c_txp(7)"
				( attribute "CDS_PHYS_NET_NAME" "P3E_CPU0_PE2_SS_C_TXP<7>"
					( Origin gPackager )
				)
				( attribute "PNN" "P3E_CPU0_PE2_SS_C_TXP<7>"
					( Origin gPackager )
				)
				( objectStatus "P3E_CPU0_PE2_SS_C_TXP<7>" )
			)
			( signal "@baseboard_fab2_lib.baseboard_fab2(sch_1):p3e_cpu0_pe2_ss_c_txp(8)"
				( attribute "CDS_PHYS_NET_NAME" "P3E_CPU0_PE2_SS_C_TXP<8>"
					( Origin gPackager )
				)
				( attribute "PNN" "P3E_CPU0_PE2_SS_C_TXP<8>"
					( Origin gPackager )
				)
				( objectStatus "P3E_CPU0_PE2_SS_C_TXP<8>" )
			)
			( signal "@baseboard_fab2_lib.baseboard_fab2(sch_1):p3e_cpu0_pe2_ss_c_txp(9)"
				( attribute "CDS_PHYS_NET_NAME" "P3E_CPU0_PE2_SS_C_TXP<9>"
					( Origin gPackager )
				)
				( attribute "PNN" "P3E_CPU0_PE2_SS_C_TXP<9>"
					( Origin gPackager )
				)
				( objectStatus "P3E_CPU0_PE2_SS_C_TXP<9>" )
			)
			( signal "@baseboard_fab2_lib.baseboard_fab2(sch_1):p3e_cpu0_pe2_ss_c_txp(10)"
				( attribute "CDS_PHYS_NET_NAME" "P3E_CPU0_PE2_SS_C_TXP<10>"
					( Origin gPackager )
				)
				( attribute "PNN" "P3E_CPU0_PE2_SS_C_TXP<10>"
					( Origin gPackager )
				)
				( objectStatus "P3E_CPU0_PE2_SS_C_TXP<10>" )
			)
			( signal "@baseboard_fab2_lib.baseboard_fab2(sch_1):p3e_cpu0_pe2_ss_c_txp(11)"
				( attribute "CDS_PHYS_NET_NAME" "P3E_CPU0_PE2_SS_C_TXP<11>"
					( Origin gPackager )
				)
				( attribute "PNN" "P3E_CPU0_PE2_SS_C_TXP<11>"
					( Origin gPackager )
				)
				( objectStatus "P3E_CPU0_PE2_SS_C_TXP<11>" )
			)
			( signal "@baseboard_fab2_lib.baseboard_fab2(sch_1):p3e_cpu0_pe2_ss_c_txp(12)"
				( attribute "CDS_PHYS_NET_NAME" "P3E_CPU0_PE2_SS_C_TXP<12>"
					( Origin gPackager )
				)
				( attribute "PNN" "P3E_CPU0_PE2_SS_C_TXP<12>"
					( Origin gPackager )
				)
				( objectStatus "P3E_CPU0_PE2_SS_C_TXP<12>" )
			)
			( signal "@baseboard_fab2_lib.baseboard_fab2(sch_1):p3e_cpu0_pe2_ss_c_txp(13)"
				( attribute "CDS_PHYS_NET_NAME" "P3E_CPU0_PE2_SS_C_TXP<13>"
					( Origin gPackager )
				)
				( attribute "PNN" "P3E_CPU0_PE2_SS_C_TXP<13>"
					( Origin gPackager )
				)
				( objectStatus "P3E_CPU0_PE2_SS_C_TXP<13>" )
			)
			( signal "@baseboard_fab2_lib.baseboard_fab2(sch_1):p3e_cpu0_pe2_ss_c_txp(14)"
				( attribute "CDS_PHYS_NET_NAME" "P3E_CPU0_PE2_SS_C_TXP<14>"
					( Origin gPackager )
				)
				( attribute "PNN" "P3E_CPU0_PE2_SS_C_TXP<14>"
					( Origin gPackager )
				)
				( objectStatus "P3E_CPU0_PE2_SS_C_TXP<14>" )
			)
			( signal "@baseboard_fab2_lib.baseboard_fab2(sch_1):p3e_cpu0_pe2_ss_c_txp(15)"
				( attribute "CDS_PHYS_NET_NAME" "P3E_CPU0_PE2_SS_C_TXP<15>"
					( Origin gPackager )
				)
				( attribute "PNN" "P3E_CPU0_PE2_SS_C_TXP<15>"
					( Origin gPackager )
				)
				( objectStatus "P3E_CPU0_PE2_SS_C_TXP<15>" )
			)
			( signal "@baseboard_fab2_lib.baseboard_fab2(sch_1):p3e_ocp_cpu0_pe3_c_txn(0)"
				( attribute "CDS_PHYS_NET_NAME" "P3E_OCP_CPU0_PE3_C_TXN<0>"
					( Origin gPackager )
				)
				( attribute "PNN" "P3E_OCP_CPU0_PE3_C_TXN<0>"
					( Origin gPackager )
				)
				( objectStatus "P3E_OCP_CPU0_PE3_C_TXN<0>" )
			)
			( signal "@baseboard_fab2_lib.baseboard_fab2(sch_1):p3e_ocp_cpu0_pe3_c_txn(1)"
				( attribute "CDS_PHYS_NET_NAME" "P3E_OCP_CPU0_PE3_C_TXN<1>"
					( Origin gPackager )
				)
				( attribute "PNN" "P3E_OCP_CPU0_PE3_C_TXN<1>"
					( Origin gPackager )
				)
				( objectStatus "P3E_OCP_CPU0_PE3_C_TXN<1>" )
			)
			( signal "@baseboard_fab2_lib.baseboard_fab2(sch_1):p3e_ocp_cpu0_pe3_c_txn(2)"
				( attribute "CDS_PHYS_NET_NAME" "P3E_OCP_CPU0_PE3_C_TXN<2>"
					( Origin gPackager )
				)
				( attribute "PNN" "P3E_OCP_CPU0_PE3_C_TXN<2>"
					( Origin gPackager )
				)
				( objectStatus "P3E_OCP_CPU0_PE3_C_TXN<2>" )
			)
			( signal "@baseboard_fab2_lib.baseboard_fab2(sch_1):p3e_ocp_cpu0_pe3_c_txn(3)"
				( attribute "CDS_PHYS_NET_NAME" "P3E_OCP_CPU0_PE3_C_TXN<3>"
					( Origin gPackager )
				)
				( attribute "PNN" "P3E_OCP_CPU0_PE3_C_TXN<3>"
					( Origin gPackager )
				)
				( objectStatus "P3E_OCP_CPU0_PE3_C_TXN<3>" )
			)
			( signal "@baseboard_fab2_lib.baseboard_fab2(sch_1):p3e_ocp_cpu0_pe3_c_txn(4)"
				( attribute "CDS_PHYS_NET_NAME" "P3E_OCP_CPU0_PE3_C_TXN<4>"
					( Origin gPackager )
				)
				( attribute "PNN" "P3E_OCP_CPU0_PE3_C_TXN<4>"
					( Origin gPackager )
				)
				( objectStatus "P3E_OCP_CPU0_PE3_C_TXN<4>" )
			)
			( signal "@baseboard_fab2_lib.baseboard_fab2(sch_1):p3e_ocp_cpu0_pe3_c_txn(5)"
				( attribute "CDS_PHYS_NET_NAME" "P3E_OCP_CPU0_PE3_C_TXN<5>"
					( Origin gPackager )
				)
				( attribute "PNN" "P3E_OCP_CPU0_PE3_C_TXN<5>"
					( Origin gPackager )
				)
				( objectStatus "P3E_OCP_CPU0_PE3_C_TXN<5>" )
			)
			( signal "@baseboard_fab2_lib.baseboard_fab2(sch_1):p3e_ocp_cpu0_pe3_c_txn(6)"
				( attribute "CDS_PHYS_NET_NAME" "P3E_OCP_CPU0_PE3_C_TXN<6>"
					( Origin gPackager )
				)
				( attribute "PNN" "P3E_OCP_CPU0_PE3_C_TXN<6>"
					( Origin gPackager )
				)
				( objectStatus "P3E_OCP_CPU0_PE3_C_TXN<6>" )
			)
			( signal "@baseboard_fab2_lib.baseboard_fab2(sch_1):p3e_ocp_cpu0_pe3_c_txn(7)"
				( attribute "CDS_PHYS_NET_NAME" "P3E_OCP_CPU0_PE3_C_TXN<7>"
					( Origin gPackager )
				)
				( attribute "PNN" "P3E_OCP_CPU0_PE3_C_TXN<7>"
					( Origin gPackager )
				)
				( objectStatus "P3E_OCP_CPU0_PE3_C_TXN<7>" )
			)
			( signal "@baseboard_fab2_lib.baseboard_fab2(sch_1):p3e_ocp_cpu0_pe3_c_txn(8)"
				( attribute "CDS_PHYS_NET_NAME" "P3E_OCP_CPU0_PE3_C_TXN<8>"
					( Origin gPackager )
				)
				( attribute "PNN" "P3E_OCP_CPU0_PE3_C_TXN<8>"
					( Origin gPackager )
				)
				( objectStatus "P3E_OCP_CPU0_PE3_C_TXN<8>" )
			)
			( signal "@baseboard_fab2_lib.baseboard_fab2(sch_1):p3e_ocp_cpu0_pe3_c_txn(9)"
				( attribute "CDS_PHYS_NET_NAME" "P3E_OCP_CPU0_PE3_C_TXN<9>"
					( Origin gPackager )
				)
				( attribute "PNN" "P3E_OCP_CPU0_PE3_C_TXN<9>"
					( Origin gPackager )
				)
				( objectStatus "P3E_OCP_CPU0_PE3_C_TXN<9>" )
			)
			( signal "@baseboard_fab2_lib.baseboard_fab2(sch_1):p3e_ocp_cpu0_pe3_c_txn(10)"
				( attribute "CDS_PHYS_NET_NAME" "P3E_OCP_CPU0_PE3_C_TXN<10>"
					( Origin gPackager )
				)
				( attribute "PNN" "P3E_OCP_CPU0_PE3_C_TXN<10>"
					( Origin gPackager )
				)
				( objectStatus "P3E_OCP_CPU0_PE3_C_TXN<10>" )
			)
			( signal "@baseboard_fab2_lib.baseboard_fab2(sch_1):p3e_ocp_cpu0_pe3_c_txn(11)"
				( attribute "CDS_PHYS_NET_NAME" "P3E_OCP_CPU0_PE3_C_TXN<11>"
					( Origin gPackager )
				)
				( attribute "PNN" "P3E_OCP_CPU0_PE3_C_TXN<11>"
					( Origin gPackager )
				)
				( objectStatus "P3E_OCP_CPU0_PE3_C_TXN<11>" )
			)
			( signal "@baseboard_fab2_lib.baseboard_fab2(sch_1):p3e_ocp_cpu0_pe3_c_txn(12)"
				( attribute "CDS_PHYS_NET_NAME" "P3E_OCP_CPU0_PE3_C_TXN<12>"
					( Origin gPackager )
				)
				( attribute "PNN" "P3E_OCP_CPU0_PE3_C_TXN<12>"
					( Origin gPackager )
				)
				( objectStatus "P3E_OCP_CPU0_PE3_C_TXN<12>" )
			)
			( signal "@baseboard_fab2_lib.baseboard_fab2(sch_1):p3e_ocp_cpu0_pe3_c_txn(13)"
				( attribute "CDS_PHYS_NET_NAME" "P3E_OCP_CPU0_PE3_C_TXN<13>"
					( Origin gPackager )
				)
				( attribute "PNN" "P3E_OCP_CPU0_PE3_C_TXN<13>"
					( Origin gPackager )
				)
				( objectStatus "P3E_OCP_CPU0_PE3_C_TXN<13>" )
			)
			( signal "@baseboard_fab2_lib.baseboard_fab2(sch_1):p3e_ocp_cpu0_pe3_c_txn(14)"
				( attribute "CDS_PHYS_NET_NAME" "P3E_OCP_CPU0_PE3_C_TXN<14>"
					( Origin gPackager )
				)
				( attribute "PNN" "P3E_OCP_CPU0_PE3_C_TXN<14>"
					( Origin gPackager )
				)
				( objectStatus "P3E_OCP_CPU0_PE3_C_TXN<14>" )
			)
			( signal "@baseboard_fab2_lib.baseboard_fab2(sch_1):p3e_ocp_cpu0_pe3_c_txn(15)"
				( attribute "CDS_PHYS_NET_NAME" "P3E_OCP_CPU0_PE3_C_TXN<15>"
					( Origin gPackager )
				)
				( attribute "PNN" "P3E_OCP_CPU0_PE3_C_TXN<15>"
					( Origin gPackager )
				)
				( objectStatus "P3E_OCP_CPU0_PE3_C_TXN<15>" )
			)
			( signal "@baseboard_fab2_lib.baseboard_fab2(sch_1):p3e_ocp_cpu0_pe3_c_txp(0)"
				( attribute "CDS_PHYS_NET_NAME" "P3E_OCP_CPU0_PE3_C_TXP<0>"
					( Origin gPackager )
				)
				( attribute "PNN" "P3E_OCP_CPU0_PE3_C_TXP<0>"
					( Origin gPackager )
				)
				( objectStatus "P3E_OCP_CPU0_PE3_C_TXP<0>" )
			)
			( signal "@baseboard_fab2_lib.baseboard_fab2(sch_1):p3e_ocp_cpu0_pe3_c_txp(1)"
				( attribute "CDS_PHYS_NET_NAME" "P3E_OCP_CPU0_PE3_C_TXP<1>"
					( Origin gPackager )
				)
				( attribute "PNN" "P3E_OCP_CPU0_PE3_C_TXP<1>"
					( Origin gPackager )
				)
				( objectStatus "P3E_OCP_CPU0_PE3_C_TXP<1>" )
			)
			( signal "@baseboard_fab2_lib.baseboard_fab2(sch_1):p3e_ocp_cpu0_pe3_c_txp(2)"
				( attribute "CDS_PHYS_NET_NAME" "P3E_OCP_CPU0_PE3_C_TXP<2>"
					( Origin gPackager )
				)
				( attribute "PNN" "P3E_OCP_CPU0_PE3_C_TXP<2>"
					( Origin gPackager )
				)
				( objectStatus "P3E_OCP_CPU0_PE3_C_TXP<2>" )
			)
			( signal "@baseboard_fab2_lib.baseboard_fab2(sch_1):p3e_ocp_cpu0_pe3_c_txp(3)"
				( attribute "CDS_PHYS_NET_NAME" "P3E_OCP_CPU0_PE3_C_TXP<3>"
					( Origin gPackager )
				)
				( attribute "PNN" "P3E_OCP_CPU0_PE3_C_TXP<3>"
					( Origin gPackager )
				)
				( objectStatus "P3E_OCP_CPU0_PE3_C_TXP<3>" )
			)
			( signal "@baseboard_fab2_lib.baseboard_fab2(sch_1):p3e_ocp_cpu0_pe3_c_txp(4)"
				( attribute "CDS_PHYS_NET_NAME" "P3E_OCP_CPU0_PE3_C_TXP<4>"
					( Origin gPackager )
				)
				( attribute "PNN" "P3E_OCP_CPU0_PE3_C_TXP<4>"
					( Origin gPackager )
				)
				( objectStatus "P3E_OCP_CPU0_PE3_C_TXP<4>" )
			)
			( signal "@baseboard_fab2_lib.baseboard_fab2(sch_1):p3e_ocp_cpu0_pe3_c_txp(5)"
				( attribute "CDS_PHYS_NET_NAME" "P3E_OCP_CPU0_PE3_C_TXP<5>"
					( Origin gPackager )
				)
				( attribute "PNN" "P3E_OCP_CPU0_PE3_C_TXP<5>"
					( Origin gPackager )
				)
				( objectStatus "P3E_OCP_CPU0_PE3_C_TXP<5>" )
			)
			( signal "@baseboard_fab2_lib.baseboard_fab2(sch_1):p3e_ocp_cpu0_pe3_c_txp(6)"
				( attribute "CDS_PHYS_NET_NAME" "P3E_OCP_CPU0_PE3_C_TXP<6>"
					( Origin gPackager )
				)
				( attribute "PNN" "P3E_OCP_CPU0_PE3_C_TXP<6>"
					( Origin gPackager )
				)
				( objectStatus "P3E_OCP_CPU0_PE3_C_TXP<6>" )
			)
			( signal "@baseboard_fab2_lib.baseboard_fab2(sch_1):p3e_ocp_cpu0_pe3_c_txp(7)"
				( attribute "CDS_PHYS_NET_NAME" "P3E_OCP_CPU0_PE3_C_TXP<7>"
					( Origin gPackager )
				)
				( attribute "PNN" "P3E_OCP_CPU0_PE3_C_TXP<7>"
					( Origin gPackager )
				)
				( objectStatus "P3E_OCP_CPU0_PE3_C_TXP<7>" )
			)
			( signal "@baseboard_fab2_lib.baseboard_fab2(sch_1):p3e_ocp_cpu0_pe3_c_txp(8)"
				( attribute "CDS_PHYS_NET_NAME" "P3E_OCP_CPU0_PE3_C_TXP<8>"
					( Origin gPackager )
				)
				( attribute "PNN" "P3E_OCP_CPU0_PE3_C_TXP<8>"
					( Origin gPackager )
				)
				( objectStatus "P3E_OCP_CPU0_PE3_C_TXP<8>" )
			)
			( signal "@baseboard_fab2_lib.baseboard_fab2(sch_1):p3e_ocp_cpu0_pe3_c_txp(9)"
				( attribute "CDS_PHYS_NET_NAME" "P3E_OCP_CPU0_PE3_C_TXP<9>"
					( Origin gPackager )
				)
				( attribute "PNN" "P3E_OCP_CPU0_PE3_C_TXP<9>"
					( Origin gPackager )
				)
				( objectStatus "P3E_OCP_CPU0_PE3_C_TXP<9>" )
			)
			( signal "@baseboard_fab2_lib.baseboard_fab2(sch_1):p3e_ocp_cpu0_pe3_c_txp(10)"
				( attribute "CDS_PHYS_NET_NAME" "P3E_OCP_CPU0_PE3_C_TXP<10>"
					( Origin gPackager )
				)
				( attribute "PNN" "P3E_OCP_CPU0_PE3_C_TXP<10>"
					( Origin gPackager )
				)
				( objectStatus "P3E_OCP_CPU0_PE3_C_TXP<10>" )
			)
			( signal "@baseboard_fab2_lib.baseboard_fab2(sch_1):p3e_ocp_cpu0_pe3_c_txp(11)"
				( attribute "CDS_PHYS_NET_NAME" "P3E_OCP_CPU0_PE3_C_TXP<11>"
					( Origin gPackager )
				)
				( attribute "PNN" "P3E_OCP_CPU0_PE3_C_TXP<11>"
					( Origin gPackager )
				)
				( objectStatus "P3E_OCP_CPU0_PE3_C_TXP<11>" )
			)
			( signal "@baseboard_fab2_lib.baseboard_fab2(sch_1):p3e_ocp_cpu0_pe3_c_txp(12)"
				( attribute "CDS_PHYS_NET_NAME" "P3E_OCP_CPU0_PE3_C_TXP<12>"
					( Origin gPackager )
				)
				( attribute "PNN" "P3E_OCP_CPU0_PE3_C_TXP<12>"
					( Origin gPackager )
				)
				( objectStatus "P3E_OCP_CPU0_PE3_C_TXP<12>" )
			)
			( signal "@baseboard_fab2_lib.baseboard_fab2(sch_1):p3e_ocp_cpu0_pe3_c_txp(13)"
				( attribute "CDS_PHYS_NET_NAME" "P3E_OCP_CPU0_PE3_C_TXP<13>"
					( Origin gPackager )
				)
				( attribute "PNN" "P3E_OCP_CPU0_PE3_C_TXP<13>"
					( Origin gPackager )
				)
				( objectStatus "P3E_OCP_CPU0_PE3_C_TXP<13>" )
			)
			( signal "@baseboard_fab2_lib.baseboard_fab2(sch_1):p3e_ocp_cpu0_pe3_c_txp(14)"
				( attribute "CDS_PHYS_NET_NAME" "P3E_OCP_CPU0_PE3_C_TXP<14>"
					( Origin gPackager )
				)
				( attribute "PNN" "P3E_OCP_CPU0_PE3_C_TXP<14>"
					( Origin gPackager )
				)
				( objectStatus "P3E_OCP_CPU0_PE3_C_TXP<14>" )
			)
			( signal "@baseboard_fab2_lib.baseboard_fab2(sch_1):p3e_ocp_cpu0_pe3_c_txp(15)"
				( attribute "CDS_PHYS_NET_NAME" "P3E_OCP_CPU0_PE3_C_TXP<15>"
					( Origin gPackager )
				)
				( attribute "PNN" "P3E_OCP_CPU0_PE3_C_TXP<15>"
					( Origin gPackager )
				)
				( objectStatus "P3E_OCP_CPU0_PE3_C_TXP<15>" )
			)
			( signal "@baseboard_fab2_lib.baseboard_fab2(sch_1):p3e_cpu0_pe1_pch_rxn(0)"
				( attribute "CDS_PHYS_NET_NAME" "P3E_CPU0_PE1_PCH_RXN<0>"
					( Origin gPackager )
				)
				( attribute "PNN" "P3E_CPU0_PE1_PCH_RXN<0>"
					( Origin gPackager )
				)
				( objectStatus "P3E_CPU0_PE1_PCH_RXN<0>" )
			)
			( signal "@baseboard_fab2_lib.baseboard_fab2(sch_1):p3e_cpu0_pe1_pch_rxn(1)"
				( attribute "CDS_PHYS_NET_NAME" "P3E_CPU0_PE1_PCH_RXN<1>"
					( Origin gPackager )
				)
				( attribute "PNN" "P3E_CPU0_PE1_PCH_RXN<1>"
					( Origin gPackager )
				)
				( objectStatus "P3E_CPU0_PE1_PCH_RXN<1>" )
			)
			( signal "@baseboard_fab2_lib.baseboard_fab2(sch_1):p3e_cpu0_pe1_pch_rxn(2)"
				( attribute "CDS_PHYS_NET_NAME" "P3E_CPU0_PE1_PCH_RXN<2>"
					( Origin gPackager )
				)
				( attribute "PNN" "P3E_CPU0_PE1_PCH_RXN<2>"
					( Origin gPackager )
				)
				( objectStatus "P3E_CPU0_PE1_PCH_RXN<2>" )
			)
			( signal "@baseboard_fab2_lib.baseboard_fab2(sch_1):p3e_cpu0_pe1_pch_rxn(3)"
				( attribute "CDS_PHYS_NET_NAME" "P3E_CPU0_PE1_PCH_RXN<3>"
					( Origin gPackager )
				)
				( attribute "PNN" "P3E_CPU0_PE1_PCH_RXN<3>"
					( Origin gPackager )
				)
				( objectStatus "P3E_CPU0_PE1_PCH_RXN<3>" )
			)
			( signal "@baseboard_fab2_lib.baseboard_fab2(sch_1):p3e_cpu0_pe1_pch_rxn(4)"
				( attribute "CDS_PHYS_NET_NAME" "P3E_CPU0_PE1_PCH_RXN<4>"
					( Origin gPackager )
				)
				( attribute "PNN" "P3E_CPU0_PE1_PCH_RXN<4>"
					( Origin gPackager )
				)
				( objectStatus "P3E_CPU0_PE1_PCH_RXN<4>" )
			)
			( signal "@baseboard_fab2_lib.baseboard_fab2(sch_1):p3e_cpu0_pe1_pch_rxn(5)"
				( attribute "CDS_PHYS_NET_NAME" "P3E_CPU0_PE1_PCH_RXN<5>"
					( Origin gPackager )
				)
				( attribute "PNN" "P3E_CPU0_PE1_PCH_RXN<5>"
					( Origin gPackager )
				)
				( objectStatus "P3E_CPU0_PE1_PCH_RXN<5>" )
			)
			( signal "@baseboard_fab2_lib.baseboard_fab2(sch_1):p3e_cpu0_pe1_pch_rxn(6)"
				( attribute "CDS_PHYS_NET_NAME" "P3E_CPU0_PE1_PCH_RXN<6>"
					( Origin gPackager )
				)
				( attribute "PNN" "P3E_CPU0_PE1_PCH_RXN<6>"
					( Origin gPackager )
				)
				( objectStatus "P3E_CPU0_PE1_PCH_RXN<6>" )
			)
			( signal "@baseboard_fab2_lib.baseboard_fab2(sch_1):p3e_cpu0_pe1_pch_rxn(7)"
				( attribute "CDS_PHYS_NET_NAME" "P3E_CPU0_PE1_PCH_RXN<7>"
					( Origin gPackager )
				)
				( attribute "PNN" "P3E_CPU0_PE1_PCH_RXN<7>"
					( Origin gPackager )
				)
				( objectStatus "P3E_CPU0_PE1_PCH_RXN<7>" )
			)
			( signal "@baseboard_fab2_lib.baseboard_fab2(sch_1):p3e_cpu0_pe1_pch_rxp(0)"
				( attribute "CDS_PHYS_NET_NAME" "P3E_CPU0_PE1_PCH_RXP<0>"
					( Origin gPackager )
				)
				( attribute "PNN" "P3E_CPU0_PE1_PCH_RXP<0>"
					( Origin gPackager )
				)
				( objectStatus "P3E_CPU0_PE1_PCH_RXP<0>" )
			)
			( signal "@baseboard_fab2_lib.baseboard_fab2(sch_1):p3e_cpu0_pe1_pch_rxp(1)"
				( attribute "CDS_PHYS_NET_NAME" "P3E_CPU0_PE1_PCH_RXP<1>"
					( Origin gPackager )
				)
				( attribute "PNN" "P3E_CPU0_PE1_PCH_RXP<1>"
					( Origin gPackager )
				)
				( objectStatus "P3E_CPU0_PE1_PCH_RXP<1>" )
			)
			( signal "@baseboard_fab2_lib.baseboard_fab2(sch_1):p3e_cpu0_pe1_pch_rxp(2)"
				( attribute "CDS_PHYS_NET_NAME" "P3E_CPU0_PE1_PCH_RXP<2>"
					( Origin gPackager )
				)
				( attribute "PNN" "P3E_CPU0_PE1_PCH_RXP<2>"
					( Origin gPackager )
				)
				( objectStatus "P3E_CPU0_PE1_PCH_RXP<2>" )
			)
			( signal "@baseboard_fab2_lib.baseboard_fab2(sch_1):p3e_cpu0_pe1_pch_rxp(3)"
				( attribute "CDS_PHYS_NET_NAME" "P3E_CPU0_PE1_PCH_RXP<3>"
					( Origin gPackager )
				)
				( attribute "PNN" "P3E_CPU0_PE1_PCH_RXP<3>"
					( Origin gPackager )
				)
				( objectStatus "P3E_CPU0_PE1_PCH_RXP<3>" )
			)
			( signal "@baseboard_fab2_lib.baseboard_fab2(sch_1):p3e_cpu0_pe1_pch_rxp(4)"
				( attribute "CDS_PHYS_NET_NAME" "P3E_CPU0_PE1_PCH_RXP<4>"
					( Origin gPackager )
				)
				( attribute "PNN" "P3E_CPU0_PE1_PCH_RXP<4>"
					( Origin gPackager )
				)
				( objectStatus "P3E_CPU0_PE1_PCH_RXP<4>" )
			)
			( signal "@baseboard_fab2_lib.baseboard_fab2(sch_1):p3e_cpu0_pe1_pch_rxp(5)"
				( attribute "CDS_PHYS_NET_NAME" "P3E_CPU0_PE1_PCH_RXP<5>"
					( Origin gPackager )
				)
				( attribute "PNN" "P3E_CPU0_PE1_PCH_RXP<5>"
					( Origin gPackager )
				)
				( objectStatus "P3E_CPU0_PE1_PCH_RXP<5>" )
			)
			( signal "@baseboard_fab2_lib.baseboard_fab2(sch_1):p3e_cpu0_pe1_pch_rxp(6)"
				( attribute "CDS_PHYS_NET_NAME" "P3E_CPU0_PE1_PCH_RXP<6>"
					( Origin gPackager )
				)
				( attribute "PNN" "P3E_CPU0_PE1_PCH_RXP<6>"
					( Origin gPackager )
				)
				( objectStatus "P3E_CPU0_PE1_PCH_RXP<6>" )
			)
			( signal "@baseboard_fab2_lib.baseboard_fab2(sch_1):p3e_cpu0_pe1_pch_rxp(7)"
				( attribute "CDS_PHYS_NET_NAME" "P3E_CPU0_PE1_PCH_RXP<7>"
					( Origin gPackager )
				)
				( attribute "PNN" "P3E_CPU0_PE1_PCH_RXP<7>"
					( Origin gPackager )
				)
				( objectStatus "P3E_CPU0_PE1_PCH_RXP<7>" )
			)
			( signal "@baseboard_fab2_lib.baseboard_fab2(sch_1):p3e_cpu0_pe1_pch_txn(0)"
				( attribute "CDS_PHYS_NET_NAME" "P3E_CPU0_PE1_PCH_TXN<0>"
					( Origin gPackager )
				)
				( attribute "PNN" "P3E_CPU0_PE1_PCH_TXN<0>"
					( Origin gPackager )
				)
				( objectStatus "P3E_CPU0_PE1_PCH_TXN<0>" )
			)
			( signal "@baseboard_fab2_lib.baseboard_fab2(sch_1):p3e_cpu0_pe1_pch_txn(1)"
				( attribute "CDS_PHYS_NET_NAME" "P3E_CPU0_PE1_PCH_TXN<1>"
					( Origin gPackager )
				)
				( attribute "PNN" "P3E_CPU0_PE1_PCH_TXN<1>"
					( Origin gPackager )
				)
				( objectStatus "P3E_CPU0_PE1_PCH_TXN<1>" )
			)
			( signal "@baseboard_fab2_lib.baseboard_fab2(sch_1):p3e_cpu0_pe1_pch_txn(2)"
				( attribute "CDS_PHYS_NET_NAME" "P3E_CPU0_PE1_PCH_TXN<2>"
					( Origin gPackager )
				)
				( attribute "PNN" "P3E_CPU0_PE1_PCH_TXN<2>"
					( Origin gPackager )
				)
				( objectStatus "P3E_CPU0_PE1_PCH_TXN<2>" )
			)
			( signal "@baseboard_fab2_lib.baseboard_fab2(sch_1):p3e_cpu0_pe1_pch_txn(3)"
				( attribute "CDS_PHYS_NET_NAME" "P3E_CPU0_PE1_PCH_TXN<3>"
					( Origin gPackager )
				)
				( attribute "PNN" "P3E_CPU0_PE1_PCH_TXN<3>"
					( Origin gPackager )
				)
				( objectStatus "P3E_CPU0_PE1_PCH_TXN<3>" )
			)
			( signal "@baseboard_fab2_lib.baseboard_fab2(sch_1):p3e_cpu0_pe1_pch_txn(4)"
				( attribute "CDS_PHYS_NET_NAME" "P3E_CPU0_PE1_PCH_TXN<4>"
					( Origin gPackager )
				)
				( attribute "PNN" "P3E_CPU0_PE1_PCH_TXN<4>"
					( Origin gPackager )
				)
				( objectStatus "P3E_CPU0_PE1_PCH_TXN<4>" )
			)
			( signal "@baseboard_fab2_lib.baseboard_fab2(sch_1):p3e_cpu0_pe1_pch_txn(5)"
				( attribute "CDS_PHYS_NET_NAME" "P3E_CPU0_PE1_PCH_TXN<5>"
					( Origin gPackager )
				)
				( attribute "PNN" "P3E_CPU0_PE1_PCH_TXN<5>"
					( Origin gPackager )
				)
				( objectStatus "P3E_CPU0_PE1_PCH_TXN<5>" )
			)
			( signal "@baseboard_fab2_lib.baseboard_fab2(sch_1):p3e_cpu0_pe1_pch_txn(6)"
				( attribute "CDS_PHYS_NET_NAME" "P3E_CPU0_PE1_PCH_TXN<6>"
					( Origin gPackager )
				)
				( attribute "PNN" "P3E_CPU0_PE1_PCH_TXN<6>"
					( Origin gPackager )
				)
				( objectStatus "P3E_CPU0_PE1_PCH_TXN<6>" )
			)
			( signal "@baseboard_fab2_lib.baseboard_fab2(sch_1):p3e_cpu0_pe1_pch_txn(7)"
				( attribute "CDS_PHYS_NET_NAME" "P3E_CPU0_PE1_PCH_TXN<7>"
					( Origin gPackager )
				)
				( attribute "PNN" "P3E_CPU0_PE1_PCH_TXN<7>"
					( Origin gPackager )
				)
				( objectStatus "P3E_CPU0_PE1_PCH_TXN<7>" )
			)
			( signal "@baseboard_fab2_lib.baseboard_fab2(sch_1):p3e_cpu0_pe1_pch_txp(0)"
				( attribute "CDS_PHYS_NET_NAME" "P3E_CPU0_PE1_PCH_TXP<0>"
					( Origin gPackager )
				)
				( attribute "PNN" "P3E_CPU0_PE1_PCH_TXP<0>"
					( Origin gPackager )
				)
				( objectStatus "P3E_CPU0_PE1_PCH_TXP<0>" )
			)
			( signal "@baseboard_fab2_lib.baseboard_fab2(sch_1):p3e_cpu0_pe1_pch_txp(1)"
				( attribute "CDS_PHYS_NET_NAME" "P3E_CPU0_PE1_PCH_TXP<1>"
					( Origin gPackager )
				)
				( attribute "PNN" "P3E_CPU0_PE1_PCH_TXP<1>"
					( Origin gPackager )
				)
				( objectStatus "P3E_CPU0_PE1_PCH_TXP<1>" )
			)
			( signal "@baseboard_fab2_lib.baseboard_fab2(sch_1):p3e_cpu0_pe1_pch_txp(2)"
				( attribute "CDS_PHYS_NET_NAME" "P3E_CPU0_PE1_PCH_TXP<2>"
					( Origin gPackager )
				)
				( attribute "PNN" "P3E_CPU0_PE1_PCH_TXP<2>"
					( Origin gPackager )
				)
				( objectStatus "P3E_CPU0_PE1_PCH_TXP<2>" )
			)
			( signal "@baseboard_fab2_lib.baseboard_fab2(sch_1):p3e_cpu0_pe1_pch_txp(3)"
				( attribute "CDS_PHYS_NET_NAME" "P3E_CPU0_PE1_PCH_TXP<3>"
					( Origin gPackager )
				)
				( attribute "PNN" "P3E_CPU0_PE1_PCH_TXP<3>"
					( Origin gPackager )
				)
				( objectStatus "P3E_CPU0_PE1_PCH_TXP<3>" )
			)
			( signal "@baseboard_fab2_lib.baseboard_fab2(sch_1):p3e_cpu0_pe1_pch_txp(4)"
				( attribute "CDS_PHYS_NET_NAME" "P3E_CPU0_PE1_PCH_TXP<4>"
					( Origin gPackager )
				)
				( attribute "PNN" "P3E_CPU0_PE1_PCH_TXP<4>"
					( Origin gPackager )
				)
				( objectStatus "P3E_CPU0_PE1_PCH_TXP<4>" )
			)
			( signal "@baseboard_fab2_lib.baseboard_fab2(sch_1):p3e_cpu0_pe1_pch_txp(5)"
				( attribute "CDS_PHYS_NET_NAME" "P3E_CPU0_PE1_PCH_TXP<5>"
					( Origin gPackager )
				)
				( attribute "PNN" "P3E_CPU0_PE1_PCH_TXP<5>"
					( Origin gPackager )
				)
				( objectStatus "P3E_CPU0_PE1_PCH_TXP<5>" )
			)
			( signal "@baseboard_fab2_lib.baseboard_fab2(sch_1):p3e_cpu0_pe1_pch_txp(6)"
				( attribute "CDS_PHYS_NET_NAME" "P3E_CPU0_PE1_PCH_TXP<6>"
					( Origin gPackager )
				)
				( attribute "PNN" "P3E_CPU0_PE1_PCH_TXP<6>"
					( Origin gPackager )
				)
				( objectStatus "P3E_CPU0_PE1_PCH_TXP<6>" )
			)
			( signal "@baseboard_fab2_lib.baseboard_fab2(sch_1):p3e_cpu0_pe1_pch_txp(7)"
				( attribute "CDS_PHYS_NET_NAME" "P3E_CPU0_PE1_PCH_TXP<7>"
					( Origin gPackager )
				)
				( attribute "PNN" "P3E_CPU0_PE1_PCH_TXP<7>"
					( Origin gPackager )
				)
				( objectStatus "P3E_CPU0_PE1_PCH_TXP<7>" )
			)
			( signal "@baseboard_fab2_lib.baseboard_fab2(sch_1):p3e_cpu0_pe1_ss_c_txn(0)"
				( attribute "CDS_PHYS_NET_NAME" "P3E_CPU0_PE1_SS_C_TXN<0>"
					( Origin gPackager )
				)
				( attribute "PNN" "P3E_CPU0_PE1_SS_C_TXN<0>"
					( Origin gPackager )
				)
				( objectStatus "P3E_CPU0_PE1_SS_C_TXN<0>" )
			)
			( signal "@baseboard_fab2_lib.baseboard_fab2(sch_1):p3e_cpu0_pe1_ss_c_txn(1)"
				( attribute "CDS_PHYS_NET_NAME" "P3E_CPU0_PE1_SS_C_TXN<1>"
					( Origin gPackager )
				)
				( attribute "PNN" "P3E_CPU0_PE1_SS_C_TXN<1>"
					( Origin gPackager )
				)
				( objectStatus "P3E_CPU0_PE1_SS_C_TXN<1>" )
			)
			( signal "@baseboard_fab2_lib.baseboard_fab2(sch_1):p3e_cpu0_pe1_ss_c_txn(2)"
				( attribute "CDS_PHYS_NET_NAME" "P3E_CPU0_PE1_SS_C_TXN<2>"
					( Origin gPackager )
				)
				( attribute "PNN" "P3E_CPU0_PE1_SS_C_TXN<2>"
					( Origin gPackager )
				)
				( objectStatus "P3E_CPU0_PE1_SS_C_TXN<2>" )
			)
			( signal "@baseboard_fab2_lib.baseboard_fab2(sch_1):p3e_cpu0_pe1_ss_c_txn(3)"
				( attribute "CDS_PHYS_NET_NAME" "P3E_CPU0_PE1_SS_C_TXN<3>"
					( Origin gPackager )
				)
				( attribute "PNN" "P3E_CPU0_PE1_SS_C_TXN<3>"
					( Origin gPackager )
				)
				( objectStatus "P3E_CPU0_PE1_SS_C_TXN<3>" )
			)
			( signal "@baseboard_fab2_lib.baseboard_fab2(sch_1):p3e_cpu0_pe1_ss_c_txn(4)"
				( attribute "CDS_PHYS_NET_NAME" "P3E_CPU0_PE1_SS_C_TXN<4>"
					( Origin gPackager )
				)
				( attribute "PNN" "P3E_CPU0_PE1_SS_C_TXN<4>"
					( Origin gPackager )
				)
				( objectStatus "P3E_CPU0_PE1_SS_C_TXN<4>" )
			)
			( signal "@baseboard_fab2_lib.baseboard_fab2(sch_1):p3e_cpu0_pe1_ss_c_txn(5)"
				( attribute "CDS_PHYS_NET_NAME" "P3E_CPU0_PE1_SS_C_TXN<5>"
					( Origin gPackager )
				)
				( attribute "PNN" "P3E_CPU0_PE1_SS_C_TXN<5>"
					( Origin gPackager )
				)
				( objectStatus "P3E_CPU0_PE1_SS_C_TXN<5>" )
			)
			( signal "@baseboard_fab2_lib.baseboard_fab2(sch_1):p3e_cpu0_pe1_ss_c_txn(6)"
				( attribute "CDS_PHYS_NET_NAME" "P3E_CPU0_PE1_SS_C_TXN<6>"
					( Origin gPackager )
				)
				( attribute "PNN" "P3E_CPU0_PE1_SS_C_TXN<6>"
					( Origin gPackager )
				)
				( objectStatus "P3E_CPU0_PE1_SS_C_TXN<6>" )
			)
			( signal "@baseboard_fab2_lib.baseboard_fab2(sch_1):p3e_cpu0_pe1_ss_c_txn(7)"
				( attribute "CDS_PHYS_NET_NAME" "P3E_CPU0_PE1_SS_C_TXN<7>"
					( Origin gPackager )
				)
				( attribute "PNN" "P3E_CPU0_PE1_SS_C_TXN<7>"
					( Origin gPackager )
				)
				( objectStatus "P3E_CPU0_PE1_SS_C_TXN<7>" )
			)
			( signal "@baseboard_fab2_lib.baseboard_fab2(sch_1):p3e_cpu0_pe1_ss_c_txp(0)"
				( attribute "CDS_PHYS_NET_NAME" "P3E_CPU0_PE1_SS_C_TXP<0>"
					( Origin gPackager )
				)
				( attribute "PNN" "P3E_CPU0_PE1_SS_C_TXP<0>"
					( Origin gPackager )
				)
				( objectStatus "P3E_CPU0_PE1_SS_C_TXP<0>" )
			)
			( signal "@baseboard_fab2_lib.baseboard_fab2(sch_1):p3e_cpu0_pe1_ss_c_txp(1)"
				( attribute "CDS_PHYS_NET_NAME" "P3E_CPU0_PE1_SS_C_TXP<1>"
					( Origin gPackager )
				)
				( attribute "PNN" "P3E_CPU0_PE1_SS_C_TXP<1>"
					( Origin gPackager )
				)
				( objectStatus "P3E_CPU0_PE1_SS_C_TXP<1>" )
			)
			( signal "@baseboard_fab2_lib.baseboard_fab2(sch_1):p3e_cpu0_pe1_ss_c_txp(2)"
				( attribute "CDS_PHYS_NET_NAME" "P3E_CPU0_PE1_SS_C_TXP<2>"
					( Origin gPackager )
				)
				( attribute "PNN" "P3E_CPU0_PE1_SS_C_TXP<2>"
					( Origin gPackager )
				)
				( objectStatus "P3E_CPU0_PE1_SS_C_TXP<2>" )
			)
			( signal "@baseboard_fab2_lib.baseboard_fab2(sch_1):p3e_cpu0_pe1_ss_c_txp(3)"
				( attribute "CDS_PHYS_NET_NAME" "P3E_CPU0_PE1_SS_C_TXP<3>"
					( Origin gPackager )
				)
				( attribute "PNN" "P3E_CPU0_PE1_SS_C_TXP<3>"
					( Origin gPackager )
				)
				( objectStatus "P3E_CPU0_PE1_SS_C_TXP<3>" )
			)
			( signal "@baseboard_fab2_lib.baseboard_fab2(sch_1):p3e_cpu0_pe1_ss_c_txp(4)"
				( attribute "CDS_PHYS_NET_NAME" "P3E_CPU0_PE1_SS_C_TXP<4>"
					( Origin gPackager )
				)
				( attribute "PNN" "P3E_CPU0_PE1_SS_C_TXP<4>"
					( Origin gPackager )
				)
				( objectStatus "P3E_CPU0_PE1_SS_C_TXP<4>" )
			)
			( signal "@baseboard_fab2_lib.baseboard_fab2(sch_1):p3e_cpu0_pe1_ss_c_txp(5)"
				( attribute "CDS_PHYS_NET_NAME" "P3E_CPU0_PE1_SS_C_TXP<5>"
					( Origin gPackager )
				)
				( attribute "PNN" "P3E_CPU0_PE1_SS_C_TXP<5>"
					( Origin gPackager )
				)
				( objectStatus "P3E_CPU0_PE1_SS_C_TXP<5>" )
			)
			( signal "@baseboard_fab2_lib.baseboard_fab2(sch_1):p3e_cpu0_pe1_ss_c_txp(6)"
				( attribute "CDS_PHYS_NET_NAME" "P3E_CPU0_PE1_SS_C_TXP<6>"
					( Origin gPackager )
				)
				( attribute "PNN" "P3E_CPU0_PE1_SS_C_TXP<6>"
					( Origin gPackager )
				)
				( objectStatus "P3E_CPU0_PE1_SS_C_TXP<6>" )
			)
			( signal "@baseboard_fab2_lib.baseboard_fab2(sch_1):p3e_cpu0_pe1_ss_c_txp(7)"
				( attribute "CDS_PHYS_NET_NAME" "P3E_CPU0_PE1_SS_C_TXP<7>"
					( Origin gPackager )
				)
				( attribute "PNN" "P3E_CPU0_PE1_SS_C_TXP<7>"
					( Origin gPackager )
				)
				( objectStatus "P3E_CPU0_PE1_SS_C_TXP<7>" )
			)
			( signal "@baseboard_fab2_lib.baseboard_fab2(sch_1):p3e_cpu0_pe1_ss_r_rxn(0)"
				( attribute "CDS_PHYS_NET_NAME" "P3E_CPU0_PE1_SS_R_RXN<0>"
					( Origin gPackager )
				)
				( attribute "PNN" "P3E_CPU0_PE1_SS_R_RXN<0>"
					( Origin gPackager )
				)
				( objectStatus "P3E_CPU0_PE1_SS_R_RXN<0>" )
			)
			( signal "@baseboard_fab2_lib.baseboard_fab2(sch_1):p3e_cpu0_pe1_ss_r_rxn(1)"
				( attribute "CDS_PHYS_NET_NAME" "P3E_CPU0_PE1_SS_R_RXN<1>"
					( Origin gPackager )
				)
				( attribute "PNN" "P3E_CPU0_PE1_SS_R_RXN<1>"
					( Origin gPackager )
				)
				( objectStatus "P3E_CPU0_PE1_SS_R_RXN<1>" )
			)
			( signal "@baseboard_fab2_lib.baseboard_fab2(sch_1):p3e_cpu0_pe1_ss_r_rxn(2)"
				( attribute "CDS_PHYS_NET_NAME" "P3E_CPU0_PE1_SS_R_RXN<2>"
					( Origin gPackager )
				)
				( attribute "PNN" "P3E_CPU0_PE1_SS_R_RXN<2>"
					( Origin gPackager )
				)
				( objectStatus "P3E_CPU0_PE1_SS_R_RXN<2>" )
			)
			( signal "@baseboard_fab2_lib.baseboard_fab2(sch_1):p3e_cpu0_pe1_ss_r_rxn(3)"
				( attribute "CDS_PHYS_NET_NAME" "P3E_CPU0_PE1_SS_R_RXN<3>"
					( Origin gPackager )
				)
				( attribute "PNN" "P3E_CPU0_PE1_SS_R_RXN<3>"
					( Origin gPackager )
				)
				( objectStatus "P3E_CPU0_PE1_SS_R_RXN<3>" )
			)
			( signal "@baseboard_fab2_lib.baseboard_fab2(sch_1):p3e_cpu0_pe1_ss_r_rxn(4)"
				( attribute "CDS_PHYS_NET_NAME" "P3E_CPU0_PE1_SS_R_RXN<4>"
					( Origin gPackager )
				)
				( attribute "PNN" "P3E_CPU0_PE1_SS_R_RXN<4>"
					( Origin gPackager )
				)
				( objectStatus "P3E_CPU0_PE1_SS_R_RXN<4>" )
			)
			( signal "@baseboard_fab2_lib.baseboard_fab2(sch_1):p3e_cpu0_pe1_ss_r_rxn(5)"
				( attribute "CDS_PHYS_NET_NAME" "P3E_CPU0_PE1_SS_R_RXN<5>"
					( Origin gPackager )
				)
				( attribute "PNN" "P3E_CPU0_PE1_SS_R_RXN<5>"
					( Origin gPackager )
				)
				( objectStatus "P3E_CPU0_PE1_SS_R_RXN<5>" )
			)
			( signal "@baseboard_fab2_lib.baseboard_fab2(sch_1):p3e_cpu0_pe1_ss_r_rxn(6)"
				( attribute "CDS_PHYS_NET_NAME" "P3E_CPU0_PE1_SS_R_RXN<6>"
					( Origin gPackager )
				)
				( attribute "PNN" "P3E_CPU0_PE1_SS_R_RXN<6>"
					( Origin gPackager )
				)
				( objectStatus "P3E_CPU0_PE1_SS_R_RXN<6>" )
			)
			( signal "@baseboard_fab2_lib.baseboard_fab2(sch_1):p3e_cpu0_pe1_ss_r_rxn(7)"
				( attribute "CDS_PHYS_NET_NAME" "P3E_CPU0_PE1_SS_R_RXN<7>"
					( Origin gPackager )
				)
				( attribute "PNN" "P3E_CPU0_PE1_SS_R_RXN<7>"
					( Origin gPackager )
				)
				( objectStatus "P3E_CPU0_PE1_SS_R_RXN<7>" )
			)
			( signal "@baseboard_fab2_lib.baseboard_fab2(sch_1):p3e_cpu0_pe1_ss_r_rxp(0)"
				( attribute "CDS_PHYS_NET_NAME" "P3E_CPU0_PE1_SS_R_RXP<0>"
					( Origin gPackager )
				)
				( attribute "PNN" "P3E_CPU0_PE1_SS_R_RXP<0>"
					( Origin gPackager )
				)
				( objectStatus "P3E_CPU0_PE1_SS_R_RXP<0>" )
			)
			( signal "@baseboard_fab2_lib.baseboard_fab2(sch_1):p3e_cpu0_pe1_ss_r_rxp(1)"
				( attribute "CDS_PHYS_NET_NAME" "P3E_CPU0_PE1_SS_R_RXP<1>"
					( Origin gPackager )
				)
				( attribute "PNN" "P3E_CPU0_PE1_SS_R_RXP<1>"
					( Origin gPackager )
				)
				( objectStatus "P3E_CPU0_PE1_SS_R_RXP<1>" )
			)
			( signal "@baseboard_fab2_lib.baseboard_fab2(sch_1):p3e_cpu0_pe1_ss_r_rxp(2)"
				( attribute "CDS_PHYS_NET_NAME" "P3E_CPU0_PE1_SS_R_RXP<2>"
					( Origin gPackager )
				)
				( attribute "PNN" "P3E_CPU0_PE1_SS_R_RXP<2>"
					( Origin gPackager )
				)
				( objectStatus "P3E_CPU0_PE1_SS_R_RXP<2>" )
			)
			( signal "@baseboard_fab2_lib.baseboard_fab2(sch_1):p3e_cpu0_pe1_ss_r_rxp(3)"
				( attribute "CDS_PHYS_NET_NAME" "P3E_CPU0_PE1_SS_R_RXP<3>"
					( Origin gPackager )
				)
				( attribute "PNN" "P3E_CPU0_PE1_SS_R_RXP<3>"
					( Origin gPackager )
				)
				( objectStatus "P3E_CPU0_PE1_SS_R_RXP<3>" )
			)
			( signal "@baseboard_fab2_lib.baseboard_fab2(sch_1):p3e_cpu0_pe1_ss_r_rxp(4)"
				( attribute "CDS_PHYS_NET_NAME" "P3E_CPU0_PE1_SS_R_RXP<4>"
					( Origin gPackager )
				)
				( attribute "PNN" "P3E_CPU0_PE1_SS_R_RXP<4>"
					( Origin gPackager )
				)
				( objectStatus "P3E_CPU0_PE1_SS_R_RXP<4>" )
			)
			( signal "@baseboard_fab2_lib.baseboard_fab2(sch_1):p3e_cpu0_pe1_ss_r_rxp(5)"
				( attribute "CDS_PHYS_NET_NAME" "P3E_CPU0_PE1_SS_R_RXP<5>"
					( Origin gPackager )
				)
				( attribute "PNN" "P3E_CPU0_PE1_SS_R_RXP<5>"
					( Origin gPackager )
				)
				( objectStatus "P3E_CPU0_PE1_SS_R_RXP<5>" )
			)
			( signal "@baseboard_fab2_lib.baseboard_fab2(sch_1):p3e_cpu0_pe1_ss_r_rxp(6)"
				( attribute "CDS_PHYS_NET_NAME" "P3E_CPU0_PE1_SS_R_RXP<6>"
					( Origin gPackager )
				)
				( attribute "PNN" "P3E_CPU0_PE1_SS_R_RXP<6>"
					( Origin gPackager )
				)
				( objectStatus "P3E_CPU0_PE1_SS_R_RXP<6>" )
			)
			( signal "@baseboard_fab2_lib.baseboard_fab2(sch_1):p3e_cpu0_pe1_ss_r_rxp(7)"
				( attribute "CDS_PHYS_NET_NAME" "P3E_CPU0_PE1_SS_R_RXP<7>"
					( Origin gPackager )
				)
				( attribute "PNN" "P3E_CPU0_PE1_SS_R_RXP<7>"
					( Origin gPackager )
				)
				( objectStatus "P3E_CPU0_PE1_SS_R_RXP<7>" )
			)
			( signal "@baseboard_fab2_lib.baseboard_fab2(sch_1):clk_100m_pch_slotx24_s0_dn"
				( attribute "CDS_PHYS_NET_NAME" "CLK_100M_PCH_SLOTX24_S0_DN"
					( Origin gPackager )
				)
				( objectStatus "CLK_100M_PCH_SLOTX24_S0_DN" )
			)
			( signal "@baseboard_fab2_lib.baseboard_fab2(sch_1):clk_100m_pch_slotx24_s0_dp"
				( attribute "CDS_PHYS_NET_NAME" "CLK_100M_PCH_SLOTX24_S0_DP"
					( Origin gPackager )
				)
				( objectStatus "CLK_100M_PCH_SLOTX24_S0_DP" )
			)
			( signal "@baseboard_fab2_lib.baseboard_fab2(sch_1):clk_100m_pch_slotx24_s1_dn"
				( attribute "CDS_PHYS_NET_NAME" "CLK_100M_PCH_SLOTX24_S1_DN"
					( Origin gPackager )
				)
				( objectStatus "CLK_100M_PCH_SLOTX24_S1_DN" )
			)
			( signal "@baseboard_fab2_lib.baseboard_fab2(sch_1):clk_100m_pch_slotx24_s1_dp"
				( attribute "CDS_PHYS_NET_NAME" "CLK_100M_PCH_SLOTX24_S1_DP"
					( Origin gPackager )
				)
				( objectStatus "CLK_100M_PCH_SLOTX24_S1_DP" )
			)
			( signal "@baseboard_fab2_lib.baseboard_fab2(sch_1):clk_100m_pch_slotx24_s2_dn"
				( attribute "CDS_PHYS_NET_NAME" "CLK_100M_PCH_SLOTX24_S2_DN"
					( Origin gPackager )
				)
				( objectStatus "CLK_100M_PCH_SLOTX24_S2_DN" )
			)
			( signal "@baseboard_fab2_lib.baseboard_fab2(sch_1):clk_100m_pch_slotx24_s2_dp"
				( attribute "CDS_PHYS_NET_NAME" "CLK_100M_PCH_SLOTX24_S2_DP"
					( Origin gPackager )
				)
				( objectStatus "CLK_100M_PCH_SLOTX24_S2_DP" )
			)
			( signal "@baseboard_fab2_lib.baseboard_fab2(sch_1):clk_100m_pch_slotx24_s3_dn"
				( attribute "CDS_PHYS_NET_NAME" "CLK_100M_PCH_SLOTX24_S3_DN"
					( Origin gPackager )
				)
				( objectStatus "CLK_100M_PCH_SLOTX24_S3_DN" )
			)
			( signal "@baseboard_fab2_lib.baseboard_fab2(sch_1):clk_100m_pch_slotx24_s3_dp"
				( attribute "CDS_PHYS_NET_NAME" "CLK_100M_PCH_SLOTX24_S3_DP"
					( Origin gPackager )
				)
				( objectStatus "CLK_100M_PCH_SLOTX24_S3_DP" )
			)
			( signal "@baseboard_fab2_lib.baseboard_fab2(sch_1):clk_100m_pch_slotx24_s4_dn"
				( attribute "CDS_PHYS_NET_NAME" "CLK_100M_PCH_SLOTX24_S4_DN"
					( Origin gPackager )
				)
				( objectStatus "CLK_100M_PCH_SLOTX24_S4_DN" )
			)
			( signal "@baseboard_fab2_lib.baseboard_fab2(sch_1):clk_100m_pch_slotx24_s4_dp"
				( attribute "CDS_PHYS_NET_NAME" "CLK_100M_PCH_SLOTX24_S4_DP"
					( Origin gPackager )
				)
				( objectStatus "CLK_100M_PCH_SLOTX24_S4_DP" )
			)
			( signal "@baseboard_fab2_lib.baseboard_fab2(sch_1):clk_100m_pch_slotx24_s5_dn"
				( attribute "CDS_PHYS_NET_NAME" "CLK_100M_PCH_SLOTX24_S5_DN"
					( Origin gPackager )
				)
				( objectStatus "CLK_100M_PCH_SLOTX24_S5_DN" )
			)
			( signal "@baseboard_fab2_lib.baseboard_fab2(sch_1):clk_100m_pch_slotx24_s5_dp"
				( attribute "CDS_PHYS_NET_NAME" "CLK_100M_PCH_SLOTX24_S5_DP"
					( Origin gPackager )
				)
				( objectStatus "CLK_100M_PCH_SLOTX24_S5_DP" )
			)
			( signal "@baseboard_fab2_lib.baseboard_fab2(sch_1):fm_pe_slotx24_wake_n"
				( attribute "CDS_PHYS_NET_NAME" "FM_PE_SLOTX24_WAKE_N"
					( Origin gPackager )
				)
				( objectStatus "FM_PE_SLOTX24_WAKE_N" )
			)
			( signal "@baseboard_fab2_lib.baseboard_fab2(sch_1):fm_prsnt_2_1_n"
				( attribute "CDS_PHYS_NET_NAME" "FM_PRSNT_2_1_N"
					( Origin gPackager )
				)
				( objectStatus "FM_PRSNT_2_1_N" )
			)
			( signal "@baseboard_fab2_lib.baseboard_fab2(sch_1):fm_prsnt_2_2_n"
				( attribute "CDS_PHYS_NET_NAME" "FM_PRSNT_2_2_N"
					( Origin gPackager )
				)
				( objectStatus "FM_PRSNT_2_2_N" )
			)
			( signal "@baseboard_fab2_lib.baseboard_fab2(sch_1):fm_prsnt_2_3_n"
				( attribute "CDS_PHYS_NET_NAME" "FM_PRSNT_2_3_N"
					( Origin gPackager )
				)
				( objectStatus "FM_PRSNT_2_3_N" )
			)
			( signal "@baseboard_fab2_lib.baseboard_fab2(sch_1):fm_prsnt_2_4_n"
				( attribute "CDS_PHYS_NET_NAME" "FM_PRSNT_2_4_N"
					( Origin gPackager )
				)
				( objectStatus "FM_PRSNT_2_4_N" )
			)
			( signal "@baseboard_fab2_lib.baseboard_fab2(sch_1):fm_prsnt_2_5_n"
				( attribute "CDS_PHYS_NET_NAME" "FM_PRSNT_2_5_N"
					( Origin gPackager )
				)
				( objectStatus "FM_PRSNT_2_5_N" )
			)
			( signal "@baseboard_fab2_lib.baseboard_fab2(sch_1):fm_pwrbrk_slot_n"
				( attribute "CDS_PHYS_NET_NAME" "FM_PWRBRK_SLOT_N"
					( Origin gPackager )
				)
				( objectStatus "FM_PWRBRK_SLOT_N" )
			)
			( signal "@baseboard_fab2_lib.baseboard_fab2(sch_1):fm_slt_cfg0"
				( attribute "CDS_PHYS_NET_NAME" "FM_SLT_CFG0"
					( Origin gPackager )
				)
				( objectStatus "FM_SLT_CFG0" )
			)
			( signal "@baseboard_fab2_lib.baseboard_fab2(sch_1):fm_slt_cfg1"
				( attribute "CDS_PHYS_NET_NAME" "FM_SLT_CFG1"
					( Origin gPackager )
				)
				( objectStatus "FM_SLT_CFG1" )
			)
			( signal "@baseboard_fab2_lib.baseboard_fab2(sch_1):irq_oob_mgmt_riser_alert_n"
				( attribute "CDS_PHYS_NET_NAME" "IRQ_OOB_MGMT_RISER_ALERT_N"
					( Origin gPackager )
				)
				( attribute "PHYS_NET_NAME" "IRQ_OOB_MGMT_RISER_ALERT_N"
					( Origin gPackager )
				)
				( objectStatus "IRQ_OOB_MGMT_RISER_ALERT_N" )
			)
			( signal "@baseboard_fab2_lib.baseboard_fab2(sch_1):p12v"
				( alias ( signalRef "@baseboard_fab2_lib.baseboard_fab2(sch_1):page108_p12v") )
				( alias ( signalRef "@baseboard_fab2_lib.baseboard_fab2(sch_1):page172_p12v") )
				( alias ( signalRef "@baseboard_fab2_lib.baseboard_fab2(sch_1):page196_p12v") )
				( alias ( signalRef "@baseboard_fab2_lib.baseboard_fab2(sch_1):page198_p12v") )
				( attribute "VOLTAGE" "+12."
					( Units "uVoltage" "V" 1.000000)
					( Status sAliasFlattened )
					( Status sAliasConflict )
					( Origin gFrontEnd )
				)
				( attribute "CDS_PHYS_NET_NAME" "P12V"
					( Origin gPackager )
				)
				( objectStatus "P12V" )
			)
			( signal "@baseboard_fab2_lib.baseboard_fab2(sch_1):page108_p12v"
				( attribute "VOLTAGE" "+12."
					( Units "uVoltage" "V" 1.000000)
					( Origin gFrontEnd )
				)
				( objectFlag fObjectAlias )
				( objectStatus "page108_p12v" )
			)
			( signal "@baseboard_fab2_lib.baseboard_fab2(sch_1):page172_p12v"
				( attribute "VOLTAGE" "12.0V"
					( Units "uVoltage" "V" 1.000000)
					( Origin gFrontEnd )
				)
				( objectFlag fObjectAlias )
				( objectStatus "page172_p12v" )
			)
			( signal "@baseboard_fab2_lib.baseboard_fab2(sch_1):page196_p12v"
				( attribute "VOLTAGE" "12.0V"
					( Units "uVoltage" "V" 1.000000)
					( Origin gFrontEnd )
				)
				( objectFlag fObjectAlias )
				( objectStatus "page196_p12v" )
			)
			( signal "@baseboard_fab2_lib.baseboard_fab2(sch_1):page198_p12v"
				( attribute "VOLTAGE" "+12.0V"
					( Units "uVoltage" "V" 1.000000)
					( Origin gFrontEnd )
				)
				( objectFlag fObjectAlias )
				( objectStatus "page198_p12v" )
			)
			( signal "@baseboard_fab2_lib.baseboard_fab2(sch_1):rst_pcie_riser1_perst_n"
				( attribute "CDS_PHYS_NET_NAME" "RST_PCIE_RISER1_PERST_N"
					( Origin gPackager )
				)
				( objectStatus "RST_PCIE_RISER1_PERST_N" )
			)
			( signal "@baseboard_fab2_lib.baseboard_fab2(sch_1):rst_pcie_riser1_perst_r_n"
				( attribute "CDS_PHYS_NET_NAME" "RST_PCIE_RISER1_PERST_R_N"
					( Origin gPackager )
				)
				( objectStatus "RST_PCIE_RISER1_PERST_R_N" )
			)
			( signal "@baseboard_fab2_lib.baseboard_fab2(sch_1):smb_slotx24_bmc_stby_lvc3_scl"
				( attribute "CDS_PHYS_NET_NAME" "SMB_SLOTX24_BMC_STBY_LVC3_SCL"
					( Origin gPackager )
				)
				( objectStatus "SMB_SLOTX24_BMC_STBY_LVC3_SCL" )
			)
			( signal "@baseboard_fab2_lib.baseboard_fab2(sch_1):smb_slotx24_bmc_stby_lvc3_sda"
				( attribute "CDS_PHYS_NET_NAME" "SMB_SLOTX24_BMC_STBY_LVC3_SDA"
					( Origin gPackager )
				)
				( objectStatus "SMB_SLOTX24_BMC_STBY_LVC3_SDA" )
			)
			( signal "@baseboard_fab2_lib.baseboard_fab2(sch_1):smb_slotx24_pch_stby_lvc3_scl"
				( attribute "CDS_PHYS_NET_NAME" "SMB_SLOTX24_PCH_STBY_LVC3_SCL"
					( Origin gPackager )
				)
				( objectStatus "SMB_SLOTX24_PCH_STBY_LVC3_SCL" )
			)
			( signal "@baseboard_fab2_lib.baseboard_fab2(sch_1):smb_slotx24_pch_stby_lvc3_sda"
				( attribute "CDS_PHYS_NET_NAME" "SMB_SLOTX24_PCH_STBY_LVC3_SDA"
					( Origin gPackager )
				)
				( objectStatus "SMB_SLOTX24_PCH_STBY_LVC3_SDA" )
			)
			( signal "@baseboard_fab2_lib.baseboard_fab2(sch_1):smb_slotx24_stby_lvc3_scl_r2"
				( attribute "CDS_PHYS_NET_NAME" "SMB_SLOTX24_STBY_LVC3_SCL_R2"
					( Origin gPackager )
				)
				( objectStatus "SMB_SLOTX24_STBY_LVC3_SCL_R2" )
			)
			( signal "@baseboard_fab2_lib.baseboard_fab2(sch_1):smb_slotx24_stby_lvc3_sda_r2"
				( attribute "CDS_PHYS_NET_NAME" "SMB_SLOTX24_STBY_LVC3_SDA_R2"
					( Origin gPackager )
				)
				( objectStatus "SMB_SLOTX24_STBY_LVC3_SDA_R2" )
			)
			( signal "@baseboard_fab2_lib.baseboard_fab2(sch_1):fm_prsnt_2_6_n"
				( attribute "CDS_PHYS_NET_NAME" "FM_PRSNT_2_6_N"
					( Origin gPackager )
				)
				( objectStatus "FM_PRSNT_2_6_N" )
			)
			( signal "@baseboard_fab2_lib.baseboard_fab2(sch_1):rcc_dfx_1940_1"
				( attribute "CDS_PHYS_NET_NAME" "RCC_DFX_1940_1"
					( Origin gPackager )
				)
				( objectStatus "RCC_DFX_1940_1" )
			)
			( signal "@baseboard_fab2_lib.baseboard_fab2(sch_1):rcc_dfx_1940_2"
				( attribute "CDS_PHYS_NET_NAME" "RCC_DFX_1940_2"
					( Origin gPackager )
				)
				( objectStatus "RCC_DFX_1940_2" )
			)
			( signal "@baseboard_fab2_lib.baseboard_fab2(sch_1):rcc_dfx_1940_3"
				( attribute "CDS_PHYS_NET_NAME" "RCC_DFX_1940_3"
					( Origin gPackager )
				)
				( objectStatus "RCC_DFX_1940_3" )
			)
			( signal "@baseboard_fab2_lib.baseboard_fab2(sch_1):rcc_dfx_1940_4"
				( attribute "CDS_PHYS_NET_NAME" "RCC_DFX_1940_4"
					( Origin gPackager )
				)
				( objectStatus "RCC_DFX_1940_4" )
			)
			( signal "@baseboard_fab2_lib.baseboard_fab2(sch_1):clk_100m_pch_xdp_dn"
				( attribute "CDS_PHYS_NET_NAME" "CLK_100M_PCH_XDP_DN"
					( Origin gPackager )
				)
				( objectStatus "CLK_100M_PCH_XDP_DN" )
			)
			( signal "@baseboard_fab2_lib.baseboard_fab2(sch_1):clk_100m_pch_xdp_dp"
				( attribute "CDS_PHYS_NET_NAME" "CLK_100M_PCH_XDP_DP"
					( Origin gPackager )
				)
				( objectStatus "CLK_100M_PCH_XDP_DP" )
			)
			( signal "@baseboard_fab2_lib.baseboard_fab2(sch_1):fm_debug_rst_btn_n"
				( attribute "CDS_PHYS_NET_NAME" "FM_DEBUG_RST_BTN_N"
					( Origin gPackager )
				)
				( objectStatus "FM_DEBUG_RST_BTN_N" )
			)
			( signal "@baseboard_fab2_lib.baseboard_fab2(sch_1):fm_debug_rst_btn_r1_n"
				( attribute "CDS_PHYS_NET_NAME" "FM_DEBUG_RST_BTN_R1_N"
					( Origin gPackager )
				)
				( objectStatus "FM_DEBUG_RST_BTN_R1_N" )
			)
			( signal "@baseboard_fab2_lib.baseboard_fab2(sch_1):p1v05_pch_stby"
				( alias ( signalRef "@baseboard_fab2_lib.baseboard_fab2(sch_1):page111_p1v05_pch_stby") )
				( alias ( signalRef "@baseboard_fab2_lib.baseboard_fab2(sch_1):page112_p1v05_pch_stby") )
				( alias ( signalRef "@baseboard_fab2_lib.baseboard_fab2(sch_1):page122_p1v05_pch_stby") )
				( alias ( signalRef "@baseboard_fab2_lib.baseboard_fab2(sch_1):page123_p1v05_pch_stby") )
				( alias ( signalRef "@baseboard_fab2_lib.baseboard_fab2(sch_1):page127_p1v05_pch_stby") )
				( alias ( signalRef "@baseboard_fab2_lib.baseboard_fab2(sch_1):page131_p1v05_pch_stby") )
				( alias ( signalRef "@baseboard_fab2_lib.baseboard_fab2(sch_1):page133_p1v05_pch_stby") )
				( alias ( signalRef "@baseboard_fab2_lib.baseboard_fab2(sch_1):page134_p1v05_pch_stby") )
				( alias ( signalRef "@baseboard_fab2_lib.baseboard_fab2(sch_1):page169_p1v05_pch_stby") )
				( alias ( signalRef "@baseboard_fab2_lib.baseboard_fab2(sch_1):page236_p1v05_pch_stby") )
				( attribute "VOLTAGE" "1.05V"
					( Units "uVoltage" "V" 1.000000)
					( Status sAliasFlattened )
					( Origin gFrontEnd )
				)
				( attribute "CDS_PHYS_NET_NAME" "P1V05_PCH_STBY"
					( Origin gPackager )
				)
				( objectStatus "P1V05_PCH_STBY" )
			)
			( signal "@baseboard_fab2_lib.baseboard_fab2(sch_1):page111_p1v05_pch_stby"
				( attribute "VOLTAGE" "1.05V"
					( Units "uVoltage" "V" 1.000000)
					( Origin gFrontEnd )
				)
				( objectFlag fObjectAlias )
				( objectStatus "page111_p1v05_pch_stby" )
			)
			( signal "@baseboard_fab2_lib.baseboard_fab2(sch_1):page112_p1v05_pch_stby"
				( attribute "VOLTAGE" "1.05V"
					( Units "uVoltage" "V" 1.000000)
					( Origin gFrontEnd )
				)
				( objectFlag fObjectAlias )
				( objectStatus "page112_p1v05_pch_stby" )
			)
			( signal "@baseboard_fab2_lib.baseboard_fab2(sch_1):page122_p1v05_pch_stby"
				( attribute "VOLTAGE" "1.05V"
					( Units "uVoltage" "V" 1.000000)
					( Origin gFrontEnd )
				)
				( objectFlag fObjectAlias )
				( objectStatus "page122_p1v05_pch_stby" )
			)
			( signal "@baseboard_fab2_lib.baseboard_fab2(sch_1):page123_p1v05_pch_stby"
				( attribute "VOLTAGE" "1.05V"
					( Units "uVoltage" "V" 1.000000)
					( Origin gFrontEnd )
				)
				( objectFlag fObjectAlias )
				( objectStatus "page123_p1v05_pch_stby" )
			)
			( signal "@baseboard_fab2_lib.baseboard_fab2(sch_1):page127_p1v05_pch_stby"
				( attribute "VOLTAGE" "1.05V"
					( Units "uVoltage" "V" 1.000000)
					( Origin gFrontEnd )
				)
				( objectFlag fObjectAlias )
				( objectStatus "page127_p1v05_pch_stby" )
			)
			( signal "@baseboard_fab2_lib.baseboard_fab2(sch_1):page131_p1v05_pch_stby"
				( attribute "VOLTAGE" "1.05V"
					( Units "uVoltage" "V" 1.000000)
					( Origin gFrontEnd )
				)
				( objectFlag fObjectAlias )
				( objectStatus "page131_p1v05_pch_stby" )
			)
			( signal "@baseboard_fab2_lib.baseboard_fab2(sch_1):page133_p1v05_pch_stby"
				( attribute "VOLTAGE" "1.05V"
					( Units "uVoltage" "V" 1.000000)
					( Origin gFrontEnd )
				)
				( objectFlag fObjectAlias )
				( objectStatus "page133_p1v05_pch_stby" )
			)
			( signal "@baseboard_fab2_lib.baseboard_fab2(sch_1):page134_p1v05_pch_stby"
				( attribute "VOLTAGE" "1.05V"
					( Units "uVoltage" "V" 1.000000)
					( Origin gFrontEnd )
				)
				( objectFlag fObjectAlias )
				( objectStatus "page134_p1v05_pch_stby" )
			)
			( signal "@baseboard_fab2_lib.baseboard_fab2(sch_1):page169_p1v05_pch_stby"
				( attribute "VOLTAGE" "1.05V"
					( Units "uVoltage" "V" 1.000000)
					( Origin gFrontEnd )
				)
				( objectFlag fObjectAlias )
				( objectStatus "page169_p1v05_pch_stby" )
			)
			( signal "@baseboard_fab2_lib.baseboard_fab2(sch_1):page236_p1v05_pch_stby"
				( attribute "VOLTAGE" "1.05V"
					( Units "uVoltage" "V" 1.000000)
					( Origin gFrontEnd )
				)
				( objectFlag fObjectAlias )
				( objectStatus "page236_p1v05_pch_stby" )
			)
			( signal "@baseboard_fab2_lib.baseboard_fab2(sch_1):rst_rsmrst_n"
				( attribute "CDS_PHYS_NET_NAME" "RST_RSMRST_N"
					( Origin gPackager )
				)
				( objectStatus "RST_RSMRST_N" )
			)
			( signal "@baseboard_fab2_lib.baseboard_fab2(sch_1):spi_pch_io2"
				( attribute "CDS_PHYS_NET_NAME" "SPI_PCH_IO2"
					( Origin gPackager )
				)
				( objectStatus "SPI_PCH_IO2" )
			)
			( signal "@baseboard_fab2_lib.baseboard_fab2(sch_1):spi_pch_mosi"
				( attribute "CDS_PHYS_NET_NAME" "SPI_PCH_MOSI"
					( Origin gPackager )
				)
				( objectStatus "SPI_PCH_MOSI" )
			)
			( signal "@baseboard_fab2_lib.baseboard_fab2(sch_1):tp_xdp_cpu_obsdata_c0"
				( attribute "CDS_PHYS_NET_NAME" "TP_XDP_CPU_OBSDATA_C0"
					( Origin gPackager )
				)
				( objectStatus "TP_XDP_CPU_OBSDATA_C0" )
			)
			( signal "@baseboard_fab2_lib.baseboard_fab2(sch_1):tp_xdp_cpu_obsdata_c1"
				( attribute "CDS_PHYS_NET_NAME" "TP_XDP_CPU_OBSDATA_C1"
					( Origin gPackager )
				)
				( objectStatus "TP_XDP_CPU_OBSDATA_C1" )
			)
			( signal "@baseboard_fab2_lib.baseboard_fab2(sch_1):tp_xdp_cpu_obsdata_c2"
				( attribute "CDS_PHYS_NET_NAME" "TP_XDP_CPU_OBSDATA_C2"
					( Origin gPackager )
				)
				( objectStatus "TP_XDP_CPU_OBSDATA_C2" )
			)
			( signal "@baseboard_fab2_lib.baseboard_fab2(sch_1):tp_xdp_cpu_obsdata_c3"
				( attribute "CDS_PHYS_NET_NAME" "TP_XDP_CPU_OBSDATA_C3"
					( Origin gPackager )
				)
				( objectStatus "TP_XDP_CPU_OBSDATA_C3" )
			)
			( signal "@baseboard_fab2_lib.baseboard_fab2(sch_1):tp_xdp_cpu_obsdata_d0"
				( attribute "CDS_PHYS_NET_NAME" "TP_XDP_CPU_OBSDATA_D0"
					( Origin gPackager )
				)
				( objectStatus "TP_XDP_CPU_OBSDATA_D0" )
			)
			( signal "@baseboard_fab2_lib.baseboard_fab2(sch_1):tp_xdp_cpu_obsdata_d1"
				( attribute "CDS_PHYS_NET_NAME" "TP_XDP_CPU_OBSDATA_D1"
					( Origin gPackager )
				)
				( objectStatus "TP_XDP_CPU_OBSDATA_D1" )
			)
			( signal "@baseboard_fab2_lib.baseboard_fab2(sch_1):tp_xdp_cpu_obsdata_d2"
				( attribute "CDS_PHYS_NET_NAME" "TP_XDP_CPU_OBSDATA_D2"
					( Origin gPackager )
				)
				( objectStatus "TP_XDP_CPU_OBSDATA_D2" )
			)
			( signal "@baseboard_fab2_lib.baseboard_fab2(sch_1):tp_xdp_cpu_obsdata_d3"
				( attribute "CDS_PHYS_NET_NAME" "TP_XDP_CPU_OBSDATA_D3"
					( Origin gPackager )
				)
				( objectStatus "TP_XDP_CPU_OBSDATA_D3" )
			)
			( signal "@baseboard_fab2_lib.baseboard_fab2(sch_1):tp_xdp_cpu_obsfn_c0"
				( attribute "CDS_PHYS_NET_NAME" "TP_XDP_CPU_OBSFN_C0"
					( Origin gPackager )
				)
				( objectStatus "TP_XDP_CPU_OBSFN_C0" )
			)
			( signal "@baseboard_fab2_lib.baseboard_fab2(sch_1):tp_xdp_obsdata_a0"
				( attribute "CDS_PHYS_NET_NAME" "TP_XDP_OBSDATA_A0"
					( Origin gPackager )
				)
				( objectStatus "TP_XDP_OBSDATA_A0" )
			)
			( signal "@baseboard_fab2_lib.baseboard_fab2(sch_1):tp_xdp_obsdata_a1"
				( attribute "CDS_PHYS_NET_NAME" "TP_XDP_OBSDATA_A1"
					( Origin gPackager )
				)
				( objectStatus "TP_XDP_OBSDATA_A1" )
			)
			( signal "@baseboard_fab2_lib.baseboard_fab2(sch_1):tp_xdp_obsdata_a2"
				( attribute "CDS_PHYS_NET_NAME" "TP_XDP_OBSDATA_A2"
					( Origin gPackager )
				)
				( objectStatus "TP_XDP_OBSDATA_A2" )
			)
			( signal "@baseboard_fab2_lib.baseboard_fab2(sch_1):tp_xdp_obsdata_a3"
				( attribute "CDS_PHYS_NET_NAME" "TP_XDP_OBSDATA_A3"
					( Origin gPackager )
				)
				( objectStatus "TP_XDP_OBSDATA_A3" )
			)
			( signal "@baseboard_fab2_lib.baseboard_fab2(sch_1):tp_xdp_obsdata_b0"
				( attribute "CDS_PHYS_NET_NAME" "TP_XDP_OBSDATA_B0"
					( Origin gPackager )
				)
				( objectStatus "TP_XDP_OBSDATA_B0" )
			)
			( signal "@baseboard_fab2_lib.baseboard_fab2(sch_1):tp_xdp_obsdata_b1"
				( attribute "CDS_PHYS_NET_NAME" "TP_XDP_OBSDATA_B1"
					( Origin gPackager )
				)
				( objectStatus "TP_XDP_OBSDATA_B1" )
			)
			( signal "@baseboard_fab2_lib.baseboard_fab2(sch_1):tp_xdp_obsdata_b2"
				( attribute "CDS_PHYS_NET_NAME" "TP_XDP_OBSDATA_B2"
					( Origin gPackager )
				)
				( objectStatus "TP_XDP_OBSDATA_B2" )
			)
			( signal "@baseboard_fab2_lib.baseboard_fab2(sch_1):tp_xdp_obsdata_b3"
				( attribute "CDS_PHYS_NET_NAME" "TP_XDP_OBSDATA_B3"
					( Origin gPackager )
				)
				( objectStatus "TP_XDP_OBSDATA_B3" )
			)
			( signal "@baseboard_fab2_lib.baseboard_fab2(sch_1):tp_xdp_obsfn_b0"
				( attribute "CDS_PHYS_NET_NAME" "TP_XDP_OBSFN_B0"
					( Origin gPackager )
				)
				( objectStatus "TP_XDP_OBSFN_B0" )
			)
			( signal "@baseboard_fab2_lib.baseboard_fab2(sch_1):tp_xdp_obsfn_b1"
				( attribute "CDS_PHYS_NET_NAME" "TP_XDP_OBSFN_B1"
					( Origin gPackager )
				)
				( objectStatus "TP_XDP_OBSFN_B1" )
			)
			( signal "@baseboard_fab2_lib.baseboard_fab2(sch_1):xdp_cpu_gtl_tck_r2"
				( attribute "CDS_PHYS_NET_NAME" "XDP_CPU_GTL_TCK_R2"
					( Origin gPackager )
				)
				( objectStatus "XDP_CPU_GTL_TCK_R2" )
			)
			( signal "@baseboard_fab2_lib.baseboard_fab2(sch_1):xdp_cpu_tck_buf"
				( attribute "CDS_PHYS_NET_NAME" "XDP_CPU_TCK_BUF"
					( Origin gPackager )
				)
				( objectStatus "XDP_CPU_TCK_BUF" )
			)
			( signal "@baseboard_fab2_lib.baseboard_fab2(sch_1):xdp_debug_consent_n"
				( attribute "CDS_PHYS_NET_NAME" "XDP_DEBUG_CONSENT_N"
					( Origin gPackager )
				)
				( objectStatus "XDP_DEBUG_CONSENT_N" )
			)
			( signal "@baseboard_fab2_lib.baseboard_fab2(sch_1):xdp_itp_pmode"
				( attribute "CDS_PHYS_NET_NAME" "XDP_ITP_PMODE"
					( Origin gPackager )
				)
				( objectStatus "XDP_ITP_PMODE" )
			)
			( signal "@baseboard_fab2_lib.baseboard_fab2(sch_1):xdp_obsfn_b0_mbp6_n"
				( attribute "CDS_PHYS_NET_NAME" "XDP_OBSFN_B0_MBP6_N"
					( Origin gPackager )
				)
				( objectStatus "XDP_OBSFN_B0_MBP6_N" )
			)
			( signal "@baseboard_fab2_lib.baseboard_fab2(sch_1):xdp_obsfn_b1_mbp7_n"
				( attribute "CDS_PHYS_NET_NAME" "XDP_OBSFN_B1_MBP7_N"
					( Origin gPackager )
				)
				( objectStatus "XDP_OBSFN_B1_MBP7_N" )
			)
			( signal "@baseboard_fab2_lib.baseboard_fab2(sch_1):xdp_pch_cpu_tck0"
				( attribute "CDS_PHYS_NET_NAME" "XDP_PCH_CPU_TCK0"
					( Origin gPackager )
				)
				( objectStatus "XDP_PCH_CPU_TCK0" )
			)
			( signal "@baseboard_fab2_lib.baseboard_fab2(sch_1):xdp_pch_tck1"
				( attribute "CDS_PHYS_NET_NAME" "XDP_PCH_TCK1"
					( Origin gPackager )
				)
				( objectStatus "XDP_PCH_TCK1" )
			)
			( signal "@baseboard_fab2_lib.baseboard_fab2(sch_1):xdp_prdy_n"
				( attribute "CDS_PHYS_NET_NAME" "XDP_PRDY_N"
					( Origin gPackager )
				)
				( objectStatus "XDP_PRDY_N" )
			)
			( signal "@baseboard_fab2_lib.baseboard_fab2(sch_1):xdp_preq_n"
				( attribute "CDS_PHYS_NET_NAME" "XDP_PREQ_N"
					( Origin gPackager )
				)
				( objectStatus "XDP_PREQ_N" )
			)
			( signal "@baseboard_fab2_lib.baseboard_fab2(sch_1):xdp_pwrgd_rst_n"
				( attribute "CDS_PHYS_NET_NAME" "XDP_PWRGD_RST_N"
					( Origin gPackager )
				)
				( objectStatus "XDP_PWRGD_RST_N" )
			)
			( signal "@baseboard_fab2_lib.baseboard_fab2(sch_1):xdp_rsmrst_n"
				( attribute "CDS_PHYS_NET_NAME" "XDP_RSMRST_N"
					( Origin gPackager )
				)
				( objectStatus "XDP_RSMRST_N" )
			)
			( signal "@baseboard_fab2_lib.baseboard_fab2(sch_1):xdp_rst_co_n"
				( attribute "CDS_PHYS_NET_NAME" "XDP_RST_CO_N"
					( Origin gPackager )
				)
				( objectStatus "XDP_RST_CO_N" )
			)
			( signal "@baseboard_fab2_lib.baseboard_fab2(sch_1):xdp_spi_pch_mosi_boot_halt_n"
				( attribute "CDS_PHYS_NET_NAME" "XDP_SPI_PCH_MOSI_BOOT_HALT_N"
					( Origin gPackager )
				)
				( objectStatus "XDP_SPI_PCH_MOSI_BOOT_HALT_N" )
			)
			( signal "@baseboard_fab2_lib.baseboard_fab2(sch_1):xdp_syspwrok"
				( attribute "CDS_PHYS_NET_NAME" "XDP_SYSPWROK"
					( Origin gPackager )
				)
				( objectStatus "XDP_SYSPWROK" )
			)
			( signal "@baseboard_fab2_lib.baseboard_fab2(sch_1):xdp_tdi"
				( attribute "CDS_PHYS_NET_NAME" "XDP_TDI"
					( Origin gPackager )
				)
				( objectStatus "XDP_TDI" )
			)
			( signal "@baseboard_fab2_lib.baseboard_fab2(sch_1):xdp_tdo"
				( attribute "CDS_PHYS_NET_NAME" "XDP_TDO"
					( Origin gPackager )
				)
				( objectStatus "XDP_TDO" )
			)
			( signal "@baseboard_fab2_lib.baseboard_fab2(sch_1):xdp_tms"
				( attribute "CDS_PHYS_NET_NAME" "XDP_TMS"
					( Origin gPackager )
				)
				( objectStatus "XDP_TMS" )
			)
			( signal "@baseboard_fab2_lib.baseboard_fab2(sch_1):xdp_trst_n"
				( attribute "CDS_PHYS_NET_NAME" "XDP_TRST_N"
					( Origin gPackager )
				)
				( objectStatus "XDP_TRST_N" )
			)
			( signal "@baseboard_fab2_lib.baseboard_fab2(sch_1):pwrgd_pvccin_cpu0"
				( attribute "CDS_PHYS_NET_NAME" "PWRGD_PVCCIN_CPU0"
					( Origin gPackager )
				)
				( objectStatus "PWRGD_PVCCIN_CPU0" )
			)
			( signal "@baseboard_fab2_lib.baseboard_fab2(sch_1):xdp_cpu_tdo"
				( attribute "CDS_PHYS_NET_NAME" "XDP_CPU_TDO"
					( Origin gPackager )
				)
				( objectStatus "XDP_CPU_TDO" )
			)
			( signal "@baseboard_fab2_lib.baseboard_fab2(sch_1):fm_cpu0_and_cpu1_mcp_pres"
				( attribute "CDS_PHYS_NET_NAME" "FM_CPU0_AND_CPU1_MCP_PRES"
					( Origin gPackager )
				)
				( objectStatus "FM_CPU0_AND_CPU1_MCP_PRES" )
			)
			( signal "@baseboard_fab2_lib.baseboard_fab2(sch_1):fm_cpu0_cd_pres"
				( attribute "CDS_PHYS_NET_NAME" "FM_CPU0_CD_PRES"
					( Origin gPackager )
				)
				( objectStatus "FM_CPU0_CD_PRES" )
			)
			( signal "@baseboard_fab2_lib.baseboard_fab2(sch_1):fm_cpu0_or_cpu1_mcp_pres"
				( attribute "CDS_PHYS_NET_NAME" "FM_CPU0_OR_CPU1_MCP_PRES"
					( Origin gPackager )
				)
				( objectStatus "FM_CPU0_OR_CPU1_MCP_PRES" )
			)
			( signal "@baseboard_fab2_lib.baseboard_fab2(sch_1):fm_cpu1_cd_pres"
				( attribute "CDS_PHYS_NET_NAME" "FM_CPU1_CD_PRES"
					( Origin gPackager )
				)
				( objectStatus "FM_CPU1_CD_PRES" )
			)
			( signal "@baseboard_fab2_lib.baseboard_fab2(sch_1):jtag_mcp_cpu0_tdi_r"
				( attribute "CDS_PHYS_NET_NAME" "JTAG_MCP_CPU0_TDI_R"
					( Origin gPackager )
				)
				( objectStatus "JTAG_MCP_CPU0_TDI_R" )
			)
			( signal "@baseboard_fab2_lib.baseboard_fab2(sch_1):jtag_mcp_cpu1_tdi_r"
				( attribute "CDS_PHYS_NET_NAME" "JTAG_MCP_CPU1_TDI_R"
					( Origin gPackager )
				)
				( objectStatus "JTAG_MCP_CPU1_TDI_R" )
			)
			( signal "@baseboard_fab2_lib.baseboard_fab2(sch_1):jtag_mcp_mux_tdi"
				( attribute "CDS_PHYS_NET_NAME" "JTAG_MCP_MUX_TDI"
					( Origin gPackager )
				)
				( objectStatus "JTAG_MCP_MUX_TDI" )
			)
			( signal "@baseboard_fab2_lib.baseboard_fab2(sch_1):jtag_mcp_mux_tdo"
				( attribute "CDS_PHYS_NET_NAME" "JTAG_MCP_MUX_TDO"
					( Origin gPackager )
				)
				( objectStatus "JTAG_MCP_MUX_TDO" )
			)
			( signal "@baseboard_fab2_lib.baseboard_fab2(sch_1):jtag_mcp_tck_r"
				( attribute "CDS_PHYS_NET_NAME" "JTAG_MCP_TCK_R"
					( Origin gPackager )
				)
				( objectStatus "JTAG_MCP_TCK_R" )
			)
			( signal "@baseboard_fab2_lib.baseboard_fab2(sch_1):jtag_mcp_tms_r"
				( attribute "CDS_PHYS_NET_NAME" "JTAG_MCP_TMS_R"
					( Origin gPackager )
				)
				( objectStatus "JTAG_MCP_TMS_R" )
			)
			( signal "@baseboard_fab2_lib.baseboard_fab2(sch_1):jtag_mcp_tms_r1"
				( attribute "CDS_PHYS_NET_NAME" "JTAG_MCP_TMS_R1"
					( Origin gPackager )
				)
				( objectStatus "JTAG_MCP_TMS_R1" )
			)
			( signal "@baseboard_fab2_lib.baseboard_fab2(sch_1):pwrgd_cpu0_g_r"
				( attribute "CDS_PHYS_NET_NAME" "PWRGD_CPU0_G_R"
					( Origin gPackager )
				)
				( objectStatus "PWRGD_CPU0_G_R" )
			)
			( signal "@baseboard_fab2_lib.baseboard_fab2(sch_1):tp_jtag_mcp_io8_rsvd"
				( attribute "CDS_PHYS_NET_NAME" "TP_JTAG_MCP_IO8_RSVD"
					( Origin gPackager )
				)
				( objectStatus "TP_JTAG_MCP_IO8_RSVD" )
			)
			( signal "@baseboard_fab2_lib.baseboard_fab2(sch_1):a_pch_xclk_biasref"
				( attribute "CDS_PHYS_NET_NAME" "A_PCH_XCLK_BIASREF"
					( Origin gPackager )
				)
				( objectStatus "A_PCH_XCLK_BIASREF" )
			)
			( signal "@baseboard_fab2_lib.baseboard_fab2(sch_1):clk_100m_airmax8_pe1_dn"
				( attribute "CDS_PHYS_NET_NAME" "CLK_100M_AIRMAX8_PE1_DN"
					( Origin gPackager )
				)
				( objectStatus "CLK_100M_AIRMAX8_PE1_DN" )
			)
			( signal "@baseboard_fab2_lib.baseboard_fab2(sch_1):clk_100m_airmax8_pe1_dp"
				( attribute "CDS_PHYS_NET_NAME" "CLK_100M_AIRMAX8_PE1_DP"
					( Origin gPackager )
				)
				( objectStatus "CLK_100M_AIRMAX8_PE1_DP" )
			)
			( signal "@baseboard_fab2_lib.baseboard_fab2(sch_1):clk_100m_bmc_pe_dn"
				( attribute "CDS_PHYS_NET_NAME" "CLK_100M_BMC_PE_DN"
					( Origin gPackager )
				)
				( objectStatus "CLK_100M_BMC_PE_DN" )
			)
			( signal "@baseboard_fab2_lib.baseboard_fab2(sch_1):clk_100m_bmc_pe_dp"
				( attribute "CDS_PHYS_NET_NAME" "CLK_100M_BMC_PE_DP"
					( Origin gPackager )
				)
				( objectStatus "CLK_100M_BMC_PE_DP" )
			)
			( signal "@baseboard_fab2_lib.baseboard_fab2(sch_1):clk_100m_bmc_pe_r_dn"
				( attribute "CDS_PHYS_NET_NAME" "CLK_100M_BMC_PE_R_DN"
					( Origin gPackager )
				)
				( objectStatus "CLK_100M_BMC_PE_R_DN" )
			)
			( signal "@baseboard_fab2_lib.baseboard_fab2(sch_1):clk_100m_bmc_pe_r_dp"
				( attribute "CDS_PHYS_NET_NAME" "CLK_100M_BMC_PE_R_DP"
					( Origin gPackager )
				)
				( objectStatus "CLK_100M_BMC_PE_R_DP" )
			)
			( signal "@baseboard_fab2_lib.baseboard_fab2(sch_1):clk_100m_m2_dn"
				( attribute "CDS_PHYS_NET_NAME" "CLK_100M_M2_DN"
					( Origin gPackager )
				)
				( objectStatus "CLK_100M_M2_DN" )
			)
			( signal "@baseboard_fab2_lib.baseboard_fab2(sch_1):clk_100m_m2_dp"
				( attribute "CDS_PHYS_NET_NAME" "CLK_100M_M2_DP"
					( Origin gPackager )
				)
				( objectStatus "CLK_100M_M2_DP" )
			)
			( signal "@baseboard_fab2_lib.baseboard_fab2(sch_1):clk_100m_mezz1_dn"
				( attribute "CDS_PHYS_NET_NAME" "CLK_100M_MEZZ1_DN"
					( Origin gPackager )
				)
				( objectStatus "CLK_100M_MEZZ1_DN" )
			)
			( signal "@baseboard_fab2_lib.baseboard_fab2(sch_1):clk_100m_mezz1_dp"
				( attribute "CDS_PHYS_NET_NAME" "CLK_100M_MEZZ1_DP"
					( Origin gPackager )
				)
				( objectStatus "CLK_100M_MEZZ1_DP" )
			)
			( signal "@baseboard_fab2_lib.baseboard_fab2(sch_1):clk_100m_mezz2_dn"
				( attribute "CDS_PHYS_NET_NAME" "CLK_100M_MEZZ2_DN"
					( Origin gPackager )
				)
				( objectStatus "CLK_100M_MEZZ2_DN" )
			)
			( signal "@baseboard_fab2_lib.baseboard_fab2(sch_1):clk_100m_mezz2_dp"
				( attribute "CDS_PHYS_NET_NAME" "CLK_100M_MEZZ2_DP"
					( Origin gPackager )
				)
				( objectStatus "CLK_100M_MEZZ2_DP" )
			)
			( signal "@baseboard_fab2_lib.baseboard_fab2(sch_1):clk_100m_mezz3_dn"
				( attribute "CDS_PHYS_NET_NAME" "CLK_100M_MEZZ3_DN"
					( Origin gPackager )
				)
				( objectStatus "CLK_100M_MEZZ3_DN" )
			)
			( signal "@baseboard_fab2_lib.baseboard_fab2(sch_1):clk_100m_mezz3_dp"
				( attribute "CDS_PHYS_NET_NAME" "CLK_100M_MEZZ3_DP"
					( Origin gPackager )
				)
				( objectStatus "CLK_100M_MEZZ3_DP" )
			)
			( signal "@baseboard_fab2_lib.baseboard_fab2(sch_1):clk_100m_mezz4_dn"
				( attribute "CDS_PHYS_NET_NAME" "CLK_100M_MEZZ4_DN"
					( Origin gPackager )
				)
				( objectStatus "CLK_100M_MEZZ4_DN" )
			)
			( signal "@baseboard_fab2_lib.baseboard_fab2(sch_1):clk_100m_mezz4_dp"
				( attribute "CDS_PHYS_NET_NAME" "CLK_100M_MEZZ4_DP"
					( Origin gPackager )
				)
				( objectStatus "CLK_100M_MEZZ4_DP" )
			)
			( signal "@baseboard_fab2_lib.baseboard_fab2(sch_1):clk_100m_sprv_dn"
				( attribute "CDS_PHYS_NET_NAME" "CLK_100M_SPRV_DN"
					( Origin gPackager )
				)
				( objectStatus "CLK_100M_SPRV_DN" )
			)
			( signal "@baseboard_fab2_lib.baseboard_fab2(sch_1):clk_100m_sprv_dp"
				( attribute "CDS_PHYS_NET_NAME" "CLK_100M_SPRV_DP"
					( Origin gPackager )
				)
				( objectStatus "CLK_100M_SPRV_DP" )
			)
			( signal "@baseboard_fab2_lib.baseboard_fab2(sch_1):clk_48m_usb_bmc"
				( attribute "CDS_PHYS_NET_NAME" "CLK_48M_USB_BMC"
					( Origin gPackager )
				)
				( attribute "PHYS_NET_NAME" "CLK_48M_USB_BMC"
					( Origin gPackager )
				)
				( objectStatus "CLK_48M_USB_BMC" )
			)
			( signal "@baseboard_fab2_lib.baseboard_fab2(sch_1):page147_fm_cpld_bmc_pwrdn_n"
				( attribute "CDS_PHYS_NET_NAME" "FM_CPLD_BMC_PWRDN_N"
					( Origin gPackager )
				)
				( attribute "PHYS_NET_NAME" "FM_CPLD_BMC_PWRDN_N"
					( Origin gFrontEnd )
				)
				( objectFlag fObjectAlias )
				( objectStatus "page147_fm_cpld_bmc_pwrdn_n" )
			)
			( signal "@baseboard_fab2_lib.baseboard_fab2(sch_1):h_pmsync_clk_24m_r"
				( attribute "CDS_PHYS_NET_NAME" "H_PMSYNC_CLK_24M_R"
					( Origin gPackager )
				)
				( objectStatus "H_PMSYNC_CLK_24M_R" )
			)
			( signal "@baseboard_fab2_lib.baseboard_fab2(sch_1):tp_clk_100m_nsscc0_dn"
				( attribute "CDS_PHYS_NET_NAME" "TP_CLK_100M_NSSCC0_DN"
					( Origin gPackager )
				)
				( objectStatus "TP_CLK_100M_NSSCC0_DN" )
			)
			( signal "@baseboard_fab2_lib.baseboard_fab2(sch_1):tp_clk_100m_nsscc0_dp"
				( attribute "CDS_PHYS_NET_NAME" "TP_CLK_100M_NSSCC0_DP"
					( Origin gPackager )
				)
				( objectStatus "TP_CLK_100M_NSSCC0_DP" )
			)
			( signal "@baseboard_fab2_lib.baseboard_fab2(sch_1):tp_clk_100m_nsscc1_dn"
				( attribute "CDS_PHYS_NET_NAME" "TP_CLK_100M_NSSCC1_DN"
					( Origin gPackager )
				)
				( objectStatus "TP_CLK_100M_NSSCC1_DN" )
			)
			( signal "@baseboard_fab2_lib.baseboard_fab2(sch_1):tp_clk_100m_nsscc1_dp"
				( attribute "CDS_PHYS_NET_NAME" "TP_CLK_100M_NSSCC1_DP"
					( Origin gPackager )
				)
				( objectStatus "TP_CLK_100M_NSSCC1_DP" )
			)
			( signal "@baseboard_fab2_lib.baseboard_fab2(sch_1):tp_clk_100m_plat1_dn"
				( attribute "CDS_PHYS_NET_NAME" "TP_CLK_100M_PLAT1_DN"
					( Origin gPackager )
				)
				( objectStatus "TP_CLK_100M_PLAT1_DN" )
			)
			( signal "@baseboard_fab2_lib.baseboard_fab2(sch_1):tp_clk_100m_plat1_dp"
				( attribute "CDS_PHYS_NET_NAME" "TP_CLK_100M_PLAT1_DP"
					( Origin gPackager )
				)
				( objectStatus "TP_CLK_100M_PLAT1_DP" )
			)
			( signal "@baseboard_fab2_lib.baseboard_fab2(sch_1):tp_clk_24m_pmsync2"
				( attribute "CDS_PHYS_NET_NAME" "TP_CLK_24M_PMSYNC2"
					( Origin gPackager )
				)
				( objectStatus "TP_CLK_24M_PMSYNC2" )
			)
			( signal "@baseboard_fab2_lib.baseboard_fab2(sch_1):tp_pch_rsvd64"
				( attribute "CDS_PHYS_NET_NAME" "TP_PCH_RSVD64"
					( Origin gPackager )
				)
				( objectStatus "TP_PCH_RSVD64" )
			)
			( signal "@baseboard_fab2_lib.baseboard_fab2(sch_1):tp_pch_rsvd65"
				( attribute "CDS_PHYS_NET_NAME" "TP_PCH_RSVD65"
					( Origin gPackager )
				)
				( objectStatus "TP_PCH_RSVD65" )
			)
			( signal "@baseboard_fab2_lib.baseboard_fab2(sch_1):xtal_33k_rtc1"
				( attribute "CDS_PHYS_NET_NAME" "XTAL_33K_RTC1"
					( Origin gPackager )
				)
				( objectStatus "XTAL_33K_RTC1" )
			)
			( signal "@baseboard_fab2_lib.baseboard_fab2(sch_1):xtal_33k_rtc2"
				( attribute "CDS_PHYS_NET_NAME" "XTAL_33K_RTC2"
					( Origin gPackager )
				)
				( objectStatus "XTAL_33K_RTC2" )
			)
			( signal "@baseboard_fab2_lib.baseboard_fab2(sch_1):xtal_pch_48m_in"
				( attribute "CDS_PHYS_NET_NAME" "XTAL_PCH_48M_IN"
					( Origin gPackager )
				)
				( objectStatus "XTAL_PCH_48M_IN" )
			)
			( signal "@baseboard_fab2_lib.baseboard_fab2(sch_1):xtal_pch_48m_out"
				( attribute "CDS_PHYS_NET_NAME" "XTAL_PCH_48M_OUT"
					( Origin gPackager )
				)
				( objectStatus "XTAL_PCH_48M_OUT" )
			)
			( signal "@baseboard_fab2_lib.baseboard_fab2(sch_1):a_usb2_comp"
				( attribute "CDS_PHYS_NET_NAME" "A_USB2_COMP"
					( Origin gPackager )
				)
				( objectStatus "A_USB2_COMP" )
			)
			( signal "@baseboard_fab2_lib.baseboard_fab2(sch_1):a_usb2_vbus"
				( attribute "CDS_PHYS_NET_NAME" "A_USB2_VBUS"
					( Origin gPackager )
				)
				( objectStatus "A_USB2_VBUS" )
			)
			( signal "@baseboard_fab2_lib.baseboard_fab2(sch_1):tp_pch_rsvd55"
				( attribute "CDS_PHYS_NET_NAME" "TP_PCH_RSVD55"
					( Origin gPackager )
				)
				( objectStatus "TP_PCH_RSVD55" )
			)
			( signal "@baseboard_fab2_lib.baseboard_fab2(sch_1):clk_100m_src12_dp"
				( attribute "CDS_PHYS_NET_NAME" "CLK_100M_SRC12_DP"
					( Origin gPackager )
				)
				( objectStatus "CLK_100M_SRC12_DP" )
			)
			( signal "@baseboard_fab2_lib.baseboard_fab2(sch_1):clk_100m_src12_dn"
				( attribute "CDS_PHYS_NET_NAME" "CLK_100M_SRC12_DN"
					( Origin gPackager )
				)
				( objectStatus "CLK_100M_SRC12_DN" )
			)
			( signal "@baseboard_fab2_lib.baseboard_fab2(sch_1):tp_usb2_p03_dn"
				( attribute "CDS_PHYS_NET_NAME" "TP_USB2_P03_DN"
					( Origin gPackager )
				)
				( objectStatus "TP_USB2_P03_DN" )
			)
			( signal "@baseboard_fab2_lib.baseboard_fab2(sch_1):tp_usb2_p03_dp"
				( attribute "CDS_PHYS_NET_NAME" "TP_USB2_P03_DP"
					( Origin gPackager )
				)
				( objectStatus "TP_USB2_P03_DP" )
			)
			( signal "@baseboard_fab2_lib.baseboard_fab2(sch_1):tp_usb2_p06_dn"
				( attribute "CDS_PHYS_NET_NAME" "TP_USB2_P06_DN"
					( Origin gPackager )
				)
				( objectStatus "TP_USB2_P06_DN" )
			)
			( signal "@baseboard_fab2_lib.baseboard_fab2(sch_1):tp_usb2_p06_dp"
				( attribute "CDS_PHYS_NET_NAME" "TP_USB2_P06_DP"
					( Origin gPackager )
				)
				( objectStatus "TP_USB2_P06_DP" )
			)
			( signal "@baseboard_fab2_lib.baseboard_fab2(sch_1):tp_usb2_p07_dn"
				( attribute "CDS_PHYS_NET_NAME" "TP_USB2_P07_DN"
					( Origin gPackager )
				)
				( objectStatus "TP_USB2_P07_DN" )
			)
			( signal "@baseboard_fab2_lib.baseboard_fab2(sch_1):tp_usb2_p07_dp"
				( attribute "CDS_PHYS_NET_NAME" "TP_USB2_P07_DP"
					( Origin gPackager )
				)
				( objectStatus "TP_USB2_P07_DP" )
			)
			( signal "@baseboard_fab2_lib.baseboard_fab2(sch_1):tp_usb2_p10_dn"
				( attribute "CDS_PHYS_NET_NAME" "TP_USB2_P10_DN"
					( Origin gPackager )
				)
				( objectStatus "TP_USB2_P10_DN" )
			)
			( signal "@baseboard_fab2_lib.baseboard_fab2(sch_1):tp_usb2_p10_dp"
				( attribute "CDS_PHYS_NET_NAME" "TP_USB2_P10_DP"
					( Origin gPackager )
				)
				( objectStatus "TP_USB2_P10_DP" )
			)
			( signal "@baseboard_fab2_lib.baseboard_fab2(sch_1):tp_usb2_p11_dn"
				( attribute "CDS_PHYS_NET_NAME" "TP_USB2_P11_DN"
					( Origin gPackager )
				)
				( objectStatus "TP_USB2_P11_DN" )
			)
			( signal "@baseboard_fab2_lib.baseboard_fab2(sch_1):tp_usb2_p11_dp"
				( attribute "CDS_PHYS_NET_NAME" "TP_USB2_P11_DP"
					( Origin gPackager )
				)
				( objectStatus "TP_USB2_P11_DP" )
			)
			( signal "@baseboard_fab2_lib.baseboard_fab2(sch_1):tp_usb2_p12_dn"
				( attribute "CDS_PHYS_NET_NAME" "TP_USB2_P12_DN"
					( Origin gPackager )
				)
				( objectStatus "TP_USB2_P12_DN" )
			)
			( signal "@baseboard_fab2_lib.baseboard_fab2(sch_1):tp_usb2_p12_dp"
				( attribute "CDS_PHYS_NET_NAME" "TP_USB2_P12_DP"
					( Origin gPackager )
				)
				( objectStatus "TP_USB2_P12_DP" )
			)
			( signal "@baseboard_fab2_lib.baseboard_fab2(sch_1):tp_usb2_p13_dn"
				( attribute "CDS_PHYS_NET_NAME" "TP_USB2_P13_DN"
					( Origin gPackager )
				)
				( objectStatus "TP_USB2_P13_DN" )
			)
			( signal "@baseboard_fab2_lib.baseboard_fab2(sch_1):tp_usb2_p13_dp"
				( attribute "CDS_PHYS_NET_NAME" "TP_USB2_P13_DP"
					( Origin gPackager )
				)
				( objectStatus "TP_USB2_P13_DP" )
			)
			( signal "@baseboard_fab2_lib.baseboard_fab2(sch_1):tp_usb2_p14_dn"
				( attribute "CDS_PHYS_NET_NAME" "TP_USB2_P14_DN"
					( Origin gPackager )
				)
				( objectStatus "TP_USB2_P14_DN" )
			)
			( signal "@baseboard_fab2_lib.baseboard_fab2(sch_1):tp_usb2_p14_dp"
				( attribute "CDS_PHYS_NET_NAME" "TP_USB2_P14_DP"
					( Origin gPackager )
				)
				( objectStatus "TP_USB2_P14_DP" )
			)
			( signal "@baseboard_fab2_lib.baseboard_fab2(sch_1):tp_usb2_p8_dn"
				( attribute "CDS_PHYS_NET_NAME" "TP_USB2_P8_DN"
					( Origin gPackager )
				)
				( objectStatus "TP_USB2_P8_DN" )
			)
			( signal "@baseboard_fab2_lib.baseboard_fab2(sch_1):tp_usb2_p8_dp"
				( attribute "CDS_PHYS_NET_NAME" "TP_USB2_P8_DP"
					( Origin gPackager )
				)
				( objectStatus "TP_USB2_P8_DP" )
			)
			( signal "@baseboard_fab2_lib.baseboard_fab2(sch_1):tp_usb2_p9_dn"
				( attribute "CDS_PHYS_NET_NAME" "TP_USB2_P9_DN"
					( Origin gPackager )
				)
				( objectStatus "TP_USB2_P9_DN" )
			)
			( signal "@baseboard_fab2_lib.baseboard_fab2(sch_1):tp_usb2_p9_dp"
				( attribute "CDS_PHYS_NET_NAME" "TP_USB2_P9_DP"
					( Origin gPackager )
				)
				( objectStatus "TP_USB2_P9_DP" )
			)
			( signal "@baseboard_fab2_lib.baseboard_fab2(sch_1):tp_usb3_p02_rxn"
				( attribute "CDS_PHYS_NET_NAME" "TP_USB3_P02_RXN"
					( Origin gPackager )
				)
				( objectStatus "TP_USB3_P02_RXN" )
			)
			( signal "@baseboard_fab2_lib.baseboard_fab2(sch_1):tp_usb3_p02_rxp"
				( attribute "CDS_PHYS_NET_NAME" "TP_USB3_P02_RXP"
					( Origin gPackager )
				)
				( objectStatus "TP_USB3_P02_RXP" )
			)
			( signal "@baseboard_fab2_lib.baseboard_fab2(sch_1):tp_usb3_p02_txn"
				( attribute "CDS_PHYS_NET_NAME" "TP_USB3_P02_TXN"
					( Origin gPackager )
				)
				( objectStatus "TP_USB3_P02_TXN" )
			)
			( signal "@baseboard_fab2_lib.baseboard_fab2(sch_1):tp_usb3_p02_txp"
				( attribute "CDS_PHYS_NET_NAME" "TP_USB3_P02_TXP"
					( Origin gPackager )
				)
				( objectStatus "TP_USB3_P02_TXP" )
			)
			( signal "@baseboard_fab2_lib.baseboard_fab2(sch_1):tp_usb3_p03_rxn"
				( attribute "CDS_PHYS_NET_NAME" "TP_USB3_P03_RXN"
					( Origin gPackager )
				)
				( objectStatus "TP_USB3_P03_RXN" )
			)
			( signal "@baseboard_fab2_lib.baseboard_fab2(sch_1):tp_usb3_p03_rxp"
				( attribute "CDS_PHYS_NET_NAME" "TP_USB3_P03_RXP"
					( Origin gPackager )
				)
				( objectStatus "TP_USB3_P03_RXP" )
			)
			( signal "@baseboard_fab2_lib.baseboard_fab2(sch_1):tp_usb3_p03_txn"
				( attribute "CDS_PHYS_NET_NAME" "TP_USB3_P03_TXN"
					( Origin gPackager )
				)
				( objectStatus "TP_USB3_P03_TXN" )
			)
			( signal "@baseboard_fab2_lib.baseboard_fab2(sch_1):tp_usb3_p03_txp"
				( attribute "CDS_PHYS_NET_NAME" "TP_USB3_P03_TXP"
					( Origin gPackager )
				)
				( objectStatus "TP_USB3_P03_TXP" )
			)
			( signal "@baseboard_fab2_lib.baseboard_fab2(sch_1):tp_usb3_p04_rxn"
				( attribute "CDS_PHYS_NET_NAME" "TP_USB3_P04_RXN"
					( Origin gPackager )
				)
				( objectStatus "TP_USB3_P04_RXN" )
			)
			( signal "@baseboard_fab2_lib.baseboard_fab2(sch_1):tp_usb3_p04_rxp"
				( attribute "CDS_PHYS_NET_NAME" "TP_USB3_P04_RXP"
					( Origin gPackager )
				)
				( objectStatus "TP_USB3_P04_RXP" )
			)
			( signal "@baseboard_fab2_lib.baseboard_fab2(sch_1):tp_usb3_p04_txn"
				( attribute "CDS_PHYS_NET_NAME" "TP_USB3_P04_TXN"
					( Origin gPackager )
				)
				( objectStatus "TP_USB3_P04_TXN" )
			)
			( signal "@baseboard_fab2_lib.baseboard_fab2(sch_1):tp_usb3_p04_txp"
				( attribute "CDS_PHYS_NET_NAME" "TP_USB3_P04_TXP"
					( Origin gPackager )
				)
				( objectStatus "TP_USB3_P04_TXP" )
			)
			( signal "@baseboard_fab2_lib.baseboard_fab2(sch_1):tp_usb3_p05_rxn"
				( attribute "CDS_PHYS_NET_NAME" "TP_USB3_P05_RXN"
					( Origin gPackager )
				)
				( objectStatus "TP_USB3_P05_RXN" )
			)
			( signal "@baseboard_fab2_lib.baseboard_fab2(sch_1):tp_usb3_p05_rxp"
				( attribute "CDS_PHYS_NET_NAME" "TP_USB3_P05_RXP"
					( Origin gPackager )
				)
				( objectStatus "TP_USB3_P05_RXP" )
			)
			( signal "@baseboard_fab2_lib.baseboard_fab2(sch_1):tp_usb3_p05_txn"
				( attribute "CDS_PHYS_NET_NAME" "TP_USB3_P05_TXN"
					( Origin gPackager )
				)
				( objectStatus "TP_USB3_P05_TXN" )
			)
			( signal "@baseboard_fab2_lib.baseboard_fab2(sch_1):tp_usb3_p05_txp"
				( attribute "CDS_PHYS_NET_NAME" "TP_USB3_P05_TXP"
					( Origin gPackager )
				)
				( objectStatus "TP_USB3_P05_TXP" )
			)
			( signal "@baseboard_fab2_lib.baseboard_fab2(sch_1):tp_usb3_p06_rxn"
				( attribute "CDS_PHYS_NET_NAME" "TP_USB3_P06_RXN"
					( Origin gPackager )
				)
				( objectStatus "TP_USB3_P06_RXN" )
			)
			( signal "@baseboard_fab2_lib.baseboard_fab2(sch_1):tp_usb3_p06_rxp"
				( attribute "CDS_PHYS_NET_NAME" "TP_USB3_P06_RXP"
					( Origin gPackager )
				)
				( objectStatus "TP_USB3_P06_RXP" )
			)
			( signal "@baseboard_fab2_lib.baseboard_fab2(sch_1):tp_usb3_p06_txn"
				( attribute "CDS_PHYS_NET_NAME" "TP_USB3_P06_TXN"
					( Origin gPackager )
				)
				( objectStatus "TP_USB3_P06_TXN" )
			)
			( signal "@baseboard_fab2_lib.baseboard_fab2(sch_1):tp_usb3_p06_txp"
				( attribute "CDS_PHYS_NET_NAME" "TP_USB3_P06_TXP"
					( Origin gPackager )
				)
				( objectStatus "TP_USB3_P06_TXP" )
			)
			( signal "@baseboard_fab2_lib.baseboard_fab2(sch_1):usb2_p01_dn"
				( attribute "CDS_PHYS_NET_NAME" "USB2_P01_DN"
					( Origin gPackager )
				)
				( objectStatus "USB2_P01_DN" )
			)
			( signal "@baseboard_fab2_lib.baseboard_fab2(sch_1):usb2_p01_dp"
				( attribute "CDS_PHYS_NET_NAME" "USB2_P01_DP"
					( Origin gPackager )
				)
				( objectStatus "USB2_P01_DP" )
			)
			( signal "@baseboard_fab2_lib.baseboard_fab2(sch_1):usb2_pch_bmc_p5_dn"
				( attribute "CDS_PHYS_NET_NAME" "USB2_PCH_BMC_P5_DN"
					( Origin gPackager )
				)
				( objectStatus "USB2_PCH_BMC_P5_DN" )
			)
			( signal "@baseboard_fab2_lib.baseboard_fab2(sch_1):usb2_pch_bmc_p5_dp"
				( attribute "CDS_PHYS_NET_NAME" "USB2_PCH_BMC_P5_DP"
					( Origin gPackager )
				)
				( objectStatus "USB2_PCH_BMC_P5_DP" )
			)
			( signal "@baseboard_fab2_lib.baseboard_fab2(sch_1):vcc_va_3v3"
				( alias ( signalRef "@baseboard_fab2_lib.baseboard_fab2(sch_1):page150_vcc_va_3v3") )
				( alias ( signalRef "@baseboard_fab2_lib.baseboard_fab2(sch_1):page148_vcc_va_3v3") )
				( attribute "CDS_PHYS_NET_NAME" "VCC_VA_3V3"
					( Origin gPackager )
				)
				( objectStatus "VCC_VA_3V3" )
			)
			( signal "@baseboard_fab2_lib.baseboard_fab2(sch_1):page150_vcc_va_3v3"
				( objectFlag fObjectAlias )
				( objectStatus "page150_vcc_va_3v3" )
			)
			( signal "@baseboard_fab2_lib.baseboard_fab2(sch_1):page148_vcc_va_3v3"
				( objectFlag fObjectAlias )
				( objectStatus "page148_vcc_va_3v3" )
			)
			( signal "@baseboard_fab2_lib.baseboard_fab2(sch_1):page150_vcc_pa_3v3"
				( objectFlag fObjectAlias )
				( objectStatus "page150_vcc_pa_3v3" )
			)
			( signal "@baseboard_fab2_lib.baseboard_fab2(sch_1):usb3_p01_rxn"
				( attribute "CDS_PHYS_NET_NAME" "USB3_P01_RXN"
					( Origin gPackager )
				)
				( objectStatus "USB3_P01_RXN" )
			)
			( signal "@baseboard_fab2_lib.baseboard_fab2(sch_1):usb3_p01_rxp"
				( attribute "CDS_PHYS_NET_NAME" "USB3_P01_RXP"
					( Origin gPackager )
				)
				( objectStatus "USB3_P01_RXP" )
			)
			( signal "@baseboard_fab2_lib.baseboard_fab2(sch_1):usb3_p01_txn"
				( attribute "CDS_PHYS_NET_NAME" "USB3_P01_TXN"
					( Origin gPackager )
				)
				( objectStatus "USB3_P01_TXN" )
			)
			( signal "@baseboard_fab2_lib.baseboard_fab2(sch_1):usb3_p01_txp"
				( attribute "CDS_PHYS_NET_NAME" "USB3_P01_TXP"
					( Origin gPackager )
				)
				( objectStatus "USB3_P01_TXP" )
			)
			( signal "@baseboard_fab2_lib.baseboard_fab2(sch_1):usb_pch_bmc_p4_dn"
				( attribute "CDS_PHYS_NET_NAME" "USB_PCH_BMC_P4_DN"
					( Origin gPackager )
				)
				( objectStatus "USB_PCH_BMC_P4_DN" )
			)
			( signal "@baseboard_fab2_lib.baseboard_fab2(sch_1):usb_pch_bmc_p4_dp"
				( attribute "CDS_PHYS_NET_NAME" "USB_PCH_BMC_P4_DP"
					( Origin gPackager )
				)
				( objectStatus "USB_PCH_BMC_P4_DP" )
			)
			( signal "@baseboard_fab2_lib.baseboard_fab2(sch_1):vcc_pa_3v3"
				( alias ( signalRef "@baseboard_fab2_lib.baseboard_fab2(sch_1):page150_vcc_pa_3v3") )
				( alias ( signalRef "@baseboard_fab2_lib.baseboard_fab2(sch_1):page148_vcc_pa_3v3") )
				( attribute "CDS_PHYS_NET_NAME" "VCC_PA_3V3"
					( Origin gPackager )
				)
				( objectStatus "VCC_PA_3V3" )
			)
			( signal "@baseboard_fab2_lib.baseboard_fab2(sch_1):page148_vcc_pa_3v3"
				( objectFlag fObjectAlias )
				( objectStatus "page148_vcc_pa_3v3" )
			)
			( signal "@baseboard_fab2_lib.baseboard_fab2(sch_1):page149_p1v2_aux_bmc"
				( objectFlag fObjectAlias )
				( objectStatus "page149_p1v2_aux_bmc" )
			)
			( signal "@baseboard_fab2_lib.baseboard_fab2(sch_1):peci_bmc_r"
				( attribute "CDS_PHYS_NET_NAME" "PECI_BMC_R"
					( Origin gPackager )
				)
				( objectStatus "PECI_BMC_R" )
			)
			( signal "@baseboard_fab2_lib.baseboard_fab2(sch_1):a_extclkn"
				( attribute "CDS_PHYS_NET_NAME" "A_EXTCLKN"
					( Origin gPackager )
				)
				( objectStatus "A_EXTCLKN" )
			)
			( signal "@baseboard_fab2_lib.baseboard_fab2(sch_1):a_extclkp"
				( attribute "CDS_PHYS_NET_NAME" "A_EXTCLKP"
					( Origin gPackager )
				)
				( objectStatus "A_EXTCLKP" )
			)
			( signal "@baseboard_fab2_lib.baseboard_fab2(sch_1):a_pcie_rcomp_n"
				( attribute "CDS_PHYS_NET_NAME" "A_PCIE_RCOMP_N"
					( Origin gPackager )
				)
				( objectStatus "A_PCIE_RCOMP_N" )
			)
			( signal "@baseboard_fab2_lib.baseboard_fab2(sch_1):a_pcie_rcomp_p"
				( attribute "CDS_PHYS_NET_NAME" "A_PCIE_RCOMP_P"
					( Origin gPackager )
				)
				( objectStatus "A_PCIE_RCOMP_P" )
			)
			( signal "@baseboard_fab2_lib.baseboard_fab2(sch_1):a_pcieup_rcomp_n"
				( attribute "CDS_PHYS_NET_NAME" "A_PCIEUP_RCOMP_N"
					( Origin gPackager )
				)
				( objectStatus "A_PCIEUP_RCOMP_N" )
			)
			( signal "@baseboard_fab2_lib.baseboard_fab2(sch_1):a_pcieup_rcomp_p"
				( attribute "CDS_PHYS_NET_NAME" "A_PCIEUP_RCOMP_P"
					( Origin gPackager )
				)
				( objectStatus "A_PCIEUP_RCOMP_P" )
			)
			( signal "@baseboard_fab2_lib.baseboard_fab2(sch_1):p2e_ssb_bmc_rx_c_dn"
				( attribute "CDS_PHYS_NET_NAME" "P2E_SSB_BMC_RX_C_DN"
					( Origin gPackager )
				)
				( objectStatus "P2E_SSB_BMC_RX_C_DN" )
			)
			( signal "@baseboard_fab2_lib.baseboard_fab2(sch_1):p2e_ssb_bmc_rx_c_dp"
				( attribute "CDS_PHYS_NET_NAME" "P2E_SSB_BMC_RX_C_DP"
					( Origin gPackager )
				)
				( objectStatus "P2E_SSB_BMC_RX_C_DP" )
			)
			( signal "@baseboard_fab2_lib.baseboard_fab2(sch_1):p2e_ssb_bmc_tx_c_dn"
				( attribute "CDS_PHYS_NET_NAME" "P2E_SSB_BMC_TX_C_DN"
					( Origin gPackager )
				)
				( objectStatus "P2E_SSB_BMC_TX_C_DN" )
			)
			( signal "@baseboard_fab2_lib.baseboard_fab2(sch_1):p2e_ssb_bmc_tx_c_dp"
				( attribute "CDS_PHYS_NET_NAME" "P2E_SSB_BMC_TX_C_DP"
					( Origin gPackager )
				)
				( objectStatus "P2E_SSB_BMC_TX_C_DP" )
			)
			( signal "@baseboard_fab2_lib.baseboard_fab2(sch_1):p2e_ssb_bmc_tx_dn"
				( attribute "CDS_PHYS_NET_NAME" "P2E_SSB_BMC_TX_DN"
					( Origin gPackager )
				)
				( objectStatus "P2E_SSB_BMC_TX_DN" )
			)
			( signal "@baseboard_fab2_lib.baseboard_fab2(sch_1):p2e_ssb_bmc_tx_dp"
				( attribute "CDS_PHYS_NET_NAME" "P2E_SSB_BMC_TX_DP"
					( Origin gPackager )
				)
				( objectStatus "P2E_SSB_BMC_TX_DP" )
			)
			( signal "@baseboard_fab2_lib.baseboard_fab2(sch_1):p3e_pch_m2_rx_dn(1)"
				( attribute "CDS_PHYS_NET_NAME" "P3E_PCH_M2_RX_DN<1>"
					( Origin gPackager )
				)
				( attribute "PNN" "P3E_PCH_M2_RX_DN<1>"
					( Origin gPackager )
				)
				( objectStatus "P3E_PCH_M2_RX_DN<1>" )
			)
			( signal "@baseboard_fab2_lib.baseboard_fab2(sch_1):p3e_pch_m2_rx_dn(2)"
				( attribute "CDS_PHYS_NET_NAME" "P3E_PCH_M2_RX_DN<2>"
					( Origin gPackager )
				)
				( attribute "PNN" "P3E_PCH_M2_RX_DN<2>"
					( Origin gPackager )
				)
				( objectStatus "P3E_PCH_M2_RX_DN<2>" )
			)
			( signal "@baseboard_fab2_lib.baseboard_fab2(sch_1):p3e_pch_m2_rx_dn(3)"
				( attribute "CDS_PHYS_NET_NAME" "P3E_PCH_M2_RX_DN<3>"
					( Origin gPackager )
				)
				( attribute "PNN" "P3E_PCH_M2_RX_DN<3>"
					( Origin gPackager )
				)
				( objectStatus "P3E_PCH_M2_RX_DN<3>" )
			)
			( signal "@baseboard_fab2_lib.baseboard_fab2(sch_1):p3e_pch_m2_rx_dp(1)"
				( attribute "CDS_PHYS_NET_NAME" "P3E_PCH_M2_RX_DP<1>"
					( Origin gPackager )
				)
				( attribute "PNN" "P3E_PCH_M2_RX_DP<1>"
					( Origin gPackager )
				)
				( objectStatus "P3E_PCH_M2_RX_DP<1>" )
			)
			( signal "@baseboard_fab2_lib.baseboard_fab2(sch_1):p3e_pch_m2_rx_dp(2)"
				( attribute "CDS_PHYS_NET_NAME" "P3E_PCH_M2_RX_DP<2>"
					( Origin gPackager )
				)
				( attribute "PNN" "P3E_PCH_M2_RX_DP<2>"
					( Origin gPackager )
				)
				( objectStatus "P3E_PCH_M2_RX_DP<2>" )
			)
			( signal "@baseboard_fab2_lib.baseboard_fab2(sch_1):p3e_pch_m2_rx_dp(3)"
				( attribute "CDS_PHYS_NET_NAME" "P3E_PCH_M2_RX_DP<3>"
					( Origin gPackager )
				)
				( attribute "PNN" "P3E_PCH_M2_RX_DP<3>"
					( Origin gPackager )
				)
				( objectStatus "P3E_PCH_M2_RX_DP<3>" )
			)
			( signal "@baseboard_fab2_lib.baseboard_fab2(sch_1):p3e_pch_m2_tx_dn(1)"
				( attribute "CDS_PHYS_NET_NAME" "P3E_PCH_M2_TX_DN<1>"
					( Origin gPackager )
				)
				( attribute "PNN" "P3E_PCH_M2_TX_DN<1>"
					( Origin gPackager )
				)
				( objectStatus "P3E_PCH_M2_TX_DN<1>" )
			)
			( signal "@baseboard_fab2_lib.baseboard_fab2(sch_1):p3e_pch_m2_tx_dn(2)"
				( attribute "CDS_PHYS_NET_NAME" "P3E_PCH_M2_TX_DN<2>"
					( Origin gPackager )
				)
				( attribute "PNN" "P3E_PCH_M2_TX_DN<2>"
					( Origin gPackager )
				)
				( objectStatus "P3E_PCH_M2_TX_DN<2>" )
			)
			( signal "@baseboard_fab2_lib.baseboard_fab2(sch_1):p3e_pch_m2_tx_dn(3)"
				( attribute "CDS_PHYS_NET_NAME" "P3E_PCH_M2_TX_DN<3>"
					( Origin gPackager )
				)
				( attribute "PNN" "P3E_PCH_M2_TX_DN<3>"
					( Origin gPackager )
				)
				( objectStatus "P3E_PCH_M2_TX_DN<3>" )
			)
			( signal "@baseboard_fab2_lib.baseboard_fab2(sch_1):p3e_pch_m2_tx_dp(1)"
				( attribute "CDS_PHYS_NET_NAME" "P3E_PCH_M2_TX_DP<1>"
					( Origin gPackager )
				)
				( attribute "PNN" "P3E_PCH_M2_TX_DP<1>"
					( Origin gPackager )
				)
				( objectStatus "P3E_PCH_M2_TX_DP<1>" )
			)
			( signal "@baseboard_fab2_lib.baseboard_fab2(sch_1):p3e_pch_m2_tx_dp(2)"
				( attribute "CDS_PHYS_NET_NAME" "P3E_PCH_M2_TX_DP<2>"
					( Origin gPackager )
				)
				( attribute "PNN" "P3E_PCH_M2_TX_DP<2>"
					( Origin gPackager )
				)
				( objectStatus "P3E_PCH_M2_TX_DP<2>" )
			)
			( signal "@baseboard_fab2_lib.baseboard_fab2(sch_1):p3e_pch_m2_tx_dp(3)"
				( attribute "CDS_PHYS_NET_NAME" "P3E_PCH_M2_TX_DP<3>"
					( Origin gPackager )
				)
				( attribute "PNN" "P3E_PCH_M2_TX_DP<3>"
					( Origin gPackager )
				)
				( objectStatus "P3E_PCH_M2_TX_DP<3>" )
			)
			( signal "@baseboard_fab2_lib.baseboard_fab2(sch_1):p3e_pch_rx_0_dn"
				( attribute "CDS_PHYS_NET_NAME" "P3E_PCH_RX_0_DN"
					( Origin gPackager )
				)
				( objectStatus "P3E_PCH_RX_0_DN" )
			)
			( signal "@baseboard_fab2_lib.baseboard_fab2(sch_1):p3e_pch_rx_0_dp"
				( attribute "CDS_PHYS_NET_NAME" "P3E_PCH_RX_0_DP"
					( Origin gPackager )
				)
				( objectStatus "P3E_PCH_RX_0_DP" )
			)
			( signal "@baseboard_fab2_lib.baseboard_fab2(sch_1):p3e_pch_tx_0_dn"
				( attribute "CDS_PHYS_NET_NAME" "P3E_PCH_TX_0_DN"
					( Origin gPackager )
				)
				( objectStatus "P3E_PCH_TX_0_DN" )
			)
			( signal "@baseboard_fab2_lib.baseboard_fab2(sch_1):p3e_pch_tx_0_dp"
				( attribute "CDS_PHYS_NET_NAME" "P3E_PCH_TX_0_DP"
					( Origin gPackager )
				)
				( objectStatus "P3E_PCH_TX_0_DP" )
			)
			( signal "@baseboard_fab2_lib.baseboard_fab2(sch_1):pe_pch_sprv_rx_c_dn"
				( attribute "CDS_PHYS_NET_NAME" "PE_PCH_SPRV_RX_C_DN"
					( Origin gPackager )
				)
				( objectStatus "PE_PCH_SPRV_RX_C_DN" )
			)
			( signal "@baseboard_fab2_lib.baseboard_fab2(sch_1):pe_pch_sprv_rx_c_dp"
				( attribute "CDS_PHYS_NET_NAME" "PE_PCH_SPRV_RX_C_DP"
					( Origin gPackager )
				)
				( objectStatus "PE_PCH_SPRV_RX_C_DP" )
			)
			( signal "@baseboard_fab2_lib.baseboard_fab2(sch_1):pe_pch_sprv_tx_dn"
				( attribute "CDS_PHYS_NET_NAME" "PE_PCH_SPRV_TX_DN"
					( Origin gPackager )
				)
				( objectStatus "PE_PCH_SPRV_TX_DN" )
			)
			( signal "@baseboard_fab2_lib.baseboard_fab2(sch_1):pe_pch_sprv_tx_dp"
				( attribute "CDS_PHYS_NET_NAME" "PE_PCH_SPRV_TX_DP"
					( Origin gPackager )
				)
				( objectStatus "PE_PCH_SPRV_TX_DP" )
			)
			( signal "@baseboard_fab2_lib.baseboard_fab2(sch_1):sata6g_pch_pcie_up_sata_rxn(0)"
				( attribute "CDS_PHYS_NET_NAME" "SATA6G_PCH_PCIE_UP_SATA_RXN<0>"
					( Origin gPackager )
				)
				( attribute "PNN" "SATA6G_PCH_PCIE_UP_SATA_RXN<0>"
					( Origin gPackager )
				)
				( objectStatus "SATA6G_PCH_PCIE_UP_SATA_RXN<0>" )
			)
			( signal "@baseboard_fab2_lib.baseboard_fab2(sch_1):sata6g_pch_pcie_up_sata_rxn(1)"
				( attribute "CDS_PHYS_NET_NAME" "SATA6G_PCH_PCIE_UP_SATA_RXN<1>"
					( Origin gPackager )
				)
				( attribute "PNN" "SATA6G_PCH_PCIE_UP_SATA_RXN<1>"
					( Origin gPackager )
				)
				( objectStatus "SATA6G_PCH_PCIE_UP_SATA_RXN<1>" )
			)
			( signal "@baseboard_fab2_lib.baseboard_fab2(sch_1):sata6g_pch_pcie_up_sata_rxn(2)"
				( attribute "CDS_PHYS_NET_NAME" "SATA6G_PCH_PCIE_UP_SATA_RXN<2>"
					( Origin gPackager )
				)
				( attribute "PNN" "SATA6G_PCH_PCIE_UP_SATA_RXN<2>"
					( Origin gPackager )
				)
				( objectStatus "SATA6G_PCH_PCIE_UP_SATA_RXN<2>" )
			)
			( signal "@baseboard_fab2_lib.baseboard_fab2(sch_1):sata6g_pch_pcie_up_sata_rxn(3)"
				( attribute "CDS_PHYS_NET_NAME" "SATA6G_PCH_PCIE_UP_SATA_RXN<3>"
					( Origin gPackager )
				)
				( attribute "PNN" "SATA6G_PCH_PCIE_UP_SATA_RXN<3>"
					( Origin gPackager )
				)
				( objectStatus "SATA6G_PCH_PCIE_UP_SATA_RXN<3>" )
			)
			( signal "@baseboard_fab2_lib.baseboard_fab2(sch_1):sata6g_pch_pcie_up_sata_rxn(4)"
				( attribute "CDS_PHYS_NET_NAME" "SATA6G_PCH_PCIE_UP_SATA_RXN<4>"
					( Origin gPackager )
				)
				( attribute "PNN" "SATA6G_PCH_PCIE_UP_SATA_RXN<4>"
					( Origin gPackager )
				)
				( objectStatus "SATA6G_PCH_PCIE_UP_SATA_RXN<4>" )
			)
			( signal "@baseboard_fab2_lib.baseboard_fab2(sch_1):sata6g_pch_pcie_up_sata_rxn(5)"
				( attribute "CDS_PHYS_NET_NAME" "SATA6G_PCH_PCIE_UP_SATA_RXN<5>"
					( Origin gPackager )
				)
				( attribute "PNN" "SATA6G_PCH_PCIE_UP_SATA_RXN<5>"
					( Origin gPackager )
				)
				( objectStatus "SATA6G_PCH_PCIE_UP_SATA_RXN<5>" )
			)
			( signal "@baseboard_fab2_lib.baseboard_fab2(sch_1):sata6g_pch_pcie_up_sata_rxn(6)"
				( attribute "CDS_PHYS_NET_NAME" "SATA6G_PCH_PCIE_UP_SATA_RXN<6>"
					( Origin gPackager )
				)
				( attribute "PNN" "SATA6G_PCH_PCIE_UP_SATA_RXN<6>"
					( Origin gPackager )
				)
				( objectStatus "SATA6G_PCH_PCIE_UP_SATA_RXN<6>" )
			)
			( signal "@baseboard_fab2_lib.baseboard_fab2(sch_1):sata6g_pch_pcie_up_sata_rxn(7)"
				( attribute "CDS_PHYS_NET_NAME" "SATA6G_PCH_PCIE_UP_SATA_RXN<7>"
					( Origin gPackager )
				)
				( attribute "PNN" "SATA6G_PCH_PCIE_UP_SATA_RXN<7>"
					( Origin gPackager )
				)
				( objectStatus "SATA6G_PCH_PCIE_UP_SATA_RXN<7>" )
			)
			( signal "@baseboard_fab2_lib.baseboard_fab2(sch_1):sata6g_pch_pcie_up_sata_rxp(0)"
				( attribute "CDS_PHYS_NET_NAME" "SATA6G_PCH_PCIE_UP_SATA_RXP<0>"
					( Origin gPackager )
				)
				( attribute "PNN" "SATA6G_PCH_PCIE_UP_SATA_RXP<0>"
					( Origin gPackager )
				)
				( objectStatus "SATA6G_PCH_PCIE_UP_SATA_RXP<0>" )
			)
			( signal "@baseboard_fab2_lib.baseboard_fab2(sch_1):sata6g_pch_pcie_up_sata_rxp(1)"
				( attribute "CDS_PHYS_NET_NAME" "SATA6G_PCH_PCIE_UP_SATA_RXP<1>"
					( Origin gPackager )
				)
				( attribute "PNN" "SATA6G_PCH_PCIE_UP_SATA_RXP<1>"
					( Origin gPackager )
				)
				( objectStatus "SATA6G_PCH_PCIE_UP_SATA_RXP<1>" )
			)
			( signal "@baseboard_fab2_lib.baseboard_fab2(sch_1):sata6g_pch_pcie_up_sata_rxp(2)"
				( attribute "CDS_PHYS_NET_NAME" "SATA6G_PCH_PCIE_UP_SATA_RXP<2>"
					( Origin gPackager )
				)
				( attribute "PNN" "SATA6G_PCH_PCIE_UP_SATA_RXP<2>"
					( Origin gPackager )
				)
				( objectStatus "SATA6G_PCH_PCIE_UP_SATA_RXP<2>" )
			)
			( signal "@baseboard_fab2_lib.baseboard_fab2(sch_1):sata6g_pch_pcie_up_sata_rxp(3)"
				( attribute "CDS_PHYS_NET_NAME" "SATA6G_PCH_PCIE_UP_SATA_RXP<3>"
					( Origin gPackager )
				)
				( attribute "PNN" "SATA6G_PCH_PCIE_UP_SATA_RXP<3>"
					( Origin gPackager )
				)
				( objectStatus "SATA6G_PCH_PCIE_UP_SATA_RXP<3>" )
			)
			( signal "@baseboard_fab2_lib.baseboard_fab2(sch_1):sata6g_pch_pcie_up_sata_rxp(4)"
				( attribute "CDS_PHYS_NET_NAME" "SATA6G_PCH_PCIE_UP_SATA_RXP<4>"
					( Origin gPackager )
				)
				( attribute "PNN" "SATA6G_PCH_PCIE_UP_SATA_RXP<4>"
					( Origin gPackager )
				)
				( objectStatus "SATA6G_PCH_PCIE_UP_SATA_RXP<4>" )
			)
			( signal "@baseboard_fab2_lib.baseboard_fab2(sch_1):sata6g_pch_pcie_up_sata_rxp(5)"
				( attribute "CDS_PHYS_NET_NAME" "SATA6G_PCH_PCIE_UP_SATA_RXP<5>"
					( Origin gPackager )
				)
				( attribute "PNN" "SATA6G_PCH_PCIE_UP_SATA_RXP<5>"
					( Origin gPackager )
				)
				( objectStatus "SATA6G_PCH_PCIE_UP_SATA_RXP<5>" )
			)
			( signal "@baseboard_fab2_lib.baseboard_fab2(sch_1):sata6g_pch_pcie_up_sata_rxp(6)"
				( attribute "CDS_PHYS_NET_NAME" "SATA6G_PCH_PCIE_UP_SATA_RXP<6>"
					( Origin gPackager )
				)
				( attribute "PNN" "SATA6G_PCH_PCIE_UP_SATA_RXP<6>"
					( Origin gPackager )
				)
				( objectStatus "SATA6G_PCH_PCIE_UP_SATA_RXP<6>" )
			)
			( signal "@baseboard_fab2_lib.baseboard_fab2(sch_1):sata6g_pch_pcie_up_sata_rxp(7)"
				( attribute "CDS_PHYS_NET_NAME" "SATA6G_PCH_PCIE_UP_SATA_RXP<7>"
					( Origin gPackager )
				)
				( attribute "PNN" "SATA6G_PCH_PCIE_UP_SATA_RXP<7>"
					( Origin gPackager )
				)
				( objectStatus "SATA6G_PCH_PCIE_UP_SATA_RXP<7>" )
			)
			( signal "@baseboard_fab2_lib.baseboard_fab2(sch_1):sata6g_pch_pcie_up_sata_txn(0)"
				( attribute "CDS_PHYS_NET_NAME" "SATA6G_PCH_PCIE_UP_SATA_TXN<0>"
					( Origin gPackager )
				)
				( attribute "PNN" "SATA6G_PCH_PCIE_UP_SATA_TXN<0>"
					( Origin gPackager )
				)
				( objectStatus "SATA6G_PCH_PCIE_UP_SATA_TXN<0>" )
			)
			( signal "@baseboard_fab2_lib.baseboard_fab2(sch_1):sata6g_pch_pcie_up_sata_txn(1)"
				( attribute "CDS_PHYS_NET_NAME" "SATA6G_PCH_PCIE_UP_SATA_TXN<1>"
					( Origin gPackager )
				)
				( attribute "PNN" "SATA6G_PCH_PCIE_UP_SATA_TXN<1>"
					( Origin gPackager )
				)
				( objectStatus "SATA6G_PCH_PCIE_UP_SATA_TXN<1>" )
			)
			( signal "@baseboard_fab2_lib.baseboard_fab2(sch_1):sata6g_pch_pcie_up_sata_txn(2)"
				( attribute "CDS_PHYS_NET_NAME" "SATA6G_PCH_PCIE_UP_SATA_TXN<2>"
					( Origin gPackager )
				)
				( attribute "PNN" "SATA6G_PCH_PCIE_UP_SATA_TXN<2>"
					( Origin gPackager )
				)
				( objectStatus "SATA6G_PCH_PCIE_UP_SATA_TXN<2>" )
			)
			( signal "@baseboard_fab2_lib.baseboard_fab2(sch_1):sata6g_pch_pcie_up_sata_txn(3)"
				( attribute "CDS_PHYS_NET_NAME" "SATA6G_PCH_PCIE_UP_SATA_TXN<3>"
					( Origin gPackager )
				)
				( attribute "PNN" "SATA6G_PCH_PCIE_UP_SATA_TXN<3>"
					( Origin gPackager )
				)
				( objectStatus "SATA6G_PCH_PCIE_UP_SATA_TXN<3>" )
			)
			( signal "@baseboard_fab2_lib.baseboard_fab2(sch_1):sata6g_pch_pcie_up_sata_txn(4)"
				( attribute "CDS_PHYS_NET_NAME" "SATA6G_PCH_PCIE_UP_SATA_TXN<4>"
					( Origin gPackager )
				)
				( attribute "PNN" "SATA6G_PCH_PCIE_UP_SATA_TXN<4>"
					( Origin gPackager )
				)
				( objectStatus "SATA6G_PCH_PCIE_UP_SATA_TXN<4>" )
			)
			( signal "@baseboard_fab2_lib.baseboard_fab2(sch_1):sata6g_pch_pcie_up_sata_txn(5)"
				( attribute "CDS_PHYS_NET_NAME" "SATA6G_PCH_PCIE_UP_SATA_TXN<5>"
					( Origin gPackager )
				)
				( attribute "PNN" "SATA6G_PCH_PCIE_UP_SATA_TXN<5>"
					( Origin gPackager )
				)
				( objectStatus "SATA6G_PCH_PCIE_UP_SATA_TXN<5>" )
			)
			( signal "@baseboard_fab2_lib.baseboard_fab2(sch_1):sata6g_pch_pcie_up_sata_txn(6)"
				( attribute "CDS_PHYS_NET_NAME" "SATA6G_PCH_PCIE_UP_SATA_TXN<6>"
					( Origin gPackager )
				)
				( attribute "PNN" "SATA6G_PCH_PCIE_UP_SATA_TXN<6>"
					( Origin gPackager )
				)
				( objectStatus "SATA6G_PCH_PCIE_UP_SATA_TXN<6>" )
			)
			( signal "@baseboard_fab2_lib.baseboard_fab2(sch_1):sata6g_pch_pcie_up_sata_txn(7)"
				( attribute "CDS_PHYS_NET_NAME" "SATA6G_PCH_PCIE_UP_SATA_TXN<7>"
					( Origin gPackager )
				)
				( attribute "PNN" "SATA6G_PCH_PCIE_UP_SATA_TXN<7>"
					( Origin gPackager )
				)
				( objectStatus "SATA6G_PCH_PCIE_UP_SATA_TXN<7>" )
			)
			( signal "@baseboard_fab2_lib.baseboard_fab2(sch_1):sata6g_pch_pcie_up_sata_txp(0)"
				( attribute "CDS_PHYS_NET_NAME" "SATA6G_PCH_PCIE_UP_SATA_TXP<0>"
					( Origin gPackager )
				)
				( attribute "PNN" "SATA6G_PCH_PCIE_UP_SATA_TXP<0>"
					( Origin gPackager )
				)
				( objectStatus "SATA6G_PCH_PCIE_UP_SATA_TXP<0>" )
			)
			( signal "@baseboard_fab2_lib.baseboard_fab2(sch_1):sata6g_pch_pcie_up_sata_txp(1)"
				( attribute "CDS_PHYS_NET_NAME" "SATA6G_PCH_PCIE_UP_SATA_TXP<1>"
					( Origin gPackager )
				)
				( attribute "PNN" "SATA6G_PCH_PCIE_UP_SATA_TXP<1>"
					( Origin gPackager )
				)
				( objectStatus "SATA6G_PCH_PCIE_UP_SATA_TXP<1>" )
			)
			( signal "@baseboard_fab2_lib.baseboard_fab2(sch_1):sata6g_pch_pcie_up_sata_txp(2)"
				( attribute "CDS_PHYS_NET_NAME" "SATA6G_PCH_PCIE_UP_SATA_TXP<2>"
					( Origin gPackager )
				)
				( attribute "PNN" "SATA6G_PCH_PCIE_UP_SATA_TXP<2>"
					( Origin gPackager )
				)
				( objectStatus "SATA6G_PCH_PCIE_UP_SATA_TXP<2>" )
			)
			( signal "@baseboard_fab2_lib.baseboard_fab2(sch_1):sata6g_pch_pcie_up_sata_txp(3)"
				( attribute "CDS_PHYS_NET_NAME" "SATA6G_PCH_PCIE_UP_SATA_TXP<3>"
					( Origin gPackager )
				)
				( attribute "PNN" "SATA6G_PCH_PCIE_UP_SATA_TXP<3>"
					( Origin gPackager )
				)
				( objectStatus "SATA6G_PCH_PCIE_UP_SATA_TXP<3>" )
			)
			( signal "@baseboard_fab2_lib.baseboard_fab2(sch_1):sata6g_pch_pcie_up_sata_txp(4)"
				( attribute "CDS_PHYS_NET_NAME" "SATA6G_PCH_PCIE_UP_SATA_TXP<4>"
					( Origin gPackager )
				)
				( attribute "PNN" "SATA6G_PCH_PCIE_UP_SATA_TXP<4>"
					( Origin gPackager )
				)
				( objectStatus "SATA6G_PCH_PCIE_UP_SATA_TXP<4>" )
			)
			( signal "@baseboard_fab2_lib.baseboard_fab2(sch_1):sata6g_pch_pcie_up_sata_txp(5)"
				( attribute "CDS_PHYS_NET_NAME" "SATA6G_PCH_PCIE_UP_SATA_TXP<5>"
					( Origin gPackager )
				)
				( attribute "PNN" "SATA6G_PCH_PCIE_UP_SATA_TXP<5>"
					( Origin gPackager )
				)
				( objectStatus "SATA6G_PCH_PCIE_UP_SATA_TXP<5>" )
			)
			( signal "@baseboard_fab2_lib.baseboard_fab2(sch_1):sata6g_pch_pcie_up_sata_txp(6)"
				( attribute "CDS_PHYS_NET_NAME" "SATA6G_PCH_PCIE_UP_SATA_TXP<6>"
					( Origin gPackager )
				)
				( attribute "PNN" "SATA6G_PCH_PCIE_UP_SATA_TXP<6>"
					( Origin gPackager )
				)
				( objectStatus "SATA6G_PCH_PCIE_UP_SATA_TXP<6>" )
			)
			( signal "@baseboard_fab2_lib.baseboard_fab2(sch_1):sata6g_pch_pcie_up_sata_txp(7)"
				( attribute "CDS_PHYS_NET_NAME" "SATA6G_PCH_PCIE_UP_SATA_TXP<7>"
					( Origin gPackager )
				)
				( attribute "PNN" "SATA6G_PCH_PCIE_UP_SATA_TXP<7>"
					( Origin gPackager )
				)
				( objectStatus "SATA6G_PCH_PCIE_UP_SATA_TXP<7>" )
			)
			( signal "@baseboard_fab2_lib.baseboard_fab2(sch_1):sata6g_rx_dn(0)"
				( attribute "CDS_PHYS_NET_NAME" "SATA6G_RX_DN<0>"
					( Origin gPackager )
				)
				( attribute "PNN" "SATA6G_RX_DN<0>"
					( Origin gPackager )
				)
				( objectStatus "SATA6G_RX_DN<0>" )
			)
			( signal "@baseboard_fab2_lib.baseboard_fab2(sch_1):sata6g_rx_dn(1)"
				( attribute "CDS_PHYS_NET_NAME" "SATA6G_RX_DN<1>"
					( Origin gPackager )
				)
				( attribute "PNN" "SATA6G_RX_DN<1>"
					( Origin gPackager )
				)
				( objectStatus "SATA6G_RX_DN<1>" )
			)
			( signal "@baseboard_fab2_lib.baseboard_fab2(sch_1):sata6g_rx_dn(2)"
				( attribute "CDS_PHYS_NET_NAME" "SATA6G_RX_DN<2>"
					( Origin gPackager )
				)
				( attribute "PNN" "SATA6G_RX_DN<2>"
					( Origin gPackager )
				)
				( objectStatus "SATA6G_RX_DN<2>" )
			)
			( signal "@baseboard_fab2_lib.baseboard_fab2(sch_1):sata6g_rx_dn(3)"
				( attribute "CDS_PHYS_NET_NAME" "SATA6G_RX_DN<3>"
					( Origin gPackager )
				)
				( attribute "PNN" "SATA6G_RX_DN<3>"
					( Origin gPackager )
				)
				( objectStatus "SATA6G_RX_DN<3>" )
			)
			( signal "@baseboard_fab2_lib.baseboard_fab2(sch_1):sata6g_rx_dp(0)"
				( attribute "CDS_PHYS_NET_NAME" "SATA6G_RX_DP<0>"
					( Origin gPackager )
				)
				( attribute "PNN" "SATA6G_RX_DP<0>"
					( Origin gPackager )
				)
				( objectStatus "SATA6G_RX_DP<0>" )
			)
			( signal "@baseboard_fab2_lib.baseboard_fab2(sch_1):sata6g_rx_dp(1)"
				( attribute "CDS_PHYS_NET_NAME" "SATA6G_RX_DP<1>"
					( Origin gPackager )
				)
				( attribute "PNN" "SATA6G_RX_DP<1>"
					( Origin gPackager )
				)
				( objectStatus "SATA6G_RX_DP<1>" )
			)
			( signal "@baseboard_fab2_lib.baseboard_fab2(sch_1):sata6g_rx_dp(2)"
				( attribute "CDS_PHYS_NET_NAME" "SATA6G_RX_DP<2>"
					( Origin gPackager )
				)
				( attribute "PNN" "SATA6G_RX_DP<2>"
					( Origin gPackager )
				)
				( objectStatus "SATA6G_RX_DP<2>" )
			)
			( signal "@baseboard_fab2_lib.baseboard_fab2(sch_1):sata6g_rx_dp(3)"
				( attribute "CDS_PHYS_NET_NAME" "SATA6G_RX_DP<3>"
					( Origin gPackager )
				)
				( attribute "PNN" "SATA6G_RX_DP<3>"
					( Origin gPackager )
				)
				( objectStatus "SATA6G_RX_DP<3>" )
			)
			( signal "@baseboard_fab2_lib.baseboard_fab2(sch_1):sata6g_s0_rx_dn"
				( attribute "CDS_PHYS_NET_NAME" "SATA6G_S0_RX_DN"
					( Origin gPackager )
				)
				( objectStatus "SATA6G_S0_RX_DN" )
			)
			( signal "@baseboard_fab2_lib.baseboard_fab2(sch_1):sata6g_s0_rx_dp"
				( attribute "CDS_PHYS_NET_NAME" "SATA6G_S0_RX_DP"
					( Origin gPackager )
				)
				( objectStatus "SATA6G_S0_RX_DP" )
			)
			( signal "@baseboard_fab2_lib.baseboard_fab2(sch_1):sata6g_s0_tx_dn"
				( attribute "CDS_PHYS_NET_NAME" "SATA6G_S0_TX_DN"
					( Origin gPackager )
				)
				( objectStatus "SATA6G_S0_TX_DN" )
			)
			( signal "@baseboard_fab2_lib.baseboard_fab2(sch_1):sata6g_s0_tx_dp"
				( attribute "CDS_PHYS_NET_NAME" "SATA6G_S0_TX_DP"
					( Origin gPackager )
				)
				( objectStatus "SATA6G_S0_TX_DP" )
			)
			( signal "@baseboard_fab2_lib.baseboard_fab2(sch_1):sata6g_s1_rx_dn"
				( attribute "CDS_PHYS_NET_NAME" "SATA6G_S1_RX_DN"
					( Origin gPackager )
				)
				( objectStatus "SATA6G_S1_RX_DN" )
			)
			( signal "@baseboard_fab2_lib.baseboard_fab2(sch_1):sata6g_s1_rx_dp"
				( attribute "CDS_PHYS_NET_NAME" "SATA6G_S1_RX_DP"
					( Origin gPackager )
				)
				( objectStatus "SATA6G_S1_RX_DP" )
			)
			( signal "@baseboard_fab2_lib.baseboard_fab2(sch_1):sata6g_s1_tx_dn"
				( attribute "CDS_PHYS_NET_NAME" "SATA6G_S1_TX_DN"
					( Origin gPackager )
				)
				( objectStatus "SATA6G_S1_TX_DN" )
			)
			( signal "@baseboard_fab2_lib.baseboard_fab2(sch_1):sata6g_s1_tx_dp"
				( attribute "CDS_PHYS_NET_NAME" "SATA6G_S1_TX_DP"
					( Origin gPackager )
				)
				( objectStatus "SATA6G_S1_TX_DP" )
			)
			( signal "@baseboard_fab2_lib.baseboard_fab2(sch_1):sata6g_tx_dn(0)"
				( attribute "CDS_PHYS_NET_NAME" "SATA6G_TX_DN<0>"
					( Origin gPackager )
				)
				( attribute "PNN" "SATA6G_TX_DN<0>"
					( Origin gPackager )
				)
				( objectStatus "SATA6G_TX_DN<0>" )
			)
			( signal "@baseboard_fab2_lib.baseboard_fab2(sch_1):sata6g_tx_dn(1)"
				( attribute "CDS_PHYS_NET_NAME" "SATA6G_TX_DN<1>"
					( Origin gPackager )
				)
				( attribute "PNN" "SATA6G_TX_DN<1>"
					( Origin gPackager )
				)
				( objectStatus "SATA6G_TX_DN<1>" )
			)
			( signal "@baseboard_fab2_lib.baseboard_fab2(sch_1):sata6g_tx_dn(2)"
				( attribute "CDS_PHYS_NET_NAME" "SATA6G_TX_DN<2>"
					( Origin gPackager )
				)
				( attribute "PNN" "SATA6G_TX_DN<2>"
					( Origin gPackager )
				)
				( objectStatus "SATA6G_TX_DN<2>" )
			)
			( signal "@baseboard_fab2_lib.baseboard_fab2(sch_1):sata6g_tx_dn(3)"
				( attribute "CDS_PHYS_NET_NAME" "SATA6G_TX_DN<3>"
					( Origin gPackager )
				)
				( attribute "PNN" "SATA6G_TX_DN<3>"
					( Origin gPackager )
				)
				( objectStatus "SATA6G_TX_DN<3>" )
			)
			( signal "@baseboard_fab2_lib.baseboard_fab2(sch_1):sata6g_tx_dp(0)"
				( attribute "CDS_PHYS_NET_NAME" "SATA6G_TX_DP<0>"
					( Origin gPackager )
				)
				( attribute "PNN" "SATA6G_TX_DP<0>"
					( Origin gPackager )
				)
				( objectStatus "SATA6G_TX_DP<0>" )
			)
			( signal "@baseboard_fab2_lib.baseboard_fab2(sch_1):sata6g_tx_dp(1)"
				( attribute "CDS_PHYS_NET_NAME" "SATA6G_TX_DP<1>"
					( Origin gPackager )
				)
				( attribute "PNN" "SATA6G_TX_DP<1>"
					( Origin gPackager )
				)
				( objectStatus "SATA6G_TX_DP<1>" )
			)
			( signal "@baseboard_fab2_lib.baseboard_fab2(sch_1):sata6g_tx_dp(2)"
				( attribute "CDS_PHYS_NET_NAME" "SATA6G_TX_DP<2>"
					( Origin gPackager )
				)
				( attribute "PNN" "SATA6G_TX_DP<2>"
					( Origin gPackager )
				)
				( objectStatus "SATA6G_TX_DP<2>" )
			)
			( signal "@baseboard_fab2_lib.baseboard_fab2(sch_1):sata6g_tx_dp(3)"
				( attribute "CDS_PHYS_NET_NAME" "SATA6G_TX_DP<3>"
					( Origin gPackager )
				)
				( attribute "PNN" "SATA6G_TX_DP<3>"
					( Origin gPackager )
				)
				( objectStatus "SATA6G_TX_DP<3>" )
			)
			( signal "@baseboard_fab2_lib.baseboard_fab2(sch_1):tp_pch_rsvd47"
				( attribute "CDS_PHYS_NET_NAME" "TP_PCH_RSVD47"
					( Origin gPackager )
				)
				( objectStatus "TP_PCH_RSVD47" )
			)
			( signal "@baseboard_fab2_lib.baseboard_fab2(sch_1):tp_pch_rsvd48"
				( attribute "CDS_PHYS_NET_NAME" "TP_PCH_RSVD48"
					( Origin gPackager )
				)
				( objectStatus "TP_PCH_RSVD48" )
			)
			( signal "@baseboard_fab2_lib.baseboard_fab2(sch_1):tp_pch_rsvd49"
				( attribute "CDS_PHYS_NET_NAME" "TP_PCH_RSVD49"
					( Origin gPackager )
				)
				( objectStatus "TP_PCH_RSVD49" )
			)
			( signal "@baseboard_fab2_lib.baseboard_fab2(sch_1):tp_pch_rsvd50"
				( attribute "CDS_PHYS_NET_NAME" "TP_PCH_RSVD50"
					( Origin gPackager )
				)
				( objectStatus "TP_PCH_RSVD50" )
			)
			( signal "@baseboard_fab2_lib.baseboard_fab2(sch_1):tp_pch_rsvd51"
				( attribute "CDS_PHYS_NET_NAME" "TP_PCH_RSVD51"
					( Origin gPackager )
				)
				( objectStatus "TP_PCH_RSVD51" )
			)
			( signal "@baseboard_fab2_lib.baseboard_fab2(sch_1):tp_pch_rsvd52"
				( attribute "CDS_PHYS_NET_NAME" "TP_PCH_RSVD52"
					( Origin gPackager )
				)
				( objectStatus "TP_PCH_RSVD52" )
			)
			( signal "@baseboard_fab2_lib.baseboard_fab2(sch_1):dmi_cpu0_pch_rx_dn(0)"
				( attribute "CDS_PHYS_NET_NAME" "DMI_CPU0_PCH_RX_DN<0>"
					( Origin gPackager )
				)
				( attribute "PNN" "DMI_CPU0_PCH_RX_DN<0>"
					( Origin gPackager )
				)
				( objectStatus "DMI_CPU0_PCH_RX_DN<0>" )
			)
			( signal "@baseboard_fab2_lib.baseboard_fab2(sch_1):dmi_cpu0_pch_rx_dn(1)"
				( attribute "CDS_PHYS_NET_NAME" "DMI_CPU0_PCH_RX_DN<1>"
					( Origin gPackager )
				)
				( attribute "PNN" "DMI_CPU0_PCH_RX_DN<1>"
					( Origin gPackager )
				)
				( objectStatus "DMI_CPU0_PCH_RX_DN<1>" )
			)
			( signal "@baseboard_fab2_lib.baseboard_fab2(sch_1):dmi_cpu0_pch_rx_dn(2)"
				( attribute "CDS_PHYS_NET_NAME" "DMI_CPU0_PCH_RX_DN<2>"
					( Origin gPackager )
				)
				( attribute "PNN" "DMI_CPU0_PCH_RX_DN<2>"
					( Origin gPackager )
				)
				( objectStatus "DMI_CPU0_PCH_RX_DN<2>" )
			)
			( signal "@baseboard_fab2_lib.baseboard_fab2(sch_1):dmi_cpu0_pch_rx_dn(3)"
				( attribute "CDS_PHYS_NET_NAME" "DMI_CPU0_PCH_RX_DN<3>"
					( Origin gPackager )
				)
				( attribute "PNN" "DMI_CPU0_PCH_RX_DN<3>"
					( Origin gPackager )
				)
				( objectStatus "DMI_CPU0_PCH_RX_DN<3>" )
			)
			( signal "@baseboard_fab2_lib.baseboard_fab2(sch_1):dmi_cpu0_pch_rx_dp(0)"
				( attribute "CDS_PHYS_NET_NAME" "DMI_CPU0_PCH_RX_DP<0>"
					( Origin gPackager )
				)
				( attribute "PNN" "DMI_CPU0_PCH_RX_DP<0>"
					( Origin gPackager )
				)
				( objectStatus "DMI_CPU0_PCH_RX_DP<0>" )
			)
			( signal "@baseboard_fab2_lib.baseboard_fab2(sch_1):dmi_cpu0_pch_rx_dp(1)"
				( attribute "CDS_PHYS_NET_NAME" "DMI_CPU0_PCH_RX_DP<1>"
					( Origin gPackager )
				)
				( attribute "PNN" "DMI_CPU0_PCH_RX_DP<1>"
					( Origin gPackager )
				)
				( objectStatus "DMI_CPU0_PCH_RX_DP<1>" )
			)
			( signal "@baseboard_fab2_lib.baseboard_fab2(sch_1):dmi_cpu0_pch_rx_dp(2)"
				( attribute "CDS_PHYS_NET_NAME" "DMI_CPU0_PCH_RX_DP<2>"
					( Origin gPackager )
				)
				( attribute "PNN" "DMI_CPU0_PCH_RX_DP<2>"
					( Origin gPackager )
				)
				( objectStatus "DMI_CPU0_PCH_RX_DP<2>" )
			)
			( signal "@baseboard_fab2_lib.baseboard_fab2(sch_1):dmi_cpu0_pch_rx_dp(3)"
				( attribute "CDS_PHYS_NET_NAME" "DMI_CPU0_PCH_RX_DP<3>"
					( Origin gPackager )
				)
				( attribute "PNN" "DMI_CPU0_PCH_RX_DP<3>"
					( Origin gPackager )
				)
				( objectStatus "DMI_CPU0_PCH_RX_DP<3>" )
			)
			( signal "@baseboard_fab2_lib.baseboard_fab2(sch_1):dmi_cpu0_pch_tx_c_dn(0)"
				( attribute "CDS_PHYS_NET_NAME" "DMI_CPU0_PCH_TX_C_DN<0>"
					( Origin gPackager )
				)
				( attribute "PNN" "DMI_CPU0_PCH_TX_C_DN<0>"
					( Origin gPackager )
				)
				( objectStatus "DMI_CPU0_PCH_TX_C_DN<0>" )
			)
			( signal "@baseboard_fab2_lib.baseboard_fab2(sch_1):dmi_cpu0_pch_tx_c_dn(1)"
				( attribute "CDS_PHYS_NET_NAME" "DMI_CPU0_PCH_TX_C_DN<1>"
					( Origin gPackager )
				)
				( attribute "PNN" "DMI_CPU0_PCH_TX_C_DN<1>"
					( Origin gPackager )
				)
				( objectStatus "DMI_CPU0_PCH_TX_C_DN<1>" )
			)
			( signal "@baseboard_fab2_lib.baseboard_fab2(sch_1):dmi_cpu0_pch_tx_c_dn(2)"
				( attribute "CDS_PHYS_NET_NAME" "DMI_CPU0_PCH_TX_C_DN<2>"
					( Origin gPackager )
				)
				( attribute "PNN" "DMI_CPU0_PCH_TX_C_DN<2>"
					( Origin gPackager )
				)
				( objectStatus "DMI_CPU0_PCH_TX_C_DN<2>" )
			)
			( signal "@baseboard_fab2_lib.baseboard_fab2(sch_1):dmi_cpu0_pch_tx_c_dn(3)"
				( attribute "CDS_PHYS_NET_NAME" "DMI_CPU0_PCH_TX_C_DN<3>"
					( Origin gPackager )
				)
				( attribute "PNN" "DMI_CPU0_PCH_TX_C_DN<3>"
					( Origin gPackager )
				)
				( objectStatus "DMI_CPU0_PCH_TX_C_DN<3>" )
			)
			( signal "@baseboard_fab2_lib.baseboard_fab2(sch_1):dmi_cpu0_pch_tx_c_dp(0)"
				( attribute "CDS_PHYS_NET_NAME" "DMI_CPU0_PCH_TX_C_DP<0>"
					( Origin gPackager )
				)
				( attribute "PNN" "DMI_CPU0_PCH_TX_C_DP<0>"
					( Origin gPackager )
				)
				( objectStatus "DMI_CPU0_PCH_TX_C_DP<0>" )
			)
			( signal "@baseboard_fab2_lib.baseboard_fab2(sch_1):dmi_cpu0_pch_tx_c_dp(1)"
				( attribute "CDS_PHYS_NET_NAME" "DMI_CPU0_PCH_TX_C_DP<1>"
					( Origin gPackager )
				)
				( attribute "PNN" "DMI_CPU0_PCH_TX_C_DP<1>"
					( Origin gPackager )
				)
				( objectStatus "DMI_CPU0_PCH_TX_C_DP<1>" )
			)
			( signal "@baseboard_fab2_lib.baseboard_fab2(sch_1):dmi_cpu0_pch_tx_c_dp(2)"
				( attribute "CDS_PHYS_NET_NAME" "DMI_CPU0_PCH_TX_C_DP<2>"
					( Origin gPackager )
				)
				( attribute "PNN" "DMI_CPU0_PCH_TX_C_DP<2>"
					( Origin gPackager )
				)
				( objectStatus "DMI_CPU0_PCH_TX_C_DP<2>" )
			)
			( signal "@baseboard_fab2_lib.baseboard_fab2(sch_1):dmi_cpu0_pch_tx_c_dp(3)"
				( attribute "CDS_PHYS_NET_NAME" "DMI_CPU0_PCH_TX_C_DP<3>"
					( Origin gPackager )
				)
				( attribute "PNN" "DMI_CPU0_PCH_TX_C_DP<3>"
					( Origin gPackager )
				)
				( objectStatus "DMI_CPU0_PCH_TX_C_DP<3>" )
			)
			( signal "@baseboard_fab2_lib.baseboard_fab2(sch_1):a_kr0_rbias"
				( attribute "CDS_PHYS_NET_NAME" "A_KR0_RBIAS"
					( Origin gPackager )
				)
				( objectStatus "A_KR0_RBIAS" )
			)
			( signal "@baseboard_fab2_lib.baseboard_fab2(sch_1):a_kr1_rbias"
				( attribute "CDS_PHYS_NET_NAME" "A_KR1_RBIAS"
					( Origin gPackager )
				)
				( objectStatus "A_KR1_RBIAS" )
			)
			( signal "@baseboard_fab2_lib.baseboard_fab2(sch_1):fm_10gbe_lom_disable_n"
				( attribute "CDS_PHYS_NET_NAME" "FM_10GBE_LOM_DISABLE_N"
					( Origin gPackager )
				)
				( objectStatus "FM_10GBE_LOM_DISABLE_N" )
			)
			( signal "@baseboard_fab2_lib.baseboard_fab2(sch_1):fm_1gb_lom_disable_n"
				( attribute "CDS_PHYS_NET_NAME" "FM_1GB_LOM_DISABLE_N"
					( Origin gPackager )
				)
				( objectStatus "FM_1GB_LOM_DISABLE_N" )
			)
			( signal "@baseboard_fab2_lib.baseboard_fab2(sch_1):fm_battery_sense_en_n"
				( attribute "CDS_PHYS_NET_NAME" "FM_BATTERY_SENSE_EN_N"
					( Origin gPackager )
				)
				( attribute "PHYS_NET_NAME" "FM_BATTERY_SENSE_EN_N"
					( Origin gPackager )
				)
				( objectStatus "FM_BATTERY_SENSE_EN_N" )
			)
			( signal "@baseboard_fab2_lib.baseboard_fab2(sch_1):fm_bmc_cpld_mp_rst_n"
				( attribute "CDS_PHYS_NET_NAME" "FM_BMC_CPLD_MP_RST_N"
					( Origin gPackager )
				)
				( attribute "PHYS_NET_NAME" "FM_BMC_CPLD_MP_RST_N"
					( Origin gPackager )
				)
				( objectStatus "FM_BMC_CPLD_MP_RST_N" )
			)
			( signal "@baseboard_fab2_lib.baseboard_fab2(sch_1):page148_p1v2_aux_bmc"
				( objectFlag fObjectAlias )
				( objectStatus "page148_p1v2_aux_bmc" )
			)
			( signal "@baseboard_fab2_lib.baseboard_fab2(sch_1):fm_gbe_lom_disable_n"
				( attribute "CDS_PHYS_NET_NAME" "FM_GBE_LOM_DISABLE_N"
					( Origin gPackager )
				)
				( objectStatus "FM_GBE_LOM_DISABLE_N" )
			)
			( signal "@baseboard_fab2_lib.baseboard_fab2(sch_1):fm_pch_lvc1_thermtrip_n"
				( attribute "CDS_PHYS_NET_NAME" "FM_PCH_LVC1_THERMTRIP_N"
					( Origin gPackager )
				)
				( objectStatus "FM_PCH_LVC1_THERMTRIP_N" )
			)
			( signal "@baseboard_fab2_lib.baseboard_fab2(sch_1):fm_pch_pwrbtn_n"
				( attribute "CDS_PHYS_NET_NAME" "FM_PCH_PWRBTN_N"
					( Origin gPackager )
				)
				( objectStatus "FM_PCH_PWRBTN_N" )
			)
			( signal "@baseboard_fab2_lib.baseboard_fab2(sch_1):fm_slp_sus_n"
				( attribute "CDS_PHYS_NET_NAME" "FM_SLP_SUS_N"
					( Origin gPackager )
				)
				( objectStatus "FM_SLP_SUS_N" )
			)
			( signal "@baseboard_fab2_lib.baseboard_fab2(sch_1):fm_slps3_n"
				( attribute "CDS_PHYS_NET_NAME" "FM_SLPS3_N"
					( Origin gPackager )
				)
				( objectStatus "FM_SLPS3_N" )
			)
			( signal "@baseboard_fab2_lib.baseboard_fab2(sch_1):fm_slps4_n"
				( attribute "CDS_PHYS_NET_NAME" "FM_SLPS4_N"
					( Origin gPackager )
				)
				( objectStatus "FM_SLPS4_N" )
			)
			( signal "@baseboard_fab2_lib.baseboard_fab2(sch_1):h_pm_sync1_gtl_r"
				( attribute "CDS_PHYS_NET_NAME" "H_PM_SYNC1_GTL_R"
					( Origin gPackager )
				)
				( objectStatus "H_PM_SYNC1_GTL_R" )
			)
			( signal "@baseboard_fab2_lib.baseboard_fab2(sch_1):irq_lvc3_wake_n"
				( attribute "CDS_PHYS_NET_NAME" "IRQ_LVC3_WAKE_N"
					( Origin gPackager )
				)
				( objectStatus "IRQ_LVC3_WAKE_N" )
			)
			( signal "@baseboard_fab2_lib.baseboard_fab2(sch_1):irq_sml1_pmbus_alert_n"
				( attribute "CDS_PHYS_NET_NAME" "IRQ_SML1_PMBUS_ALERT_N"
					( Origin gPackager )
				)
				( attribute "PHYS_NET_NAME" "IRQ_SML1_PMBUS_ALERT_N"
					( Origin gPackager )
				)
				( objectStatus "IRQ_SML1_PMBUS_ALERT_N" )
			)
			( signal "@baseboard_fab2_lib.baseboard_fab2(sch_1):kr_p0_ocp_rx_c_dn"
				( attribute "CDS_PHYS_NET_NAME" "KR_P0_OCP_RX_C_DN"
					( Origin gPackager )
				)
				( objectStatus "KR_P0_OCP_RX_C_DN" )
			)
			( signal "@baseboard_fab2_lib.baseboard_fab2(sch_1):kr_p0_ocp_rx_c_dp"
				( attribute "CDS_PHYS_NET_NAME" "KR_P0_OCP_RX_C_DP"
					( Origin gPackager )
				)
				( objectStatus "KR_P0_OCP_RX_C_DP" )
			)
			( signal "@baseboard_fab2_lib.baseboard_fab2(sch_1):kr_p0_ocp_tx_dn"
				( attribute "CDS_PHYS_NET_NAME" "KR_P0_OCP_TX_DN"
					( Origin gPackager )
				)
				( objectStatus "KR_P0_OCP_TX_DN" )
			)
			( signal "@baseboard_fab2_lib.baseboard_fab2(sch_1):kr_p0_ocp_tx_dp"
				( attribute "CDS_PHYS_NET_NAME" "KR_P0_OCP_TX_DP"
					( Origin gPackager )
				)
				( objectStatus "KR_P0_OCP_TX_DP" )
			)
			( signal "@baseboard_fab2_lib.baseboard_fab2(sch_1):kr_p1_ocp_rx_c_dn"
				( attribute "CDS_PHYS_NET_NAME" "KR_P1_OCP_RX_C_DN"
					( Origin gPackager )
				)
				( objectStatus "KR_P1_OCP_RX_C_DN" )
			)
			( signal "@baseboard_fab2_lib.baseboard_fab2(sch_1):kr_p1_ocp_rx_c_dp"
				( attribute "CDS_PHYS_NET_NAME" "KR_P1_OCP_RX_C_DP"
					( Origin gPackager )
				)
				( objectStatus "KR_P1_OCP_RX_C_DP" )
			)
			( signal "@baseboard_fab2_lib.baseboard_fab2(sch_1):kr_p1_ocp_tx_dn"
				( attribute "CDS_PHYS_NET_NAME" "KR_P1_OCP_TX_DN"
					( Origin gPackager )
				)
				( objectStatus "KR_P1_OCP_TX_DN" )
			)
			( signal "@baseboard_fab2_lib.baseboard_fab2(sch_1):kr_p1_ocp_tx_dp"
				( attribute "CDS_PHYS_NET_NAME" "KR_P1_OCP_TX_DP"
					( Origin gPackager )
				)
				( objectStatus "KR_P1_OCP_TX_DP" )
			)
			( signal "@baseboard_fab2_lib.baseboard_fab2(sch_1):kr_p2_ocp_rx_c_dn"
				( attribute "CDS_PHYS_NET_NAME" "KR_P2_OCP_RX_C_DN"
					( Origin gPackager )
				)
				( objectStatus "KR_P2_OCP_RX_C_DN" )
			)
			( signal "@baseboard_fab2_lib.baseboard_fab2(sch_1):kr_p2_ocp_rx_c_dp"
				( attribute "CDS_PHYS_NET_NAME" "KR_P2_OCP_RX_C_DP"
					( Origin gPackager )
				)
				( objectStatus "KR_P2_OCP_RX_C_DP" )
			)
			( signal "@baseboard_fab2_lib.baseboard_fab2(sch_1):kr_p2_ocp_tx_dn"
				( attribute "CDS_PHYS_NET_NAME" "KR_P2_OCP_TX_DN"
					( Origin gPackager )
				)
				( objectStatus "KR_P2_OCP_TX_DN" )
			)
			( signal "@baseboard_fab2_lib.baseboard_fab2(sch_1):kr_p2_ocp_tx_dp"
				( attribute "CDS_PHYS_NET_NAME" "KR_P2_OCP_TX_DP"
					( Origin gPackager )
				)
				( objectStatus "KR_P2_OCP_TX_DP" )
			)
			( signal "@baseboard_fab2_lib.baseboard_fab2(sch_1):kr_p3_ocp_rx_c_dn"
				( attribute "CDS_PHYS_NET_NAME" "KR_P3_OCP_RX_C_DN"
					( Origin gPackager )
				)
				( objectStatus "KR_P3_OCP_RX_C_DN" )
			)
			( signal "@baseboard_fab2_lib.baseboard_fab2(sch_1):kr_p3_ocp_rx_c_dp"
				( attribute "CDS_PHYS_NET_NAME" "KR_P3_OCP_RX_C_DP"
					( Origin gPackager )
				)
				( objectStatus "KR_P3_OCP_RX_C_DP" )
			)
			( signal "@baseboard_fab2_lib.baseboard_fab2(sch_1):kr_p3_ocp_tx_dn"
				( attribute "CDS_PHYS_NET_NAME" "KR_P3_OCP_TX_DN"
					( Origin gPackager )
				)
				( objectStatus "KR_P3_OCP_TX_DN" )
			)
			( signal "@baseboard_fab2_lib.baseboard_fab2(sch_1):kr_p3_ocp_tx_dp"
				( attribute "CDS_PHYS_NET_NAME" "KR_P3_OCP_TX_DP"
					( Origin gPackager )
				)
				( objectStatus "KR_P3_OCP_TX_DP" )
			)
			( signal "@baseboard_fab2_lib.baseboard_fab2(sch_1):p1v05_pch_stby_kr_pll"
				( alias ( signalRef "@baseboard_fab2_lib.baseboard_fab2(sch_1):page118_p1v05_pch_stby_kr_pll") )
				( alias ( signalRef "@baseboard_fab2_lib.baseboard_fab2(sch_1):page122_p1v05_pch_stby_kr_pll") )
				( alias ( signalRef "@baseboard_fab2_lib.baseboard_fab2(sch_1):page127_p1v05_pch_stby_kr_pll") )
				( attribute "VOLTAGE" "1.05V"
					( Units "uVoltage" "V" 1.000000)
					( Status sAliasFlattened )
					( Origin gFrontEnd )
				)
				( attribute "CDS_PHYS_NET_NAME" "P1V05_PCH_STBY_KR_PLL"
					( Origin gPackager )
				)
				( objectStatus "P1V05_PCH_STBY_KR_PLL" )
			)
			( signal "@baseboard_fab2_lib.baseboard_fab2(sch_1):page118_p1v05_pch_stby_kr_pll"
				( attribute "VOLTAGE" "1.05V"
					( Units "uVoltage" "V" 1.000000)
					( Origin gFrontEnd )
				)
				( objectFlag fObjectAlias )
				( objectStatus "page118_p1v05_pch_stby_kr_pll" )
			)
			( signal "@baseboard_fab2_lib.baseboard_fab2(sch_1):page122_p1v05_pch_stby_kr_pll"
				( attribute "VOLTAGE" "1.05V"
					( Units "uVoltage" "V" 1.000000)
					( Origin gFrontEnd )
				)
				( objectFlag fObjectAlias )
				( objectStatus "page122_p1v05_pch_stby_kr_pll" )
			)
			( signal "@baseboard_fab2_lib.baseboard_fab2(sch_1):page127_p1v05_pch_stby_kr_pll"
				( attribute "VOLTAGE" "1.05V"
					( Units "uVoltage" "V" 1.000000)
					( Origin gFrontEnd )
				)
				( objectFlag fObjectAlias )
				( objectStatus "page127_p1v05_pch_stby_kr_pll" )
			)
			( signal "@baseboard_fab2_lib.baseboard_fab2(sch_1):peci_pch"
				( attribute "CDS_PHYS_NET_NAME" "PECI_PCH"
					( Origin gPackager )
				)
				( objectStatus "PECI_PCH" )
			)
			( signal "@baseboard_fab2_lib.baseboard_fab2(sch_1):pwrgd_dsw_pwrok"
				( attribute "CDS_PHYS_NET_NAME" "PWRGD_DSW_PWROK"
					( Origin gPackager )
				)
				( objectStatus "PWRGD_DSW_PWROK" )
			)
			( signal "@baseboard_fab2_lib.baseboard_fab2(sch_1):pwrgd_pch_pwrok"
				( attribute "CDS_PHYS_NET_NAME" "PWRGD_PCH_PWROK"
					( Origin gPackager )
				)
				( attribute "PHYS_NET_NAME" "PWRGD_PCH_PWROK"
					( Origin gPackager )
				)
				( objectStatus "PWRGD_PCH_PWROK" )
			)
			( signal "@baseboard_fab2_lib.baseboard_fab2(sch_1):pwrgd_pvccio_cpu0"
				( attribute "CDS_PHYS_NET_NAME" "PWRGD_PVCCIO_CPU0"
					( Origin gPackager )
				)
				( objectStatus "PWRGD_PVCCIO_CPU0" )
			)
			( signal "@baseboard_fab2_lib.baseboard_fab2(sch_1):pwrgd_sys_pwrok"
				( attribute "CDS_PHYS_NET_NAME" "PWRGD_SYS_PWROK"
					( Origin gPackager )
				)
				( attribute "PHYS_NET_NAME" "PWRGD_SYS_PWROK"
					( Origin gPackager )
				)
				( objectStatus "PWRGD_SYS_PWROK" )
			)
			( signal "@baseboard_fab2_lib.baseboard_fab2(sch_1):rst_bmc_srst_n"
				( attribute "CDS_PHYS_NET_NAME" "RST_BMC_SRST_N"
					( Origin gPackager )
				)
				( attribute "PHYS_NET_NAME" "RST_BMC_SRST_N"
					( Origin gPackager )
				)
				( objectStatus "RST_BMC_SRST_N" )
			)
			( signal "@baseboard_fab2_lib.baseboard_fab2(sch_1):rst_bmc_srst_r_n"
				( attribute "CDS_PHYS_NET_NAME" "RST_BMC_SRST_R_N"
					( Origin gPackager )
				)
				( objectStatus "RST_BMC_SRST_R_N" )
			)
			( signal "@baseboard_fab2_lib.baseboard_fab2(sch_1):rst_bmc_sysrst_btn_out_b_n"
				( attribute "CDS_PHYS_NET_NAME" "RST_BMC_SYSRST_BTN_OUT_B_N"
					( Origin gPackager )
				)
				( objectStatus "RST_BMC_SYSRST_BTN_OUT_B_N" )
			)
			( signal "@baseboard_fab2_lib.baseboard_fab2(sch_1):tp_10gbe_kr0_mon_dn"
				( attribute "CDS_PHYS_NET_NAME" "TP_10GBE_KR0_MON_DN"
					( Origin gPackager )
				)
				( objectStatus "TP_10GBE_KR0_MON_DN" )
			)
			( signal "@baseboard_fab2_lib.baseboard_fab2(sch_1):tp_10gbe_kr0_mon_dp"
				( attribute "CDS_PHYS_NET_NAME" "TP_10GBE_KR0_MON_DP"
					( Origin gPackager )
				)
				( objectStatus "TP_10GBE_KR0_MON_DP" )
			)
			( signal "@baseboard_fab2_lib.baseboard_fab2(sch_1):tp_10gbe_kr1_mon_dn"
				( attribute "CDS_PHYS_NET_NAME" "TP_10GBE_KR1_MON_DN"
					( Origin gPackager )
				)
				( objectStatus "TP_10GBE_KR1_MON_DN" )
			)
			( signal "@baseboard_fab2_lib.baseboard_fab2(sch_1):tp_10gbe_kr1_mon_dp"
				( attribute "CDS_PHYS_NET_NAME" "TP_10GBE_KR1_MON_DP"
					( Origin gPackager )
				)
				( objectStatus "TP_10GBE_KR1_MON_DP" )
			)
			( signal "@baseboard_fab2_lib.baseboard_fab2(sch_1):tp_cpu_pch_trigger_in"
				( attribute "CDS_PHYS_NET_NAME" "TP_CPU_PCH_TRIGGER_IN"
					( Origin gPackager )
				)
				( objectStatus "TP_CPU_PCH_TRIGGER_IN" )
			)
			( signal "@baseboard_fab2_lib.baseboard_fab2(sch_1):tp_cpu_pch_trigger_out"
				( attribute "CDS_PHYS_NET_NAME" "TP_CPU_PCH_TRIGGER_OUT"
					( Origin gPackager )
				)
				( objectStatus "TP_CPU_PCH_TRIGGER_OUT" )
			)
			( signal "@baseboard_fab2_lib.baseboard_fab2(sch_1):tp_pch_rsvd32"
				( attribute "CDS_PHYS_NET_NAME" "TP_PCH_RSVD32"
					( Origin gPackager )
				)
				( objectStatus "TP_PCH_RSVD32" )
			)
			( signal "@baseboard_fab2_lib.baseboard_fab2(sch_1):tp_pch_rsvd33"
				( attribute "CDS_PHYS_NET_NAME" "TP_PCH_RSVD33"
					( Origin gPackager )
				)
				( objectStatus "TP_PCH_RSVD33" )
			)
			( signal "@baseboard_fab2_lib.baseboard_fab2(sch_1):tp_pch_rsvd34"
				( attribute "CDS_PHYS_NET_NAME" "TP_PCH_RSVD34"
					( Origin gPackager )
				)
				( objectStatus "TP_PCH_RSVD34" )
			)
			( signal "@baseboard_fab2_lib.baseboard_fab2(sch_1):tp_pch_rsvd35"
				( attribute "CDS_PHYS_NET_NAME" "TP_PCH_RSVD35"
					( Origin gPackager )
				)
				( objectStatus "TP_PCH_RSVD35" )
			)
			( signal "@baseboard_fab2_lib.baseboard_fab2(sch_1):tp_pch_rsvd36"
				( attribute "CDS_PHYS_NET_NAME" "TP_PCH_RSVD36"
					( Origin gPackager )
				)
				( objectStatus "TP_PCH_RSVD36" )
			)
			( signal "@baseboard_fab2_lib.baseboard_fab2(sch_1):tp_pch_rsvd37"
				( attribute "CDS_PHYS_NET_NAME" "TP_PCH_RSVD37"
					( Origin gPackager )
				)
				( objectStatus "TP_PCH_RSVD37" )
			)
			( signal "@baseboard_fab2_lib.baseboard_fab2(sch_1):tp_pch_rsvd38"
				( attribute "CDS_PHYS_NET_NAME" "TP_PCH_RSVD38"
					( Origin gPackager )
				)
				( objectStatus "TP_PCH_RSVD38" )
			)
			( signal "@baseboard_fab2_lib.baseboard_fab2(sch_1):tp_pch_rsvd41"
				( attribute "CDS_PHYS_NET_NAME" "TP_PCH_RSVD41"
					( Origin gPackager )
				)
				( objectStatus "TP_PCH_RSVD41" )
			)
			( signal "@baseboard_fab2_lib.baseboard_fab2(sch_1):tp_pch_rsvd42"
				( attribute "CDS_PHYS_NET_NAME" "TP_PCH_RSVD42"
					( Origin gPackager )
				)
				( objectStatus "TP_PCH_RSVD42" )
			)
			( signal "@baseboard_fab2_lib.baseboard_fab2(sch_1):tp_pch_rsvd45"
				( attribute "CDS_PHYS_NET_NAME" "TP_PCH_RSVD45"
					( Origin gPackager )
				)
				( objectStatus "TP_PCH_RSVD45" )
			)
			( signal "@baseboard_fab2_lib.baseboard_fab2(sch_1):tp_pch_rsvd53"
				( attribute "CDS_PHYS_NET_NAME" "TP_PCH_RSVD53"
					( Origin gPackager )
				)
				( objectStatus "TP_PCH_RSVD53" )
			)
			( signal "@baseboard_fab2_lib.baseboard_fab2(sch_1):tp_pch_rsvd54"
				( attribute "CDS_PHYS_NET_NAME" "TP_PCH_RSVD54"
					( Origin gPackager )
				)
				( objectStatus "TP_PCH_RSVD54" )
			)
			( signal "@baseboard_fab2_lib.baseboard_fab2(sch_1):tp_pltrst_cpu_n"
				( attribute "CDS_PHYS_NET_NAME" "TP_PLTRST_CPU_N"
					( Origin gPackager )
				)
				( objectStatus "TP_PLTRST_CPU_N" )
			)
			( signal "@baseboard_fab2_lib.baseboard_fab2(sch_1):tp_pm_sync_gtl"
				( attribute "CDS_PHYS_NET_NAME" "TP_PM_SYNC_GTL"
					( Origin gPackager )
				)
				( objectStatus "TP_PM_SYNC_GTL" )
			)
			( signal "@baseboard_fab2_lib.baseboard_fab2(sch_1):tp_slp_lan_n"
				( attribute "CDS_PHYS_NET_NAME" "TP_SLP_LAN_N"
					( Origin gPackager )
				)
				( objectStatus "TP_SLP_LAN_N" )
			)
			( signal "@baseboard_fab2_lib.baseboard_fab2(sch_1):xdp_pch_pwr_debug_n"
				( attribute "CDS_PHYS_NET_NAME" "XDP_PCH_PWR_DEBUG_N"
					( Origin gPackager )
				)
				( objectStatus "XDP_PCH_PWR_DEBUG_N" )
			)
			( signal "@baseboard_fab2_lib.baseboard_fab2(sch_1):xtal_kr_25m_in"
				( attribute "CDS_PHYS_NET_NAME" "XTAL_KR_25M_IN"
					( Origin gPackager )
				)
				( objectStatus "XTAL_KR_25M_IN" )
			)
			( signal "@baseboard_fab2_lib.baseboard_fab2(sch_1):xtal_kr_25m_out"
				( attribute "CDS_PHYS_NET_NAME" "XTAL_KR_25M_OUT"
					( Origin gPackager )
				)
				( objectStatus "XTAL_KR_25M_OUT" )
			)
			( signal "@baseboard_fab2_lib.baseboard_fab2(sch_1):clk_24m_bmc_lpc"
				( attribute "CDS_PHYS_NET_NAME" "CLK_24M_BMC_LPC"
					( Origin gPackager )
				)
				( objectStatus "CLK_24M_BMC_LPC" )
			)
			( signal "@baseboard_fab2_lib.baseboard_fab2(sch_1):clk_24m_bmc_lpc_r"
				( attribute "CDS_PHYS_NET_NAME" "CLK_24M_BMC_LPC_R"
					( Origin gPackager )
				)
				( objectStatus "CLK_24M_BMC_LPC_R" )
			)
			( signal "@baseboard_fab2_lib.baseboard_fab2(sch_1):fm_adr_mode_sel"
				( attribute "CDS_PHYS_NET_NAME" "FM_ADR_MODE_SEL"
					( Origin gPackager )
				)
				( objectStatus "FM_ADR_MODE_SEL" )
			)
			( signal "@baseboard_fab2_lib.baseboard_fab2(sch_1):fm_adr_mode_sel_r"
				( attribute "CDS_PHYS_NET_NAME" "FM_ADR_MODE_SEL_R"
					( Origin gPackager )
				)
				( objectStatus "FM_ADR_MODE_SEL_R" )
			)
			( signal "@baseboard_fab2_lib.baseboard_fab2(sch_1):fm_bb_bmc_mp_gpio"
				( attribute "CDS_PHYS_NET_NAME" "FM_BB_BMC_MP_GPIO"
					( Origin gPackager )
				)
				( attribute "PHYS_NET_NAME" "FM_BB_BMC_MP_GPIO"
					( Origin gPackager )
				)
				( objectStatus "FM_BB_BMC_MP_GPIO" )
			)
			( signal "@baseboard_fab2_lib.baseboard_fab2(sch_1):page144_fm_fast_prochot_en_n"
				( attribute "CDS_PHYS_NET_NAME" "FM_FAST_PROCHOT_EN_N"
					( Origin gPackager )
				)
				( objectFlag fObjectAlias )
				( objectStatus "page144_fm_fast_prochot_en_n" )
			)
			( signal "@baseboard_fab2_lib.baseboard_fab2(sch_1):page147_p3v3_stby_bmc_adcvrefp"
				( attribute "VOLTAGE" "+3.3V"
					( Units "uVoltage" "V" 1.000000)
					( Origin gFrontEnd )
				)
				( objectFlag fObjectAlias )
				( objectStatus "page147_p3v3_stby_bmc_adcvrefp" )
			)
			( signal "@baseboard_fab2_lib.baseboard_fab2(sch_1):fm_bios_post_cmplt_n"
				( attribute "CDS_PHYS_NET_NAME" "FM_BIOS_POST_CMPLT_N"
					( Origin gPackager )
				)
				( attribute "PHYS_NET_NAME" "FM_BIOS_POST_CMPLT_N"
					( Origin gPackager )
				)
				( objectStatus "FM_BIOS_POST_CMPLT_N" )
			)
			( signal "@baseboard_fab2_lib.baseboard_fab2(sch_1):fm_bios_prefrb2_good"
				( attribute "CDS_PHYS_NET_NAME" "FM_BIOS_PREFRB2_GOOD"
					( Origin gPackager )
				)
				( attribute "PHYS_NET_NAME" "FM_BIOS_PREFRB2_GOOD"
					( Origin gPackager )
				)
				( objectStatus "FM_BIOS_PREFRB2_GOOD" )
			)
			( signal "@baseboard_fab2_lib.baseboard_fab2(sch_1):fm_bios_top_swap_spkr"
				( attribute "CDS_PHYS_NET_NAME" "FM_BIOS_TOP_SWAP_SPKR"
					( Origin gPackager )
				)
				( objectStatus "FM_BIOS_TOP_SWAP_SPKR" )
			)
			( signal "@baseboard_fab2_lib.baseboard_fab2(sch_1):fm_bmc_cpld_gpo"
				( alias ( signalRef "@baseboard_fab2_lib.baseboard_fab2(sch_1):page144_fm_bmc_cpld_gpo") )
				( attribute "CDS_PHYS_NET_NAME" "FM_BMC_CPLD_GPO"
					( Origin gPackager )
				)
				( attribute "PHYS_NET_NAME" "FM_BMC_CPLD_GPO"
					( Origin gPackager )
				)
				( objectStatus "FM_BMC_CPLD_GPO" )
			)
			( signal "@baseboard_fab2_lib.baseboard_fab2(sch_1):page144_fm_bmc_cpld_gpo"
				( attribute "CDS_PHYS_NET_NAME" "FM_BMC_CPLD_GPO"
					( Origin gPackager )
				)
				( attribute "PHYS_NET_NAME" "FM_BMC_CPLD_GPO"
					( Origin gFrontEnd )
				)
				( objectFlag fObjectAlias )
				( objectStatus "page144_fm_bmc_cpld_gpo" )
			)
			( signal "@baseboard_fab2_lib.baseboard_fab2(sch_1):fm_bmc_enable_n"
				( alias ( signalRef "@baseboard_fab2_lib.baseboard_fab2(sch_1):page143_fm_bmc_enable_n") )
				( attribute "CDS_PHYS_NET_NAME" "FM_BMC_ENABLE_N"
					( Origin gPackager )
				)
				( objectStatus "FM_BMC_ENABLE_N" )
			)
			( signal "@baseboard_fab2_lib.baseboard_fab2(sch_1):page143_fm_bmc_enable_n"
				( objectFlag fObjectAlias )
				( objectStatus "page143_fm_bmc_enable_n" )
			)
			( signal "@baseboard_fab2_lib.baseboard_fab2(sch_1):fm_bmc_fault_led_n"
				( attribute "CDS_PHYS_NET_NAME" "FM_BMC_FAULT_LED_N"
					( Origin gPackager )
				)
				( attribute "PHYS_NET_NAME" "FM_BMC_FAULT_LED_N"
					( Origin gPackager )
				)
				( objectStatus "FM_BMC_FAULT_LED_N" )
			)
			( signal "@baseboard_fab2_lib.baseboard_fab2(sch_1):fm_bmc_heartbeat_n"
				( attribute "CDS_PHYS_NET_NAME" "FM_BMC_HEARTBEAT_N"
					( Origin gPackager )
				)
				( objectStatus "FM_BMC_HEARTBEAT_N" )
			)
			( signal "@baseboard_fab2_lib.baseboard_fab2(sch_1):fm_bmc_ready_n"
				( attribute "CDS_PHYS_NET_NAME" "FM_BMC_READY_N"
					( Origin gPackager )
				)
				( attribute "PHYS_NET_NAME" "FM_BMC_READY_N"
					( Origin gPackager )
				)
				( objectStatus "FM_BMC_READY_N" )
			)
			( signal "@baseboard_fab2_lib.baseboard_fab2(sch_1):fm_board_rev_id0"
				( attribute "CDS_PHYS_NET_NAME" "FM_BOARD_REV_ID0"
					( Origin gPackager )
				)
				( attribute "PHYS_NET_NAME" "FM_BOARD_REV_ID0"
					( Origin gPackager )
				)
				( objectStatus "FM_BOARD_REV_ID0" )
			)
			( signal "@baseboard_fab2_lib.baseboard_fab2(sch_1):page148_vcc_a_1v1"
				( objectFlag fObjectAlias )
				( objectStatus "page148_vcc_a_1v1" )
			)
			( signal "@baseboard_fab2_lib.baseboard_fab2(sch_1):fm_board_rev_id1"
				( attribute "CDS_PHYS_NET_NAME" "FM_BOARD_REV_ID1"
					( Origin gPackager )
				)
				( attribute "PHYS_NET_NAME" "FM_BOARD_REV_ID1"
					( Origin gPackager )
				)
				( objectStatus "FM_BOARD_REV_ID1" )
			)
			( signal "@baseboard_fab2_lib.baseboard_fab2(sch_1):page148_vcc_d_3v3"
				( objectFlag fObjectAlias )
				( objectStatus "page148_vcc_d_3v3" )
			)
			( signal "@baseboard_fab2_lib.baseboard_fab2(sch_1):fm_board_rev_id2"
				( attribute "CDS_PHYS_NET_NAME" "FM_BOARD_REV_ID2"
					( Origin gPackager )
				)
				( attribute "PHYS_NET_NAME" "FM_BOARD_REV_ID2"
					( Origin gPackager )
				)
				( objectStatus "FM_BOARD_REV_ID2" )
			)
			( signal "@baseboard_fab2_lib.baseboard_fab2(sch_1):page148_vcc_d_pll_3v3"
				( objectFlag fObjectAlias )
				( objectStatus "page148_vcc_d_pll_3v3" )
			)
			( signal "@baseboard_fab2_lib.baseboard_fab2(sch_1):fm_cpld_bmc_pwrdn_n"
				( alias ( signalRef "@baseboard_fab2_lib.baseboard_fab2(sch_1):page147_fm_cpld_bmc_pwrdn_n") )
				( attribute "CDS_PHYS_NET_NAME" "FM_CPLD_BMC_PWRDN_N"
					( Origin gPackager )
				)
				( objectStatus "FM_CPLD_BMC_PWRDN_N" )
			)
			( signal "@baseboard_fab2_lib.baseboard_fab2(sch_1):smb_ie_3v3aux_sda"
				( attribute "CDS_PHYS_NET_NAME" "SMB_IE_3V3AUX_SDA"
					( Origin gPackager )
				)
				( objectStatus "SMB_IE_3V3AUX_SDA" )
			)
			( signal "@baseboard_fab2_lib.baseboard_fab2(sch_1):fm_cpu0_thermtrip_latch_lvt3_n"
				( attribute "CDS_PHYS_NET_NAME" "FM_CPU0_THERMTRIP_LATCH_LVT3_N"
					( Origin gPackager )
				)
				( objectStatus "FM_CPU0_THERMTRIP_LATCH_LVT3_N" )
			)
			( signal "@baseboard_fab2_lib.baseboard_fab2(sch_1):fm_cpu1_rc_en"
				( attribute "CDS_PHYS_NET_NAME" "FM_CPU1_RC_EN"
					( Origin gPackager )
				)
				( objectStatus "FM_CPU1_RC_EN" )
			)
			( signal "@baseboard_fab2_lib.baseboard_fab2(sch_1):fm_cpu_bmc_init"
				( alias ( signalRef "@baseboard_fab2_lib.baseboard_fab2(sch_1):page144_fm_cpu_bmc_init") )
				( attribute "CDS_PHYS_NET_NAME" "FM_CPU_BMC_INIT"
					( Origin gPackager )
				)
				( objectStatus "FM_CPU_BMC_INIT" )
			)
			( signal "@baseboard_fab2_lib.baseboard_fab2(sch_1):page144_fm_cpu_bmc_init"
				( attribute "CDS_PHYS_NET_NAME" "FM_CPU_BMC_INIT"
					( Origin gPackager )
				)
				( objectFlag fObjectAlias )
				( objectStatus "page144_fm_cpu_bmc_init" )
			)
			( signal "@baseboard_fab2_lib.baseboard_fab2(sch_1):fm_cpu_caterr_dly_lvt3_n"
				( attribute "CDS_PHYS_NET_NAME" "FM_CPU_CATERR_DLY_LVT3_N"
					( Origin gPackager )
				)
				( objectStatus "FM_CPU_CATERR_DLY_LVT3_N" )
			)
			( signal "@baseboard_fab2_lib.baseboard_fab2(sch_1):fm_cpu_caterr_dly_lvt3_r_n"
				( attribute "CDS_PHYS_NET_NAME" "FM_CPU_CATERR_DLY_LVT3_R_N"
					( Origin gPackager )
				)
				( objectStatus "FM_CPU_CATERR_DLY_LVT3_R_N" )
			)
			( signal "@baseboard_fab2_lib.baseboard_fab2(sch_1):fm_fast_prochot_en_n"
				( alias ( signalRef "@baseboard_fab2_lib.baseboard_fab2(sch_1):page144_fm_fast_prochot_en_n") )
				( attribute "CDS_PHYS_NET_NAME" "FM_FAST_PROCHOT_EN_N"
					( Origin gPackager )
				)
				( objectStatus "FM_FAST_PROCHOT_EN_N" )
			)
			( signal "@baseboard_fab2_lib.baseboard_fab2(sch_1):fm_global_rst_warn_n"
				( attribute "CDS_PHYS_NET_NAME" "FM_GLOBAL_RST_WARN_N"
					( Origin gPackager )
				)
				( objectStatus "FM_GLOBAL_RST_WARN_N" )
			)
			( signal "@baseboard_fab2_lib.baseboard_fab2(sch_1):fm_mb_slot_id0"
				( attribute "CDS_PHYS_NET_NAME" "FM_MB_SLOT_ID0"
					( Origin gPackager )
				)
				( attribute "PHYS_NET_NAME" "FM_MB_SLOT_ID0"
					( Origin gPackager )
				)
				( objectStatus "FM_MB_SLOT_ID0" )
			)
			( signal "@baseboard_fab2_lib.baseboard_fab2(sch_1):fm_mb_slot_id1"
				( attribute "CDS_PHYS_NET_NAME" "FM_MB_SLOT_ID1"
					( Origin gPackager )
				)
				( attribute "PHYS_NET_NAME" "FM_MB_SLOT_ID1"
					( Origin gPackager )
				)
				( objectStatus "FM_MB_SLOT_ID1" )
			)
			( signal "@baseboard_fab2_lib.baseboard_fab2(sch_1):fm_flash_desc_override_r"
				( attribute "CDS_PHYS_NET_NAME" "FM_FLASH_DESC_OVERRIDE_R"
					( Origin gPackager )
				)
				( objectStatus "FM_FLASH_DESC_OVERRIDE_R" )
			)
			( signal "@baseboard_fab2_lib.baseboard_fab2(sch_1):fm_mb_slot_id2"
				( attribute "CDS_PHYS_NET_NAME" "FM_MB_SLOT_ID2"
					( Origin gPackager )
				)
				( attribute "PHYS_NET_NAME" "FM_MB_SLOT_ID2"
					( Origin gPackager )
				)
				( objectStatus "FM_MB_SLOT_ID2" )
			)
			( signal "@baseboard_fab2_lib.baseboard_fab2(sch_1):fm_me_recover_n"
				( attribute "CDS_PHYS_NET_NAME" "FM_ME_RECOVER_N"
					( Origin gPackager )
				)
				( objectStatus "FM_ME_RECOVER_N" )
			)
			( signal "@baseboard_fab2_lib.baseboard_fab2(sch_1):fm_ocp_mezza_pres_n"
				( attribute "CDS_PHYS_NET_NAME" "FM_OCP_MEZZA_PRES_N"
					( Origin gPackager )
				)
				( objectStatus "FM_OCP_MEZZA_PRES_N" )
			)
			( signal "@baseboard_fab2_lib.baseboard_fab2(sch_1):fm_password_clear_n"
				( attribute "CDS_PHYS_NET_NAME" "FM_PASSWORD_CLEAR_N"
					( Origin gPackager )
				)
				( objectStatus "FM_PASSWORD_CLEAR_N" )
			)
			( signal "@baseboard_fab2_lib.baseboard_fab2(sch_1):fm_pch_bmc_thermtrip_exi_strap_n"
				( attribute "CDS_PHYS_NET_NAME" "FM_PCH_BMC_THERMTRIP_EXI_STRAP_"
					( Origin gPackager )
				)
				( attribute "PNN" "FM_PCH_BMC_THERMTRIP_EXI_STRAP_"
					( Origin gPackager )
				)
				( objectStatus "FM_PCH_BMC_THERMTRIP_EXI_STRAP_" )
			)
			( signal "@baseboard_fab2_lib.baseboard_fab2(sch_1):fm_pch_pld_data"
				( attribute "CDS_PHYS_NET_NAME" "FM_PCH_PLD_DATA"
					( Origin gPackager )
				)
				( objectStatus "FM_PCH_PLD_DATA" )
			)
			( signal "@baseboard_fab2_lib.baseboard_fab2(sch_1):fm_pch_pld_data_r"
				( attribute "CDS_PHYS_NET_NAME" "FM_PCH_PLD_DATA_R"
					( Origin gPackager )
				)
				( objectStatus "FM_PCH_PLD_DATA_R" )
			)
			( signal "@baseboard_fab2_lib.baseboard_fab2(sch_1):fm_pch_pwrbtn_out_n"
				( attribute "CDS_PHYS_NET_NAME" "FM_PCH_PWRBTN_OUT_N"
					( Origin gPackager )
				)
				( objectStatus "FM_PCH_PWRBTN_OUT_N" )
			)
			( signal "@baseboard_fab2_lib.baseboard_fab2(sch_1):fm_pch_sata_raid_key"
				( attribute "CDS_PHYS_NET_NAME" "FM_PCH_SATA_RAID_KEY"
					( Origin gPackager )
				)
				( objectStatus "FM_PCH_SATA_RAID_KEY" )
			)
			( signal "@baseboard_fab2_lib.baseboard_fab2(sch_1):fm_pmbus_alert_buf_en_n"
				( attribute "CDS_PHYS_NET_NAME" "FM_PMBUS_ALERT_BUF_EN_N"
					( Origin gPackager )
				)
				( attribute "PHYS_NET_NAME" "FM_PMBUS_ALERT_BUF_EN_N"
					( Origin gPackager )
				)
				( objectStatus "FM_PMBUS_ALERT_BUF_EN_N" )
			)
			( signal "@baseboard_fab2_lib.baseboard_fab2(sch_1):fm_post_card_pres_bmc_n"
				( attribute "CDS_PHYS_NET_NAME" "FM_POST_CARD_PRES_BMC_N"
					( Origin gPackager )
				)
				( objectStatus "FM_POST_CARD_PRES_BMC_N" )
			)
			( signal "@baseboard_fab2_lib.baseboard_fab2(sch_1):fm_pwr_btn_n"
				( attribute "CDS_PHYS_NET_NAME" "FM_PWR_BTN_N"
					( Origin gPackager )
				)
				( attribute "PHYS_NET_NAME" "FM_PWR_BTN_N"
					( Origin gPackager )
				)
				( objectStatus "FM_PWR_BTN_N" )
			)
			( signal "@baseboard_fab2_lib.baseboard_fab2(sch_1):fm_pwr_led"
				( attribute "CDS_PHYS_NET_NAME" "FM_PWR_LED"
					( Origin gPackager )
				)
				( objectStatus "FM_PWR_LED" )
			)
			( signal "@baseboard_fab2_lib.baseboard_fab2(sch_1):fm_pwr_led_a"
				( attribute "CDS_PHYS_NET_NAME" "FM_PWR_LED_A"
					( Origin gPackager )
				)
				( objectStatus "FM_PWR_LED_A" )
			)
			( signal "@baseboard_fab2_lib.baseboard_fab2(sch_1):fm_pwr_led_k"
				( attribute "CDS_PHYS_NET_NAME" "FM_PWR_LED_K"
					( Origin gPackager )
				)
				( objectStatus "FM_PWR_LED_K" )
			)
			( signal "@baseboard_fab2_lib.baseboard_fab2(sch_1):fm_pwr_led_n"
				( attribute "CDS_PHYS_NET_NAME" "FM_PWR_LED_N"
					( Origin gPackager )
				)
				( objectStatus "FM_PWR_LED_N" )
			)
			( signal "@baseboard_fab2_lib.baseboard_fab2(sch_1):fm_qat_en_n"
				( attribute "CDS_PHYS_NET_NAME" "FM_QAT_EN_N"
					( Origin gPackager )
				)
				( objectStatus "FM_QAT_EN_N" )
			)
			( signal "@baseboard_fab2_lib.baseboard_fab2(sch_1):fm_slt_cfg2_r"
				( attribute "CDS_PHYS_NET_NAME" "FM_SLT_CFG2_R"
					( Origin gPackager )
				)
				( objectStatus "FM_SLT_CFG2_R" )
			)
			( signal "@baseboard_fab2_lib.baseboard_fab2(sch_1):fm_tpm_pres_n"
				( attribute "CDS_PHYS_NET_NAME" "FM_TPM_PRES_N"
					( Origin gPackager )
				)
				( objectStatus "FM_TPM_PRES_N" )
			)
			( signal "@baseboard_fab2_lib.baseboard_fab2(sch_1):fm_uart_alert_n"
				( attribute "CDS_PHYS_NET_NAME" "FM_UART_ALERT_N"
					( Origin gPackager )
				)
				( objectStatus "FM_UART_ALERT_N" )
			)
			( signal "@baseboard_fab2_lib.baseboard_fab2(sch_1):fm_uart_pres_n"
				( attribute "CDS_PHYS_NET_NAME" "FM_UART_PRES_N"
					( Origin gPackager )
				)
				( objectStatus "FM_UART_PRES_N" )
			)
			( signal "@baseboard_fab2_lib.baseboard_fab2(sch_1):fm_usb_p0_en_boot_bios_strap_n"
				( attribute "CDS_PHYS_NET_NAME" "FM_USB_P0_EN_BOOT_BIOS_STRAP_N"
					( Origin gPackager )
				)
				( objectStatus "FM_USB_P0_EN_BOOT_BIOS_STRAP_N" )
			)
			( signal "@baseboard_fab2_lib.baseboard_fab2(sch_1):fm_uv_adr_trigger_en"
				( attribute "CDS_PHYS_NET_NAME" "FM_UV_ADR_TRIGGER_EN"
					( Origin gPackager )
				)
				( attribute "PHYS_NET_NAME" "FM_UV_ADR_TRIGGER_EN"
					( Origin gPackager )
				)
				( objectStatus "FM_UV_ADR_TRIGGER_EN" )
			)
			( signal "@baseboard_fab2_lib.baseboard_fab2(sch_1):smb_ipmb_3v3aux_scl"
				( attribute "CDS_PHYS_NET_NAME" "SMB_IPMB_3V3AUX_SCL"
					( Origin gPackager )
				)
				( objectStatus "SMB_IPMB_3V3AUX_SCL" )
			)
			( signal "@baseboard_fab2_lib.baseboard_fab2(sch_1):fm_xrc_present_n"
				( attribute "CDS_PHYS_NET_NAME" "FM_XRC_PRESENT_N"
					( Origin gPackager )
				)
				( attribute "PHYS_NET_NAME" "FM_XRC_PRESENT_N"
					( Origin gPackager )
				)
				( objectStatus "FM_XRC_PRESENT_N" )
			)
			( signal "@baseboard_fab2_lib.baseboard_fab2(sch_1):fm_xrc_ready_n"
				( attribute "CDS_PHYS_NET_NAME" "FM_XRC_READY_N"
					( Origin gPackager )
				)
				( attribute "PHYS_NET_NAME" "FM_XRC_READY_N"
					( Origin gPackager )
				)
				( objectStatus "FM_XRC_READY_N" )
			)
			( signal "@baseboard_fab2_lib.baseboard_fab2(sch_1):fp_nmi_btn_n"
				( attribute "CDS_PHYS_NET_NAME" "FP_NMI_BTN_N"
					( Origin gPackager )
				)
				( attribute "PHYS_NET_NAME" "FP_NMI_BTN_N"
					( Origin gPackager )
				)
				( objectStatus "FP_NMI_BTN_N" )
			)
			( signal "@baseboard_fab2_lib.baseboard_fab2(sch_1):h_cpu0_fast_wake_lvt3_n"
				( alias ( signalRef "@baseboard_fab2_lib.baseboard_fab2(sch_1):page147_h_cpu0_fast_wake_lvt3_n") )
				( attribute "CDS_PHYS_NET_NAME" "H_CPU0_FAST_WAKE_LVT3_N"
					( Origin gPackager )
				)
				( attribute "PHYS_NET_NAME" "H_CPU0_FAST_WAKE_LVT3_N"
					( Origin gPackager )
				)
				( objectStatus "H_CPU0_FAST_WAKE_LVT3_N" )
			)
			( signal "@baseboard_fab2_lib.baseboard_fab2(sch_1):page147_h_cpu0_fast_wake_lvt3_n"
				( attribute "CDS_PHYS_NET_NAME" "H_CPU0_FAST_WAKE_LVT3_N"
					( Origin gPackager )
				)
				( attribute "PHYS_NET_NAME" "H_CPU0_FAST_WAKE_LVT3_N"
					( Origin gPackager )
				)
				( objectFlag fObjectAlias )
				( objectStatus "page147_h_cpu0_fast_wake_lvt3_n" )
			)
			( signal "@baseboard_fab2_lib.baseboard_fab2(sch_1):page144_irq_hsc_fault_n"
				( attribute "CDS_PHYS_NET_NAME" "IRQ_HSC_FAULT_N"
					( Origin gPackager )
				)
				( attribute "PHYS_NET_NAME" "IRQ_HSC_FAULT_N"
					( Origin gPackager )
				)
				( objectFlag fObjectAlias )
				( objectStatus "page144_irq_hsc_fault_n" )
			)
			( signal "@baseboard_fab2_lib.baseboard_fab2(sch_1):irq_bmc_pch_nmi_stby_r_n"
				( attribute "CDS_PHYS_NET_NAME" "IRQ_BMC_PCH_NMI_STBY_R_N"
					( Origin gPackager )
				)
				( objectStatus "IRQ_BMC_PCH_NMI_STBY_R_N" )
			)
			( signal "@baseboard_fab2_lib.baseboard_fab2(sch_1):irq_bmc_pch_sci_lpc_n"
				( attribute "CDS_PHYS_NET_NAME" "IRQ_BMC_PCH_SCI_LPC_N"
					( Origin gPackager )
				)
				( attribute "PHYS_NET_NAME" "IRQ_BMC_PCH_SCI_LPC_N"
					( Origin gPackager )
				)
				( objectStatus "IRQ_BMC_PCH_SCI_LPC_N" )
			)
			( signal "@baseboard_fab2_lib.baseboard_fab2(sch_1):irq_bmc_pch_smi_lpc_n"
				( attribute "CDS_PHYS_NET_NAME" "IRQ_BMC_PCH_SMI_LPC_N"
					( Origin gPackager )
				)
				( attribute "PHYS_NET_NAME" "IRQ_BMC_PCH_SMI_LPC_N"
					( Origin gPackager )
				)
				( objectStatus "IRQ_BMC_PCH_SMI_LPC_N" )
			)
			( signal "@baseboard_fab2_lib.baseboard_fab2(sch_1):irq_force_nm_throttle_n"
				( alias ( signalRef "@baseboard_fab2_lib.baseboard_fab2(sch_1):page146_irq_force_nm_throttle_n") )
				( attribute "CDS_PHYS_NET_NAME" "IRQ_FORCE_NM_THROTTLE_N"
					( Origin gPackager )
				)
				( objectStatus "IRQ_FORCE_NM_THROTTLE_N" )
			)
			( signal "@baseboard_fab2_lib.baseboard_fab2(sch_1):page146_irq_force_nm_throttle_n"
				( attribute "CDS_PHYS_NET_NAME" "IRQ_FORCE_NM_THROTTLE_N"
					( Origin gPackager )
				)
				( objectFlag fObjectAlias )
				( objectStatus "page146_irq_force_nm_throttle_n" )
			)
			( signal "@baseboard_fab2_lib.baseboard_fab2(sch_1):irq_hsc_fault_n"
				( alias ( signalRef "@baseboard_fab2_lib.baseboard_fab2(sch_1):page144_irq_hsc_fault_n") )
				( attribute "CDS_PHYS_NET_NAME" "IRQ_HSC_FAULT_N"
					( Origin gPackager )
				)
				( attribute "PHYS_NET_NAME" "IRQ_HSC_FAULT_N"
					( Origin gPackager )
				)
				( objectStatus "IRQ_HSC_FAULT_N" )
			)
			( signal "@baseboard_fab2_lib.baseboard_fab2(sch_1):irq_lom_alert_n"
				( attribute "CDS_PHYS_NET_NAME" "IRQ_LOM_ALERT_N"
					( Origin gPackager )
				)
				( attribute "PHYS_NET_NAME" "IRQ_LOM_ALERT_N"
					( Origin gPackager )
				)
				( objectStatus "IRQ_LOM_ALERT_N" )
			)
			( signal "@baseboard_fab2_lib.baseboard_fab2(sch_1):fm_bmc_onctl_r_n"
				( attribute "CDS_PHYS_NET_NAME" "FM_BMC_ONCTL_R_N"
					( Origin gPackager )
				)
				( objectStatus "FM_BMC_ONCTL_R_N" )
			)
			( signal "@baseboard_fab2_lib.baseboard_fab2(sch_1):irq_lpc_serirq_n"
				( attribute "CDS_PHYS_NET_NAME" "IRQ_LPC_SERIRQ_N"
					( Origin gPackager )
				)
				( objectStatus "IRQ_LPC_SERIRQ_N" )
			)
			( signal "@baseboard_fab2_lib.baseboard_fab2(sch_1):irq_mezz_lan_alert_n"
				( alias ( signalRef "@baseboard_fab2_lib.baseboard_fab2(sch_1):page146_irq_mezz_lan_alert_n") )
				( attribute "CDS_PHYS_NET_NAME" "IRQ_MEZZ_LAN_ALERT_N"
					( Origin gPackager )
				)
				( attribute "PHYS_NET_NAME" "IRQ_MEZZ_LAN_ALERT_N"
					( Origin gPackager )
				)
				( objectStatus "IRQ_MEZZ_LAN_ALERT_N" )
			)
			( signal "@baseboard_fab2_lib.baseboard_fab2(sch_1):page146_irq_mezz_lan_alert_n"
				( attribute "CDS_PHYS_NET_NAME" "IRQ_MEZZ_LAN_ALERT_N"
					( Origin gPackager )
				)
				( attribute "PHYS_NET_NAME" "IRQ_MEZZ_LAN_ALERT_N"
					( Origin gPackager )
				)
				( objectFlag fObjectAlias )
				( objectStatus "page146_irq_mezz_lan_alert_n" )
			)
			( signal "@baseboard_fab2_lib.baseboard_fab2(sch_1):irq_pch_nic_alert_n"
				( alias ( signalRef "@baseboard_fab2_lib.baseboard_fab2(sch_1):page143_irq_pch_nic_alert_n") )
				( attribute "CDS_PHYS_NET_NAME" "IRQ_PCH_NIC_ALERT_N"
					( Origin gPackager )
				)
				( objectStatus "IRQ_PCH_NIC_ALERT_N" )
			)
			( signal "@baseboard_fab2_lib.baseboard_fab2(sch_1):page143_irq_pch_nic_alert_n"
				( objectFlag fObjectAlias )
				( objectStatus "page143_irq_pch_nic_alert_n" )
			)
			( signal "@baseboard_fab2_lib.baseboard_fab2(sch_1):\unnamed_239_21k5r2f-gp_i99_2\"
				( attribute "CDS_PHYS_NET_NAME" "UNNAMED_239_21K5R2F-GP_I99_2"
					( Origin gPackager )
				)
				( objectStatus "UNNAMED_239_21K5R2F-GP_I99_2" )
			)
			( signal "@baseboard_fab2_lib.baseboard_fab2(sch_1):irq_pirqa_spi_tpm_n"
				( attribute "CDS_PHYS_NET_NAME" "IRQ_PIRQA_SPI_TPM_N"
					( Origin gPackager )
				)
				( objectStatus "IRQ_PIRQA_SPI_TPM_N" )
			)
			( signal "@baseboard_fab2_lib.baseboard_fab2(sch_1):irq_sml0_alert_n"
				( attribute "CDS_PHYS_NET_NAME" "IRQ_SML0_ALERT_N"
					( Origin gPackager )
				)
				( attribute "PHYS_NET_NAME" "IRQ_SML0_ALERT_N"
					( Origin gPackager )
				)
				( objectStatus "IRQ_SML0_ALERT_N" )
			)
			( signal "@baseboard_fab2_lib.baseboard_fab2(sch_1):irq_vm_int_n"
				( attribute "CDS_PHYS_NET_NAME" "IRQ_VM_INT_N"
					( Origin gPackager )
				)
				( objectStatus "IRQ_VM_INT_N" )
			)
			( signal "@baseboard_fab2_lib.baseboard_fab2(sch_1):lpc_lad0_io0"
				( alias ( signalRef "@baseboard_fab2_lib.baseboard_fab2(sch_1):page119_lpc_lad0_io0") )
				( alias ( signalRef "@baseboard_fab2_lib.baseboard_fab2(sch_1):page119_lpc_lad_io(0)") )
				( alias ( signalRef "@baseboard_fab2_lib.baseboard_fab2(sch_1):lpc_lad_io(0)") )
				( attribute "CDS_PHYS_NET_NAME" "LPC_LAD0_IO0"
					( Origin gPackager )
				)
				( objectStatus "LPC_LAD0_IO0" )
			)
			( signal "@baseboard_fab2_lib.baseboard_fab2(sch_1):page119_lpc_lad0_io0"
				( objectFlag fObjectAlias )
				( objectStatus "page119_lpc_lad0_io0" )
			)
			( signal "@baseboard_fab2_lib.baseboard_fab2(sch_1):page119_lpc_lad_io(0)"
				( objectFlag fObjectAlias )
				( objectStatus "page119_lpc_lad_io<0>" )
			)
			( signal "@baseboard_fab2_lib.baseboard_fab2(sch_1):lpc_lad_io(0)"
				( objectFlag fObjectAlias )
				( objectStatus "lpc_lad_io<0>" )
			)
			( signal "@baseboard_fab2_lib.baseboard_fab2(sch_1):lpc_lad1_io1"
				( alias ( signalRef "@baseboard_fab2_lib.baseboard_fab2(sch_1):page119_lpc_lad1_io1") )
				( alias ( signalRef "@baseboard_fab2_lib.baseboard_fab2(sch_1):page119_lpc_lad_io(1)") )
				( alias ( signalRef "@baseboard_fab2_lib.baseboard_fab2(sch_1):lpc_lad_io(1)") )
				( attribute "CDS_PHYS_NET_NAME" "LPC_LAD1_IO1"
					( Origin gPackager )
				)
				( objectStatus "LPC_LAD1_IO1" )
			)
			( signal "@baseboard_fab2_lib.baseboard_fab2(sch_1):page119_lpc_lad1_io1"
				( objectFlag fObjectAlias )
				( objectStatus "page119_lpc_lad1_io1" )
			)
			( signal "@baseboard_fab2_lib.baseboard_fab2(sch_1):page119_lpc_lad_io(1)"
				( objectFlag fObjectAlias )
				( objectStatus "page119_lpc_lad_io<1>" )
			)
			( signal "@baseboard_fab2_lib.baseboard_fab2(sch_1):lpc_lad_io(1)"
				( objectFlag fObjectAlias )
				( objectStatus "lpc_lad_io<1>" )
			)
			( signal "@baseboard_fab2_lib.baseboard_fab2(sch_1):lpc_lad2_io2"
				( alias ( signalRef "@baseboard_fab2_lib.baseboard_fab2(sch_1):page119_lpc_lad2_io2") )
				( alias ( signalRef "@baseboard_fab2_lib.baseboard_fab2(sch_1):page119_lpc_lad_io(2)") )
				( alias ( signalRef "@baseboard_fab2_lib.baseboard_fab2(sch_1):lpc_lad_io(2)") )
				( attribute "CDS_PHYS_NET_NAME" "LPC_LAD2_IO2"
					( Origin gPackager )
				)
				( objectStatus "LPC_LAD2_IO2" )
			)
			( signal "@baseboard_fab2_lib.baseboard_fab2(sch_1):page119_lpc_lad2_io2"
				( objectFlag fObjectAlias )
				( objectStatus "page119_lpc_lad2_io2" )
			)
			( signal "@baseboard_fab2_lib.baseboard_fab2(sch_1):page119_lpc_lad_io(2)"
				( objectFlag fObjectAlias )
				( objectStatus "page119_lpc_lad_io<2>" )
			)
			( signal "@baseboard_fab2_lib.baseboard_fab2(sch_1):lpc_lad_io(2)"
				( objectFlag fObjectAlias )
				( objectStatus "lpc_lad_io<2>" )
			)
			( signal "@baseboard_fab2_lib.baseboard_fab2(sch_1):lpc_lad3_io3"
				( alias ( signalRef "@baseboard_fab2_lib.baseboard_fab2(sch_1):page119_lpc_lad3_io3") )
				( alias ( signalRef "@baseboard_fab2_lib.baseboard_fab2(sch_1):page119_lpc_lad_io(3)") )
				( alias ( signalRef "@baseboard_fab2_lib.baseboard_fab2(sch_1):lpc_lad_io(3)") )
				( attribute "CDS_PHYS_NET_NAME" "LPC_LAD3_IO3"
					( Origin gPackager )
				)
				( objectStatus "LPC_LAD3_IO3" )
			)
			( signal "@baseboard_fab2_lib.baseboard_fab2(sch_1):page119_lpc_lad3_io3"
				( objectFlag fObjectAlias )
				( objectStatus "page119_lpc_lad3_io3" )
			)
			( signal "@baseboard_fab2_lib.baseboard_fab2(sch_1):page119_lpc_lad_io(3)"
				( objectFlag fObjectAlias )
				( objectStatus "page119_lpc_lad_io<3>" )
			)
			( signal "@baseboard_fab2_lib.baseboard_fab2(sch_1):lpc_lad_io(3)"
				( objectFlag fObjectAlias )
				( objectStatus "lpc_lad_io<3>" )
			)
			( signal "@baseboard_fab2_lib.baseboard_fab2(sch_1):lpc_lframe_n_cs0_n"
				( attribute "CDS_PHYS_NET_NAME" "LPC_LFRAME_N_CS0_N"
					( Origin gPackager )
				)
				( objectStatus "LPC_LFRAME_N_CS0_N" )
			)
			( signal "@baseboard_fab2_lib.baseboard_fab2(sch_1):pu_fm_rcin_n"
				( attribute "CDS_PHYS_NET_NAME" "PU_FM_RCIN_N"
					( Origin gPackager )
				)
				( objectStatus "PU_FM_RCIN_N" )
			)
			( signal "@baseboard_fab2_lib.baseboard_fab2(sch_1):pu_irq_pch_sci_whea_n"
				( attribute "CDS_PHYS_NET_NAME" "PU_IRQ_PCH_SCI_WHEA_N"
					( Origin gPackager )
				)
				( objectStatus "PU_IRQ_PCH_SCI_WHEA_N" )
			)
			( signal "@baseboard_fab2_lib.baseboard_fab2(sch_1):pu_irq_vralert_n"
				( attribute "CDS_PHYS_NET_NAME" "PU_IRQ_VRALERT_N"
					( Origin gPackager )
				)
				( objectStatus "PU_IRQ_VRALERT_N" )
			)
			( signal "@baseboard_fab2_lib.baseboard_fab2(sch_1):pu_lpc_clkrun_n"
				( attribute "CDS_PHYS_NET_NAME" "PU_LPC_CLKRUN_N"
					( Origin gPackager )
				)
				( objectStatus "PU_LPC_CLKRUN_N" )
			)
			( signal "@baseboard_fab2_lib.baseboard_fab2(sch_1):pu_lpc_pme_n"
				( attribute "CDS_PHYS_NET_NAME" "PU_LPC_PME_N"
					( Origin gPackager )
				)
				( objectStatus "PU_LPC_PME_N" )
			)
			( signal "@baseboard_fab2_lib.baseboard_fab2(sch_1):pu_pch_tls_enable_strap"
				( attribute "CDS_PHYS_NET_NAME" "PU_PCH_TLS_ENABLE_STRAP"
					( Origin gPackager )
				)
				( objectStatus "PU_PCH_TLS_ENABLE_STRAP" )
			)
			( signal "@baseboard_fab2_lib.baseboard_fab2(sch_1):rst_pch_sysrst_btn_out_n"
				( attribute "CDS_PHYS_NET_NAME" "RST_PCH_SYSRST_BTN_OUT_N"
					( Origin gPackager )
				)
				( objectStatus "RST_PCH_SYSRST_BTN_OUT_N" )
			)
			( signal "@baseboard_fab2_lib.baseboard_fab2(sch_1):rst_pltrst_n"
				( attribute "CDS_PHYS_NET_NAME" "RST_PLTRST_N"
					( Origin gPackager )
				)
				( objectStatus "RST_PLTRST_N" )
			)
			( signal "@baseboard_fab2_lib.baseboard_fab2(sch_1):rst_system_btn_n"
				( attribute "CDS_PHYS_NET_NAME" "RST_SYSTEM_BTN_N"
					( Origin gPackager )
				)
				( attribute "PHYS_NET_NAME" "RST_SYSTEM_BTN_N"
					( Origin gPackager )
				)
				( objectStatus "RST_SYSTEM_BTN_N" )
			)
			( signal "@baseboard_fab2_lib.baseboard_fab2(sch_1):sgpio_pch_ssata_dout0"
				( attribute "CDS_PHYS_NET_NAME" "SGPIO_PCH_SSATA_DOUT0"
					( Origin gPackager )
				)
				( objectStatus "SGPIO_PCH_SSATA_DOUT0" )
			)
			( signal "@baseboard_fab2_lib.baseboard_fab2(sch_1):smb_host_stby_lvc3_scl_r1"
				( attribute "CDS_PHYS_NET_NAME" "SMB_HOST_STBY_LVC3_SCL_R1"
					( Origin gPackager )
				)
				( objectStatus "SMB_HOST_STBY_LVC3_SCL_R1" )
			)
			( signal "@baseboard_fab2_lib.baseboard_fab2(sch_1):smb_host_stby_lvc3_sda_r1"
				( attribute "CDS_PHYS_NET_NAME" "SMB_HOST_STBY_LVC3_SDA_R1"
					( Origin gPackager )
				)
				( objectStatus "SMB_HOST_STBY_LVC3_SDA_R1" )
			)
			( signal "@baseboard_fab2_lib.baseboard_fab2(sch_1):smb_pmbus_bmc_stby_lvc3_scl_r1"
				( alias ( signalRef "@baseboard_fab2_lib.baseboard_fab2(sch_1):page247_smb_pmbus_bmc_stby_lvc3_scl_r1") )
				( attribute "CDS_PHYS_NET_NAME" "SMB_PMBUS_BMC_STBY_LVC3_SCL_R1"
					( Origin gPackager )
				)
				( objectStatus "SMB_PMBUS_BMC_STBY_LVC3_SCL_R1" )
			)
			( signal "@baseboard_fab2_lib.baseboard_fab2(sch_1):page247_smb_pmbus_bmc_stby_lvc3_scl_r1"
				( attribute "CDS_PHYS_NET_NAME" "SMB_PMBUS_BMC_STBY_LVC3_SCL_R1"
					( Origin gPackager )
				)
				( objectFlag fObjectAlias )
				( objectStatus "page247_smb_pmbus_bmc_stby_lvc3_scl_r1" )
			)
			( signal "@baseboard_fab2_lib.baseboard_fab2(sch_1):smb_pmbus_bmc_stby_lvc3_sda_r1"
				( alias ( signalRef "@baseboard_fab2_lib.baseboard_fab2(sch_1):page247_smb_pmbus_bmc_stby_lvc3_sda_r1") )
				( attribute "CDS_PHYS_NET_NAME" "SMB_PMBUS_BMC_STBY_LVC3_SDA_R1"
					( Origin gPackager )
				)
				( objectStatus "SMB_PMBUS_BMC_STBY_LVC3_SDA_R1" )
			)
			( signal "@baseboard_fab2_lib.baseboard_fab2(sch_1):page247_smb_pmbus_bmc_stby_lvc3_sda_r1"
				( attribute "CDS_PHYS_NET_NAME" "SMB_PMBUS_BMC_STBY_LVC3_SDA_R1"
					( Origin gPackager )
				)
				( objectFlag fObjectAlias )
				( objectStatus "page247_smb_pmbus_bmc_stby_lvc3_sda_r1" )
			)
			( signal "@baseboard_fab2_lib.baseboard_fab2(sch_1):smb_slotx24_stby_lvc3_scl_r1"
				( attribute "CDS_PHYS_NET_NAME" "SMB_SLOTX24_STBY_LVC3_SCL_R1"
					( Origin gPackager )
				)
				( objectStatus "SMB_SLOTX24_STBY_LVC3_SCL_R1" )
			)
			( signal "@baseboard_fab2_lib.baseboard_fab2(sch_1):smb_slotx24_stby_lvc3_sda_r1"
				( attribute "CDS_PHYS_NET_NAME" "SMB_SLOTX24_STBY_LVC3_SDA_R1"
					( Origin gPackager )
				)
				( objectStatus "SMB_SLOTX24_STBY_LVC3_SDA_R1" )
			)
			( signal "@baseboard_fab2_lib.baseboard_fab2(sch_1):smb_smlink0_stby_lvc3_scl_r1"
				( attribute "CDS_PHYS_NET_NAME" "SMB_SMLINK0_STBY_LVC3_SCL_R1"
					( Origin gPackager )
				)
				( objectStatus "SMB_SMLINK0_STBY_LVC3_SCL_R1" )
			)
			( signal "@baseboard_fab2_lib.baseboard_fab2(sch_1):smb_smlink0_stby_lvc3_sda_r1"
				( attribute "CDS_PHYS_NET_NAME" "SMB_SMLINK0_STBY_LVC3_SDA_R1"
					( Origin gPackager )
				)
				( objectStatus "SMB_SMLINK0_STBY_LVC3_SDA_R1" )
			)
			( signal "@baseboard_fab2_lib.baseboard_fab2(sch_1):sp2_bmc_cm_uart_rx"
				( attribute "CDS_PHYS_NET_NAME" "SP2_BMC_CM_UART_RX"
					( Origin gPackager )
				)
				( attribute "PHYS_NET_NAME" "SP2_BMC_CM_UART_RX"
					( Origin gPackager )
				)
				( objectStatus "SP2_BMC_CM_UART_RX" )
			)
			( signal "@baseboard_fab2_lib.baseboard_fab2(sch_1):sp2_bmc_cm_uart_tx"
				( attribute "CDS_PHYS_NET_NAME" "SP2_BMC_CM_UART_TX"
					( Origin gPackager )
				)
				( attribute "PHYS_NET_NAME" "SP2_BMC_CM_UART_TX"
					( Origin gPackager )
				)
				( objectStatus "SP2_BMC_CM_UART_TX" )
			)
			( signal "@baseboard_fab2_lib.baseboard_fab2(sch_1):tp_pch_gpp_d12"
				( attribute "CDS_PHYS_NET_NAME" "TP_PCH_GPP_D12"
					( Origin gPackager )
				)
				( objectStatus "TP_PCH_GPP_D12" )
			)
			( signal "@baseboard_fab2_lib.baseboard_fab2(sch_1):vid_pch_core_pvnn_aux_vid_0"
				( attribute "CDS_PHYS_NET_NAME" "VID_PCH_CORE_PVNN_AUX_VID_0"
					( Origin gPackager )
				)
				( objectStatus "VID_PCH_CORE_PVNN_AUX_VID_0" )
			)
			( signal "@baseboard_fab2_lib.baseboard_fab2(sch_1):vid_pch_core_pvnn_aux_vid_1"
				( attribute "CDS_PHYS_NET_NAME" "VID_PCH_CORE_PVNN_AUX_VID_1"
					( Origin gPackager )
				)
				( objectStatus "VID_PCH_CORE_PVNN_AUX_VID_1" )
			)
			( signal "@baseboard_fab2_lib.baseboard_fab2(sch_1):a_rcomp_3p3"
				( attribute "CDS_PHYS_NET_NAME" "A_RCOMP_3P3"
					( Origin gPackager )
				)
				( objectStatus "A_RCOMP_3P3" )
			)
			( signal "@baseboard_fab2_lib.baseboard_fab2(sch_1):fan_pwm_out_sys0"
				( attribute "CDS_PHYS_NET_NAME" "FAN_PWM_OUT_SYS0"
					( Origin gPackager )
				)
				( attribute "PHYS_NET_NAME" "FAN_PWM_OUT_SYS0"
					( Origin gPackager )
				)
				( objectStatus "FAN_PWM_OUT_SYS0" )
			)
			( signal "@baseboard_fab2_lib.baseboard_fab2(sch_1):fan_pwm_out_sys1"
				( attribute "CDS_PHYS_NET_NAME" "FAN_PWM_OUT_SYS1"
					( Origin gPackager )
				)
				( attribute "PHYS_NET_NAME" "FAN_PWM_OUT_SYS1"
					( Origin gPackager )
				)
				( objectStatus "FAN_PWM_OUT_SYS1" )
			)
			( signal "@baseboard_fab2_lib.baseboard_fab2(sch_1):fan_tach0"
				( attribute "CDS_PHYS_NET_NAME" "FAN_TACH0"
					( Origin gPackager )
				)
				( objectStatus "FAN_TACH0" )
			)
			( signal "@baseboard_fab2_lib.baseboard_fab2(sch_1):fan_tach1"
				( attribute "CDS_PHYS_NET_NAME" "FAN_TACH1"
					( Origin gPackager )
				)
				( objectStatus "FAN_TACH1" )
			)
			( signal "@baseboard_fab2_lib.baseboard_fab2(sch_1):fan_tach2"
				( attribute "CDS_PHYS_NET_NAME" "FAN_TACH2"
					( Origin gPackager )
				)
				( objectStatus "FAN_TACH2" )
			)
			( signal "@baseboard_fab2_lib.baseboard_fab2(sch_1):fan_tach3"
				( attribute "CDS_PHYS_NET_NAME" "FAN_TACH3"
					( Origin gPackager )
				)
				( objectStatus "FAN_TACH3" )
			)
			( signal "@baseboard_fab2_lib.baseboard_fab2(sch_1):fm_adr_complete_r1"
				( attribute "CDS_PHYS_NET_NAME" "FM_ADR_COMPLETE_R1"
					( Origin gPackager )
				)
				( objectStatus "FM_ADR_COMPLETE_R1" )
			)
			( signal "@baseboard_fab2_lib.baseboard_fab2(sch_1):fm_backup_bios_sel_n"
				( attribute "CDS_PHYS_NET_NAME" "FM_BACKUP_BIOS_SEL_N"
					( Origin gPackager )
				)
				( attribute "PHYS_NET_NAME" "FM_BACKUP_BIOS_SEL_N"
					( Origin gPackager )
				)
				( objectStatus "FM_BACKUP_BIOS_SEL_N" )
			)
			( signal "@baseboard_fab2_lib.baseboard_fab2(sch_1):smb_pcie_ssd_3v3aux_scl"
				( attribute "CDS_PHYS_NET_NAME" "SMB_PCIE_SSD_3V3AUX_SCL"
					( Origin gPackager )
				)
				( objectStatus "SMB_PCIE_SSD_3V3AUX_SCL" )
			)
			( signal "@baseboard_fab2_lib.baseboard_fab2(sch_1):page147_p3v3_stby_bmc_adcvrefn"
				( attribute "VOLTAGE" "+3.3V"
					( Units "uVoltage" "V" 1.000000)
					( Origin gFrontEnd )
				)
				( objectFlag fObjectAlias )
				( objectStatus "page147_p3v3_stby_bmc_adcvrefn" )
			)
			( signal "@baseboard_fab2_lib.baseboard_fab2(sch_1):fm_bios_mrc_debug_msg_dis_n"
				( alias ( signalRef "@baseboard_fab2_lib.baseboard_fab2(sch_1):page144_fm_bios_mrc_debug_msg_dis_n") )
				( attribute "CDS_PHYS_NET_NAME" "FM_BIOS_MRC_DEBUG_MSG_DIS_N"
					( Origin gPackager )
				)
				( attribute "PHYS_NET_NAME" "FM_BIOS_MRC_DEBUG_MSG_DIS_N"
					( Origin gPackager )
				)
				( objectStatus "FM_BIOS_MRC_DEBUG_MSG_DIS_N" )
			)
			( signal "@baseboard_fab2_lib.baseboard_fab2(sch_1):page147_pd_adcrext"
				( attribute "CDS_PHYS_NET_NAME" "PD_ADCREXT"
					( Origin gPackager )
				)
				( objectFlag fObjectAlias )
				( objectStatus "page147_pd_adcrext" )
			)
			( signal "@baseboard_fab2_lib.baseboard_fab2(sch_1):fm_bios_smi_active_n"
				( attribute "CDS_PHYS_NET_NAME" "FM_BIOS_SMI_ACTIVE_N"
					( Origin gPackager )
				)
				( objectStatus "FM_BIOS_SMI_ACTIVE_N" )
			)
			( signal "@baseboard_fab2_lib.baseboard_fab2(sch_1):fm_bios_top_swap"
				( attribute "CDS_PHYS_NET_NAME" "FM_BIOS_TOP_SWAP"
					( Origin gPackager )
				)
				( attribute "PHYS_NET_NAME" "FM_BIOS_TOP_SWAP"
					( Origin gPackager )
				)
				( objectStatus "FM_BIOS_TOP_SWAP" )
			)
			( signal "@baseboard_fab2_lib.baseboard_fab2(sch_1):page147_vcc_adcav3v3"
				( attribute "VOLTAGE" "+3.3V"
					( Units "uVoltage" "V" 1.000000)
					( Origin gFrontEnd )
				)
				( attribute "CDS_PHYS_NET_NAME" "P3V3_STBY_BMC_ADCAV33"
					( Origin gPackager )
				)
				( objectFlag fObjectAlias )
				( objectStatus "page147_vcc_adcav3v3" )
			)
			( signal "@baseboard_fab2_lib.baseboard_fab2(sch_1):fm_bios_usb_recovery"
				( attribute "CDS_PHYS_NET_NAME" "FM_BIOS_USB_RECOVERY"
					( Origin gPackager )
				)
				( objectStatus "FM_BIOS_USB_RECOVERY" )
			)
			( signal "@baseboard_fab2_lib.baseboard_fab2(sch_1):fm_bmc_nmi_n"
				( attribute "CDS_PHYS_NET_NAME" "FM_BMC_NMI_N"
					( Origin gPackager )
				)
				( attribute "PHYS_NET_NAME" "FM_BMC_NMI_N"
					( Origin gPackager )
				)
				( objectStatus "FM_BMC_NMI_N" )
			)
			( signal "@baseboard_fab2_lib.baseboard_fab2(sch_1):fm_board_sku_id0"
				( attribute "CDS_PHYS_NET_NAME" "FM_BOARD_SKU_ID0"
					( Origin gPackager )
				)
				( attribute "PHYS_NET_NAME" "FM_BOARD_SKU_ID0"
					( Origin gPackager )
				)
				( objectStatus "FM_BOARD_SKU_ID0" )
			)
			( signal "@baseboard_fab2_lib.baseboard_fab2(sch_1):page148_vcc_dacav3v3"
				( objectFlag fObjectAlias )
				( objectStatus "page148_vcc_dacav3v3" )
			)
			( signal "@baseboard_fab2_lib.baseboard_fab2(sch_1):fm_board_sku_id1"
				( attribute "CDS_PHYS_NET_NAME" "FM_BOARD_SKU_ID1"
					( Origin gPackager )
				)
				( attribute "PHYS_NET_NAME" "FM_BOARD_SKU_ID1"
					( Origin gPackager )
				)
				( objectStatus "FM_BOARD_SKU_ID1" )
			)
			( signal "@baseboard_fab2_lib.baseboard_fab2(sch_1):fm_board_sku_id2"
				( attribute "CDS_PHYS_NET_NAME" "FM_BOARD_SKU_ID2"
					( Origin gPackager )
				)
				( attribute "PHYS_NET_NAME" "FM_BOARD_SKU_ID2"
					( Origin gPackager )
				)
				( objectStatus "FM_BOARD_SKU_ID2" )
			)
			( signal "@baseboard_fab2_lib.baseboard_fab2(sch_1):fm_board_sku_id3"
				( attribute "CDS_PHYS_NET_NAME" "FM_BOARD_SKU_ID3"
					( Origin gPackager )
				)
				( attribute "PHYS_NET_NAME" "FM_BOARD_SKU_ID3"
					( Origin gPackager )
				)
				( objectStatus "FM_BOARD_SKU_ID3" )
			)
			( signal "@baseboard_fab2_lib.baseboard_fab2(sch_1):fm_board_sku_id4"
				( attribute "CDS_PHYS_NET_NAME" "FM_BOARD_SKU_ID4"
					( Origin gPackager )
				)
				( attribute "PHYS_NET_NAME" "FM_BOARD_SKU_ID4"
					( Origin gPackager )
				)
				( objectStatus "FM_BOARD_SKU_ID4" )
			)
			( signal "@baseboard_fab2_lib.baseboard_fab2(sch_1):fm_cpld_adr_trigger_n"
				( attribute "CDS_PHYS_NET_NAME" "FM_CPLD_ADR_TRIGGER_N"
					( Origin gPackager )
				)
				( objectStatus "FM_CPLD_ADR_TRIGGER_N" )
			)
			( signal "@baseboard_fab2_lib.baseboard_fab2(sch_1):fm_cpld_adr_trigger_r_n"
				( attribute "CDS_PHYS_NET_NAME" "FM_CPLD_ADR_TRIGGER_R_N"
					( Origin gPackager )
				)
				( objectStatus "FM_CPLD_ADR_TRIGGER_R_N" )
			)
			( signal "@baseboard_fab2_lib.baseboard_fab2(sch_1):fm_cpu0_fivr_fault_lvt3_n"
				( attribute "CDS_PHYS_NET_NAME" "FM_CPU0_FIVR_FAULT_LVT3_N"
					( Origin gPackager )
				)
				( objectStatus "FM_CPU0_FIVR_FAULT_LVT3_N" )
			)
			( signal "@baseboard_fab2_lib.baseboard_fab2(sch_1):fm_cpu0_rc_en"
				( attribute "CDS_PHYS_NET_NAME" "FM_CPU0_RC_EN"
					( Origin gPackager )
				)
				( objectStatus "FM_CPU0_RC_EN" )
			)
			( signal "@baseboard_fab2_lib.baseboard_fab2(sch_1):fm_cpu1_fivr_fault_lvt3_n"
				( attribute "CDS_PHYS_NET_NAME" "FM_CPU1_FIVR_FAULT_LVT3_N"
					( Origin gPackager )
				)
				( objectStatus "FM_CPU1_FIVR_FAULT_LVT3_N" )
			)
			( signal "@baseboard_fab2_lib.baseboard_fab2(sch_1):fm_cpu1_thermtrip_latch_lvt3_n"
				( attribute "CDS_PHYS_NET_NAME" "FM_CPU1_THERMTRIP_LATCH_LVT3_N"
					( Origin gPackager )
				)
				( objectStatus "FM_CPU1_THERMTRIP_LATCH_LVT3_N" )
			)
			( signal "@baseboard_fab2_lib.baseboard_fab2(sch_1):fm_flash_attach_cfg_strap"
				( attribute "CDS_PHYS_NET_NAME" "FM_FLASH_ATTACH_CFG_STRAP"
					( Origin gPackager )
				)
				( objectStatus "FM_FLASH_ATTACH_CFG_STRAP" )
			)
			( signal "@baseboard_fab2_lib.baseboard_fab2(sch_1):fm_force_adr_n"
				( attribute "CDS_PHYS_NET_NAME" "FM_FORCE_ADR_N"
					( Origin gPackager )
				)
				( attribute "PHYS_NET_NAME" "FM_FORCE_ADR_N"
					( Origin gPackager )
				)
				( objectStatus "FM_FORCE_ADR_N" )
			)
			( signal "@baseboard_fab2_lib.baseboard_fab2(sch_1):tp_smb_storage_bp_3v3aux_sda"
				( attribute "CDS_PHYS_NET_NAME" "TP_SMB_STORAGE_BP_3V3AUX_SDA"
					( Origin gPackager )
				)
				( objectStatus "TP_SMB_STORAGE_BP_3V3AUX_SDA" )
			)
			( signal "@baseboard_fab2_lib.baseboard_fab2(sch_1):fm_gbe0_lvc3_mod_abs"
				( attribute "CDS_PHYS_NET_NAME" "FM_GBE0_LVC3_MOD_ABS"
					( Origin gPackager )
				)
				( objectStatus "FM_GBE0_LVC3_MOD_ABS" )
			)
			( signal "@baseboard_fab2_lib.baseboard_fab2(sch_1):fm_gbe1_lvc3_mod_abs"
				( attribute "CDS_PHYS_NET_NAME" "FM_GBE1_LVC3_MOD_ABS"
					( Origin gPackager )
				)
				( objectStatus "FM_GBE1_LVC3_MOD_ABS" )
			)
			( signal "@baseboard_fab2_lib.baseboard_fab2(sch_1):fm_gbe2_lvc3_mod_abs"
				( attribute "CDS_PHYS_NET_NAME" "FM_GBE2_LVC3_MOD_ABS"
					( Origin gPackager )
				)
				( objectStatus "FM_GBE2_LVC3_MOD_ABS" )
			)
			( signal "@baseboard_fab2_lib.baseboard_fab2(sch_1):fm_gbe3_lvc3_mod_abs"
				( attribute "CDS_PHYS_NET_NAME" "FM_GBE3_LVC3_MOD_ABS"
					( Origin gPackager )
				)
				( objectStatus "FM_GBE3_LVC3_MOD_ABS" )
			)
			( signal "@baseboard_fab2_lib.baseboard_fab2(sch_1):fm_hsc_timer_exp_n"
				( attribute "CDS_PHYS_NET_NAME" "FM_HSC_TIMER_EXP_N"
					( Origin gPackager )
				)
				( attribute "PHYS_NET_NAME" "FM_HSC_TIMER_EXP_N"
					( Origin gPackager )
				)
				( objectStatus "FM_HSC_TIMER_EXP_N" )
			)
			( signal "@baseboard_fab2_lib.baseboard_fab2(sch_1):fm_ie_disable_n"
				( attribute "CDS_PHYS_NET_NAME" "FM_IE_DISABLE_N"
					( Origin gPackager )
				)
				( objectStatus "FM_IE_DISABLE_N" )
			)
			( signal "@baseboard_fab2_lib.baseboard_fab2(sch_1):fm_mem_therm_event_pch_n"
				( attribute "CDS_PHYS_NET_NAME" "FM_MEM_THERM_EVENT_PCH_N"
					( Origin gPackager )
				)
				( attribute "PHYS_NET_NAME" "FM_MEM_THERM_EVENT_PCH_N"
					( Origin gPackager )
				)
				( objectStatus "FM_MEM_THERM_EVENT_PCH_N" )
			)
			( signal "@baseboard_fab2_lib.baseboard_fab2(sch_1):fm_mp_ps_fail_n"
				( attribute "CDS_PHYS_NET_NAME" "FM_MP_PS_FAIL_N"
					( Origin gPackager )
				)
				( attribute "PHYS_NET_NAME" "FM_MP_PS_FAIL_N"
					( Origin gPackager )
				)
				( objectStatus "FM_MP_PS_FAIL_N" )
			)
			( signal "@baseboard_fab2_lib.baseboard_fab2(sch_1):fm_mp_ps_redundant_lost_n"
				( attribute "CDS_PHYS_NET_NAME" "FM_MP_PS_REDUNDANT_LOST_N"
					( Origin gPackager )
				)
				( attribute "PHYS_NET_NAME" "FM_MP_PS_REDUNDANT_LOST_N"
					( Origin gPackager )
				)
				( objectStatus "FM_MP_PS_REDUNDANT_LOST_N" )
			)
			( signal "@baseboard_fab2_lib.baseboard_fab2(sch_1):fm_nmi_event_n"
				( attribute "CDS_PHYS_NET_NAME" "FM_NMI_EVENT_N"
					( Origin gPackager )
				)
				( objectStatus "FM_NMI_EVENT_N" )
			)
			( signal "@baseboard_fab2_lib.baseboard_fab2(sch_1):fm_oc0_usb_n"
				( attribute "CDS_PHYS_NET_NAME" "FM_OC0_USB_N"
					( Origin gPackager )
				)
				( objectStatus "FM_OC0_USB_N" )
			)
			( signal "@baseboard_fab2_lib.baseboard_fab2(sch_1):fm_oc_detect_en_n"
				( alias ( signalRef "@baseboard_fab2_lib.baseboard_fab2(sch_1):page145_fm_oc_detect_en_n") )
				( attribute "CDS_PHYS_NET_NAME" "FM_OC_DETECT_EN_N"
					( Origin gPackager )
				)
				( attribute "PHYS_NET_NAME" "FM_OC_DETECT_EN_N"
					( Origin gPackager )
				)
				( objectStatus "FM_OC_DETECT_EN_N" )
			)
			( signal "@baseboard_fab2_lib.baseboard_fab2(sch_1):page145_fm_oc_detect_en_n"
				( attribute "CDS_PHYS_NET_NAME" "FM_OC_DETECT_EN_N"
					( Origin gPackager )
				)
				( attribute "PHYS_NET_NAME" "FM_OC_DETECT_EN_N"
					( Origin gFrontEnd )
				)
				( objectFlag fObjectAlias )
				( objectStatus "page145_fm_oc_detect_en_n" )
			)
			( signal "@baseboard_fab2_lib.baseboard_fab2(sch_1):fm_pch_bmc_thermtrip_n"
				( attribute "CDS_PHYS_NET_NAME" "FM_PCH_BMC_THERMTRIP_N"
					( Origin gPackager )
				)
				( attribute "PHYS_NET_NAME" "FM_PCH_BMC_THERMTRIP_N"
					( Origin gPackager )
				)
				( objectStatus "FM_PCH_BMC_THERMTRIP_N" )
			)
			( signal "@baseboard_fab2_lib.baseboard_fab2(sch_1):fm_sol_uart_ch_sel"
				( attribute "CDS_PHYS_NET_NAME" "FM_SOL_UART_CH_SEL"
					( Origin gPackager )
				)
				( attribute "PHYS_NET_NAME" "FM_SOL_UART_CH_SEL"
					( Origin gPackager )
				)
				( objectStatus "FM_SOL_UART_CH_SEL" )
			)
			( signal "@baseboard_fab2_lib.baseboard_fab2(sch_1):fm_ssata_pcie_m2_sel"
				( attribute "CDS_PHYS_NET_NAME" "FM_SSATA_PCIE_M2_SEL"
					( Origin gPackager )
				)
				( objectStatus "FM_SSATA_PCIE_M2_SEL" )
			)
			( signal "@baseboard_fab2_lib.baseboard_fab2(sch_1):fm_uartsw_lsb_n"
				( attribute "CDS_PHYS_NET_NAME" "FM_UARTSW_LSB_N"
					( Origin gPackager )
				)
				( attribute "PHYS_NET_NAME" "FM_UARTSW_LSB_N"
					( Origin gPackager )
				)
				( objectStatus "FM_UARTSW_LSB_N" )
			)
			( signal "@baseboard_fab2_lib.baseboard_fab2(sch_1):tp_smb_storage_bp_3v3aux_scl"
				( attribute "CDS_PHYS_NET_NAME" "TP_SMB_STORAGE_BP_3V3AUX_SCL"
					( Origin gPackager )
				)
				( objectStatus "TP_SMB_STORAGE_BP_3V3AUX_SCL" )
			)
			( signal "@baseboard_fab2_lib.baseboard_fab2(sch_1):fm_uartsw_msb_n"
				( attribute "CDS_PHYS_NET_NAME" "FM_UARTSW_MSB_N"
					( Origin gPackager )
				)
				( attribute "PHYS_NET_NAME" "FM_UARTSW_MSB_N"
					( Origin gPackager )
				)
				( objectStatus "FM_UARTSW_MSB_N" )
			)
			( signal "@baseboard_fab2_lib.baseboard_fab2(sch_1):smb_ipmb_3v3aux_sda"
				( attribute "CDS_PHYS_NET_NAME" "SMB_IPMB_3V3AUX_SDA"
					( Origin gPackager )
				)
				( objectStatus "SMB_IPMB_3V3AUX_SDA" )
			)
			( signal "@baseboard_fab2_lib.baseboard_fab2(sch_1):fp_pwr_id_led_n"
				( attribute "CDS_PHYS_NET_NAME" "FP_PWR_ID_LED_N"
					( Origin gPackager )
				)
				( attribute "PHYS_NET_NAME" "FP_PWR_ID_LED_N"
					( Origin gPackager )
				)
				( objectStatus "FP_PWR_ID_LED_N" )
			)
			( signal "@baseboard_fab2_lib.baseboard_fab2(sch_1):irq_bmc_pch_nmi_stby_n"
				( attribute "CDS_PHYS_NET_NAME" "IRQ_BMC_PCH_NMI_STBY_N"
					( Origin gPackager )
				)
				( attribute "PHYS_NET_NAME" "IRQ_BMC_PCH_NMI_STBY_N"
					( Origin gPackager )
				)
				( objectStatus "IRQ_BMC_PCH_NMI_STBY_N" )
			)
			( signal "@baseboard_fab2_lib.baseboard_fab2(sch_1):irq_board_bmc_alert_n"
				( alias ( signalRef "@baseboard_fab2_lib.baseboard_fab2(sch_1):page145_irq_board_bmc_alert_n") )
				( attribute "CDS_PHYS_NET_NAME" "IRQ_BOARD_BMC_ALERT_N"
					( Origin gPackager )
				)
				( attribute "PHYS_NET_NAME" "IRQ_BOARD_BMC_ALERT_N"
					( Origin gPackager )
				)
				( objectStatus "IRQ_BOARD_BMC_ALERT_N" )
			)
			( signal "@baseboard_fab2_lib.baseboard_fab2(sch_1):page145_irq_board_bmc_alert_n"
				( attribute "CDS_PHYS_NET_NAME" "IRQ_BOARD_BMC_ALERT_N"
					( Origin gPackager )
				)
				( attribute "PHYS_NET_NAME" "IRQ_BOARD_BMC_ALERT_N"
					( Origin gFrontEnd )
				)
				( objectFlag fObjectAlias )
				( objectStatus "page145_irq_board_bmc_alert_n" )
			)
			( signal "@baseboard_fab2_lib.baseboard_fab2(sch_1):irq_oc_detect_n"
				( attribute "CDS_PHYS_NET_NAME" "IRQ_OC_DETECT_N"
					( Origin gPackager )
				)
				( attribute "PHYS_NET_NAME" "IRQ_OC_DETECT_N"
					( Origin gPackager )
				)
				( objectStatus "IRQ_OC_DETECT_N" )
			)
			( signal "@baseboard_fab2_lib.baseboard_fab2(sch_1):irq_uv_detect_n"
				( attribute "CDS_PHYS_NET_NAME" "IRQ_UV_DETECT_N"
					( Origin gPackager )
				)
				( attribute "PHYS_NET_NAME" "IRQ_UV_DETECT_N"
					( Origin gPackager )
				)
				( objectStatus "IRQ_UV_DETECT_N" )
			)
			( signal "@baseboard_fab2_lib.baseboard_fab2(sch_1):jtag_pch_gbe_clk"
				( attribute "CDS_PHYS_NET_NAME" "JTAG_PCH_GBE_CLK"
					( Origin gPackager )
				)
				( objectStatus "JTAG_PCH_GBE_CLK" )
			)
			( signal "@baseboard_fab2_lib.baseboard_fab2(sch_1):jtag_pch_gbe_tdi"
				( attribute "CDS_PHYS_NET_NAME" "JTAG_PCH_GBE_TDI"
					( Origin gPackager )
				)
				( objectStatus "JTAG_PCH_GBE_TDI" )
			)
			( signal "@baseboard_fab2_lib.baseboard_fab2(sch_1):jtag_pch_gbe_tdo"
				( attribute "CDS_PHYS_NET_NAME" "JTAG_PCH_GBE_TDO"
					( Origin gPackager )
				)
				( objectStatus "JTAG_PCH_GBE_TDO" )
			)
			( signal "@baseboard_fab2_lib.baseboard_fab2(sch_1):jtag_pch_gbe_tms"
				( attribute "CDS_PHYS_NET_NAME" "JTAG_PCH_GBE_TMS"
					( Origin gPackager )
				)
				( objectStatus "JTAG_PCH_GBE_TMS" )
			)
			( signal "@baseboard_fab2_lib.baseboard_fab2(sch_1):jtag_pch_gbe_trst_n"
				( attribute "CDS_PHYS_NET_NAME" "JTAG_PCH_GBE_TRST_N"
					( Origin gPackager )
				)
				( objectStatus "JTAG_PCH_GBE_TRST_N" )
			)
			( signal "@baseboard_fab2_lib.baseboard_fab2(sch_1):jtag_pch_pld_tck"
				( attribute "CDS_PHYS_NET_NAME" "JTAG_PCH_PLD_TCK"
					( Origin gPackager )
				)
				( objectStatus "JTAG_PCH_PLD_TCK" )
			)
			( signal "@baseboard_fab2_lib.baseboard_fab2(sch_1):jtag_pch_pld_tdi"
				( attribute "CDS_PHYS_NET_NAME" "JTAG_PCH_PLD_TDI"
					( Origin gPackager )
				)
				( objectStatus "JTAG_PCH_PLD_TDI" )
			)
			( signal "@baseboard_fab2_lib.baseboard_fab2(sch_1):jtag_pch_pld_tdo"
				( attribute "CDS_PHYS_NET_NAME" "JTAG_PCH_PLD_TDO"
					( Origin gPackager )
				)
				( objectStatus "JTAG_PCH_PLD_TDO" )
			)
			( signal "@baseboard_fab2_lib.baseboard_fab2(sch_1):jtag_pch_pld_tms"
				( attribute "CDS_PHYS_NET_NAME" "JTAG_PCH_PLD_TMS"
					( Origin gPackager )
				)
				( objectStatus "JTAG_PCH_PLD_TMS" )
			)
			( signal "@baseboard_fab2_lib.baseboard_fab2(sch_1):led_gbe_p0_0"
				( attribute "CDS_PHYS_NET_NAME" "LED_GBE_P0_0"
					( Origin gPackager )
				)
				( objectStatus "LED_GBE_P0_0" )
			)
			( signal "@baseboard_fab2_lib.baseboard_fab2(sch_1):led_gbe_p0_1"
				( attribute "CDS_PHYS_NET_NAME" "LED_GBE_P0_1"
					( Origin gPackager )
				)
				( objectStatus "LED_GBE_P0_1" )
			)
			( signal "@baseboard_fab2_lib.baseboard_fab2(sch_1):led_gbe_p1_0"
				( attribute "CDS_PHYS_NET_NAME" "LED_GBE_P1_0"
					( Origin gPackager )
				)
				( objectStatus "LED_GBE_P1_0" )
			)
			( signal "@baseboard_fab2_lib.baseboard_fab2(sch_1):led_gbe_p1_1"
				( attribute "CDS_PHYS_NET_NAME" "LED_GBE_P1_1"
					( Origin gPackager )
				)
				( objectStatus "LED_GBE_P1_1" )
			)
			( signal "@baseboard_fab2_lib.baseboard_fab2(sch_1):led_gbe_p2_0"
				( attribute "CDS_PHYS_NET_NAME" "LED_GBE_P2_0"
					( Origin gPackager )
				)
				( objectStatus "LED_GBE_P2_0" )
			)
			( signal "@baseboard_fab2_lib.baseboard_fab2(sch_1):led_gbe_p2_1"
				( attribute "CDS_PHYS_NET_NAME" "LED_GBE_P2_1"
					( Origin gPackager )
				)
				( objectStatus "LED_GBE_P2_1" )
			)
			( signal "@baseboard_fab2_lib.baseboard_fab2(sch_1):led_gbe_p3_0"
				( attribute "CDS_PHYS_NET_NAME" "LED_GBE_P3_0"
					( Origin gPackager )
				)
				( objectStatus "LED_GBE_P3_0" )
			)
			( signal "@baseboard_fab2_lib.baseboard_fab2(sch_1):led_gbe_p3_1"
				( attribute "CDS_PHYS_NET_NAME" "LED_GBE_P3_1"
					( Origin gPackager )
				)
				( objectStatus "LED_GBE_P3_1" )
			)
			( signal "@baseboard_fab2_lib.baseboard_fab2(sch_1):led_pch_sata_hdd_n"
				( attribute "CDS_PHYS_NET_NAME" "LED_PCH_SATA_HDD_N"
					( Origin gPackager )
				)
				( objectStatus "LED_PCH_SATA_HDD_N" )
			)
			( signal "@baseboard_fab2_lib.baseboard_fab2(sch_1):led_pch_ssata_hdd_n"
				( attribute "CDS_PHYS_NET_NAME" "LED_PCH_SSATA_HDD_N"
					( Origin gPackager )
				)
				( objectStatus "LED_PCH_SSATA_HDD_N" )
			)
			( signal "@baseboard_fab2_lib.baseboard_fab2(sch_1):led_postcode_0"
				( attribute "CDS_PHYS_NET_NAME" "LED_POSTCODE_0"
					( Origin gPackager )
				)
				( attribute "PHYS_NET_NAME" "LED_POSTCODE_0"
					( Origin gPackager )
				)
				( objectStatus "LED_POSTCODE_0" )
			)
			( signal "@baseboard_fab2_lib.baseboard_fab2(sch_1):led_postcode_1"
				( attribute "CDS_PHYS_NET_NAME" "LED_POSTCODE_1"
					( Origin gPackager )
				)
				( attribute "PHYS_NET_NAME" "LED_POSTCODE_1"
					( Origin gPackager )
				)
				( objectStatus "LED_POSTCODE_1" )
			)
			( signal "@baseboard_fab2_lib.baseboard_fab2(sch_1):led_postcode_2"
				( attribute "CDS_PHYS_NET_NAME" "LED_POSTCODE_2"
					( Origin gPackager )
				)
				( attribute "PHYS_NET_NAME" "LED_POSTCODE_2"
					( Origin gPackager )
				)
				( objectStatus "LED_POSTCODE_2" )
			)
			( signal "@baseboard_fab2_lib.baseboard_fab2(sch_1):led_postcode_3"
				( attribute "CDS_PHYS_NET_NAME" "LED_POSTCODE_3"
					( Origin gPackager )
				)
				( attribute "PHYS_NET_NAME" "LED_POSTCODE_3"
					( Origin gPackager )
				)
				( objectStatus "LED_POSTCODE_3" )
			)
			( signal "@baseboard_fab2_lib.baseboard_fab2(sch_1):led_postcode_4"
				( attribute "CDS_PHYS_NET_NAME" "LED_POSTCODE_4"
					( Origin gPackager )
				)
				( attribute "PHYS_NET_NAME" "LED_POSTCODE_4"
					( Origin gPackager )
				)
				( objectStatus "LED_POSTCODE_4" )
			)
			( signal "@baseboard_fab2_lib.baseboard_fab2(sch_1):led_postcode_5"
				( attribute "CDS_PHYS_NET_NAME" "LED_POSTCODE_5"
					( Origin gPackager )
				)
				( attribute "PHYS_NET_NAME" "LED_POSTCODE_5"
					( Origin gPackager )
				)
				( objectStatus "LED_POSTCODE_5" )
			)
			( signal "@baseboard_fab2_lib.baseboard_fab2(sch_1):led_postcode_6"
				( attribute "CDS_PHYS_NET_NAME" "LED_POSTCODE_6"
					( Origin gPackager )
				)
				( attribute "PHYS_NET_NAME" "LED_POSTCODE_6"
					( Origin gPackager )
				)
				( objectStatus "LED_POSTCODE_6" )
			)
			( signal "@baseboard_fab2_lib.baseboard_fab2(sch_1):led_postcode_7"
				( attribute "CDS_PHYS_NET_NAME" "LED_POSTCODE_7"
					( Origin gPackager )
				)
				( attribute "PHYS_NET_NAME" "LED_POSTCODE_7"
					( Origin gPackager )
				)
				( objectStatus "LED_POSTCODE_7" )
			)
			( signal "@baseboard_fab2_lib.baseboard_fab2(sch_1):pu_10gbe_lom_pci_disable_n"
				( attribute "CDS_PHYS_NET_NAME" "PU_10GBE_LOM_PCI_DISABLE_N"
					( Origin gPackager )
				)
				( objectStatus "PU_10GBE_LOM_PCI_DISABLE_N" )
			)
			( signal "@baseboard_fab2_lib.baseboard_fab2(sch_1):pu_adr_timer_hold_off_n"
				( attribute "CDS_PHYS_NET_NAME" "PU_ADR_TIMER_HOLD_OFF_N"
					( Origin gPackager )
				)
				( objectStatus "PU_ADR_TIMER_HOLD_OFF_N" )
			)
			( signal "@baseboard_fab2_lib.baseboard_fab2(sch_1):sgpio_pch_sata_clock"
				( attribute "CDS_PHYS_NET_NAME" "SGPIO_PCH_SATA_CLOCK"
					( Origin gPackager )
				)
				( objectStatus "SGPIO_PCH_SATA_CLOCK" )
			)
			( signal "@baseboard_fab2_lib.baseboard_fab2(sch_1):sgpio_pch_sata_dout0"
				( attribute "CDS_PHYS_NET_NAME" "SGPIO_PCH_SATA_DOUT0"
					( Origin gPackager )
				)
				( objectStatus "SGPIO_PCH_SATA_DOUT0" )
			)
			( signal "@baseboard_fab2_lib.baseboard_fab2(sch_1):sgpio_pch_sata_load"
				( attribute "CDS_PHYS_NET_NAME" "SGPIO_PCH_SATA_LOAD"
					( Origin gPackager )
				)
				( objectStatus "SGPIO_PCH_SATA_LOAD" )
			)
			( signal "@baseboard_fab2_lib.baseboard_fab2(sch_1):sgpio_pch_ssata_clock"
				( attribute "CDS_PHYS_NET_NAME" "SGPIO_PCH_SSATA_CLOCK"
					( Origin gPackager )
				)
				( objectStatus "SGPIO_PCH_SSATA_CLOCK" )
			)
			( signal "@baseboard_fab2_lib.baseboard_fab2(sch_1):sgpio_pch_ssata_load"
				( attribute "CDS_PHYS_NET_NAME" "SGPIO_PCH_SSATA_LOAD"
					( Origin gPackager )
				)
				( objectStatus "SGPIO_PCH_SSATA_LOAD" )
			)
			( signal "@baseboard_fab2_lib.baseboard_fab2(sch_1):smb_lan_stby_lvc3_scl_r1"
				( attribute "CDS_PHYS_NET_NAME" "SMB_LAN_STBY_LVC3_SCL_R1"
					( Origin gPackager )
				)
				( objectStatus "SMB_LAN_STBY_LVC3_SCL_R1" )
			)
			( signal "@baseboard_fab2_lib.baseboard_fab2(sch_1):smb_lan_stby_lvc3_scl_r2"
				( attribute "CDS_PHYS_NET_NAME" "SMB_LAN_STBY_LVC3_SCL_R2"
					( Origin gPackager )
				)
				( objectStatus "SMB_LAN_STBY_LVC3_SCL_R2" )
			)
			( signal "@baseboard_fab2_lib.baseboard_fab2(sch_1):smb_lan_stby_lvc3_sda_r1"
				( attribute "CDS_PHYS_NET_NAME" "SMB_LAN_STBY_LVC3_SDA_R1"
					( Origin gPackager )
				)
				( objectStatus "SMB_LAN_STBY_LVC3_SDA_R1" )
			)
			( signal "@baseboard_fab2_lib.baseboard_fab2(sch_1):smb_lan_stby_lvc3_sda_r2"
				( attribute "CDS_PHYS_NET_NAME" "SMB_LAN_STBY_LVC3_SDA_R2"
					( Origin gPackager )
				)
				( objectStatus "SMB_LAN_STBY_LVC3_SDA_R2" )
			)
			( signal "@baseboard_fab2_lib.baseboard_fab2(sch_1):smb_pch_mezz_lom0_scl"
				( attribute "CDS_PHYS_NET_NAME" "SMB_PCH_MEZZ_LOM0_SCL"
					( Origin gPackager )
				)
				( objectStatus "SMB_PCH_MEZZ_LOM0_SCL" )
			)
			( signal "@baseboard_fab2_lib.baseboard_fab2(sch_1):smb_pch_mezz_lom0_sda"
				( attribute "CDS_PHYS_NET_NAME" "SMB_PCH_MEZZ_LOM0_SDA"
					( Origin gPackager )
				)
				( objectStatus "SMB_PCH_MEZZ_LOM0_SDA" )
			)
			( signal "@baseboard_fab2_lib.baseboard_fab2(sch_1):smb_pch_mezz_lom1_scl"
				( attribute "CDS_PHYS_NET_NAME" "SMB_PCH_MEZZ_LOM1_SCL"
					( Origin gPackager )
				)
				( objectStatus "SMB_PCH_MEZZ_LOM1_SCL" )
			)
			( signal "@baseboard_fab2_lib.baseboard_fab2(sch_1):smb_pch_mezz_lom1_sda"
				( attribute "CDS_PHYS_NET_NAME" "SMB_PCH_MEZZ_LOM1_SDA"
					( Origin gPackager )
				)
				( objectStatus "SMB_PCH_MEZZ_LOM1_SDA" )
			)
			( signal "@baseboard_fab2_lib.baseboard_fab2(sch_1):smb_pch_mezz_lom2_scl"
				( attribute "CDS_PHYS_NET_NAME" "SMB_PCH_MEZZ_LOM2_SCL"
					( Origin gPackager )
				)
				( objectStatus "SMB_PCH_MEZZ_LOM2_SCL" )
			)
			( signal "@baseboard_fab2_lib.baseboard_fab2(sch_1):smb_pch_mezz_lom2_sda"
				( attribute "CDS_PHYS_NET_NAME" "SMB_PCH_MEZZ_LOM2_SDA"
					( Origin gPackager )
				)
				( objectStatus "SMB_PCH_MEZZ_LOM2_SDA" )
			)
			( signal "@baseboard_fab2_lib.baseboard_fab2(sch_1):smb_pch_mezz_lom3_scl"
				( attribute "CDS_PHYS_NET_NAME" "SMB_PCH_MEZZ_LOM3_SCL"
					( Origin gPackager )
				)
				( objectStatus "SMB_PCH_MEZZ_LOM3_SCL" )
			)
			( signal "@baseboard_fab2_lib.baseboard_fab2(sch_1):smb_pch_mezz_lom3_sda"
				( attribute "CDS_PHYS_NET_NAME" "SMB_PCH_MEZZ_LOM3_SDA"
					( Origin gPackager )
				)
				( objectStatus "SMB_PCH_MEZZ_LOM3_SDA" )
			)
			( signal "@baseboard_fab2_lib.baseboard_fab2(sch_1):smb_sensor_stby_lvc3_scl_r1"
				( attribute "CDS_PHYS_NET_NAME" "SMB_SENSOR_STBY_LVC3_SCL_R1"
					( Origin gPackager )
				)
				( objectStatus "SMB_SENSOR_STBY_LVC3_SCL_R1" )
			)
			( signal "@baseboard_fab2_lib.baseboard_fab2(sch_1):smb_sensor_stby_lvc3_sda_r1"
				( attribute "CDS_PHYS_NET_NAME" "SMB_SENSOR_STBY_LVC3_SDA_R1"
					( Origin gPackager )
				)
				( objectStatus "SMB_SENSOR_STBY_LVC3_SDA_R1" )
			)
			( signal "@baseboard_fab2_lib.baseboard_fab2(sch_1):smb_vr_stby_lvc3_scl_r1"
				( attribute "CDS_PHYS_NET_NAME" "SMB_VR_STBY_LVC3_SCL_R1"
					( Origin gPackager )
				)
				( objectStatus "SMB_VR_STBY_LVC3_SCL_R1" )
			)
			( signal "@baseboard_fab2_lib.baseboard_fab2(sch_1):smb_vr_stby_lvc3_sda_r1"
				( attribute "CDS_PHYS_NET_NAME" "SMB_VR_STBY_LVC3_SDA_R1"
					( Origin gPackager )
				)
				( objectStatus "SMB_VR_STBY_LVC3_SDA_R1" )
			)
			( signal "@baseboard_fab2_lib.baseboard_fab2(sch_1):tp_pch_gpp_f12"
				( attribute "CDS_PHYS_NET_NAME" "TP_PCH_GPP_F12"
					( Origin gPackager )
				)
				( objectStatus "TP_PCH_GPP_F12" )
			)
			( signal "@baseboard_fab2_lib.baseboard_fab2(sch_1):tp_pch_gpp_j17"
				( attribute "CDS_PHYS_NET_NAME" "TP_PCH_GPP_J17"
					( Origin gPackager )
				)
				( objectStatus "TP_PCH_GPP_J17" )
			)
			( signal "@baseboard_fab2_lib.baseboard_fab2(sch_1):tp_pch_gpp_j19"
				( attribute "CDS_PHYS_NET_NAME" "TP_PCH_GPP_J19"
					( Origin gPackager )
				)
				( objectStatus "TP_PCH_GPP_J19" )
			)
			( signal "@baseboard_fab2_lib.baseboard_fab2(sch_1):tp_pch_gpp_j21"
				( attribute "CDS_PHYS_NET_NAME" "TP_PCH_GPP_J21"
					( Origin gPackager )
				)
				( objectStatus "TP_PCH_GPP_J21" )
			)
			( signal "@baseboard_fab2_lib.baseboard_fab2(sch_1):tp_pch_gpp_j23"
				( attribute "CDS_PHYS_NET_NAME" "TP_PCH_GPP_J23"
					( Origin gPackager )
				)
				( objectStatus "TP_PCH_GPP_J23" )
			)
			( signal "@baseboard_fab2_lib.baseboard_fab2(sch_1):a_1p8_3p3_rcomp"
				( attribute "CDS_PHYS_NET_NAME" "A_1P8_3P3_RCOMP"
					( Origin gPackager )
				)
				( objectStatus "A_1P8_3P3_RCOMP" )
			)
			( signal "@baseboard_fab2_lib.baseboard_fab2(sch_1):fm_flash_desc_override"
				( attribute "CDS_PHYS_NET_NAME" "FM_FLASH_DESC_OVERRIDE"
					( Origin gPackager )
				)
				( objectStatus "FM_FLASH_DESC_OVERRIDE" )
			)
			( signal "@baseboard_fab2_lib.baseboard_fab2(sch_1):fm_intruder_hdr_pch_n"
				( attribute "CDS_PHYS_NET_NAME" "FM_INTRUDER_HDR_PCH_N"
					( Origin gPackager )
				)
				( objectStatus "FM_INTRUDER_HDR_PCH_N" )
			)
			( signal "@baseboard_fab2_lib.baseboard_fab2(sch_1):fm_ocp_mezzb_pres_n"
				( attribute "CDS_PHYS_NET_NAME" "FM_OCP_MEZZB_PRES_N"
					( Origin gPackager )
				)
				( objectStatus "FM_OCP_MEZZB_PRES_N" )
			)
			( signal "@baseboard_fab2_lib.baseboard_fab2(sch_1):fm_ocp_mezzc_pres_n"
				( attribute "CDS_PHYS_NET_NAME" "FM_OCP_MEZZC_PRES_N"
					( Origin gPackager )
				)
				( objectStatus "FM_OCP_MEZZC_PRES_N" )
			)
			( signal "@baseboard_fab2_lib.baseboard_fab2(sch_1):fm_pch_prsnt_n"
				( attribute "CDS_PHYS_NET_NAME" "FM_PCH_PRSNT_N"
					( Origin gPackager )
				)
				( objectStatus "FM_PCH_PRSNT_N" )
			)
			( signal "@baseboard_fab2_lib.baseboard_fab2(sch_1):fm_sint_prsnt_n"
				( attribute "CDS_PHYS_NET_NAME" "FM_SINT_PRSNT_N"
					( Origin gPackager )
				)
				( objectStatus "FM_SINT_PRSNT_N" )
			)
			( signal "@baseboard_fab2_lib.baseboard_fab2(sch_1):fm_wbg_prsnt_n"
				( attribute "CDS_PHYS_NET_NAME" "FM_WBG_PRSNT_N"
					( Origin gPackager )
				)
				( objectStatus "FM_WBG_PRSNT_N" )
			)
			( signal "@baseboard_fab2_lib.baseboard_fab2(sch_1):h_cpu0_memabc_memhot_pch_n"
				( attribute "CDS_PHYS_NET_NAME" "H_CPU0_MEMABC_MEMHOT_PCH_N"
					( Origin gPackager )
				)
				( objectStatus "H_CPU0_MEMABC_MEMHOT_PCH_N" )
			)
			( signal "@baseboard_fab2_lib.baseboard_fab2(sch_1):h_cpu0_memdef_memhot_pch_n"
				( attribute "CDS_PHYS_NET_NAME" "H_CPU0_MEMDEF_MEMHOT_PCH_N"
					( Origin gPackager )
				)
				( objectStatus "H_CPU0_MEMDEF_MEMHOT_PCH_N" )
			)
			( signal "@baseboard_fab2_lib.baseboard_fab2(sch_1):h_cpu1_memghj_memhot_pch_n"
				( attribute "CDS_PHYS_NET_NAME" "H_CPU1_MEMGHJ_MEMHOT_PCH_N"
					( Origin gPackager )
				)
				( objectStatus "H_CPU1_MEMGHJ_MEMHOT_PCH_N" )
			)
			( signal "@baseboard_fab2_lib.baseboard_fab2(sch_1):h_cpu1_memklm_memhot_pch_n"
				( attribute "CDS_PHYS_NET_NAME" "H_CPU1_MEMKLM_MEMHOT_PCH_N"
					( Origin gPackager )
				)
				( objectStatus "H_CPU1_MEMKLM_MEMHOT_PCH_N" )
			)
			( signal "@baseboard_fab2_lib.baseboard_fab2(sch_1):rmii_bmc_pch_sprngvlle_crsdv"
				( attribute "CDS_PHYS_NET_NAME" "RMII_BMC_PCH_SPRNGVLLE_CRSDV"
					( Origin gPackager )
				)
				( attribute "PHYS_NET_NAME" "RMII_BMC_PCH_SPRNGVLLE_CRSDV"
					( Origin gPackager )
				)
				( objectStatus "RMII_BMC_PCH_SPRNGVLLE_CRSDV" )
			)
			( signal "@baseboard_fab2_lib.baseboard_fab2(sch_1):rmii_bmc_pch_sprngvlle_crsdv_r1"
				( attribute "CDS_PHYS_NET_NAME" "RMII_BMC_PCH_SPRNGVLLE_CRSDV_R1"
					( Origin gPackager )
				)
				( objectStatus "RMII_BMC_PCH_SPRNGVLLE_CRSDV_R1" )
			)
			( signal "@baseboard_fab2_lib.baseboard_fab2(sch_1):rmii_bmc_pch_sprngvlle_rxer"
				( attribute "CDS_PHYS_NET_NAME" "RMII_BMC_PCH_SPRNGVLLE_RXER"
					( Origin gPackager )
				)
				( attribute "PHYS_NET_NAME" "RMII_BMC_PCH_SPRNGVLLE_RXER"
					( Origin gPackager )
				)
				( objectStatus "RMII_BMC_PCH_SPRNGVLLE_RXER" )
			)
			( signal "@baseboard_fab2_lib.baseboard_fab2(sch_1):rmii_bmc_pch_sprngvlle_rxer_r"
				( attribute "CDS_PHYS_NET_NAME" "RMII_BMC_PCH_SPRNGVLLE_RXER_R"
					( Origin gPackager )
				)
				( objectStatus "RMII_BMC_PCH_SPRNGVLLE_RXER_R" )
			)
			( signal "@baseboard_fab2_lib.baseboard_fab2(sch_1):rmii_bmc_pch_sprngvlle_txd0"
				( attribute "CDS_PHYS_NET_NAME" "RMII_BMC_PCH_SPRNGVLLE_TXD0"
					( Origin gPackager )
				)
				( objectStatus "RMII_BMC_PCH_SPRNGVLLE_TXD0" )
			)
			( signal "@baseboard_fab2_lib.baseboard_fab2(sch_1):rmii_bmc_pch_sprngvlle_txd1"
				( attribute "CDS_PHYS_NET_NAME" "RMII_BMC_PCH_SPRNGVLLE_TXD1"
					( Origin gPackager )
				)
				( objectStatus "RMII_BMC_PCH_SPRNGVLLE_TXD1" )
			)
			( signal "@baseboard_fab2_lib.baseboard_fab2(sch_1):rmii_bmc_pch_sprngvlle_txen"
				( attribute "CDS_PHYS_NET_NAME" "RMII_BMC_PCH_SPRNGVLLE_TXEN"
					( Origin gPackager )
				)
				( objectStatus "RMII_BMC_PCH_SPRNGVLLE_TXEN" )
			)
			( signal "@baseboard_fab2_lib.baseboard_fab2(sch_1):rmii_pch_sprngvlle_arb_in"
				( attribute "CDS_PHYS_NET_NAME" "RMII_PCH_SPRNGVLLE_ARB_IN"
					( Origin gPackager )
				)
				( objectStatus "RMII_PCH_SPRNGVLLE_ARB_IN" )
			)
			( signal "@baseboard_fab2_lib.baseboard_fab2(sch_1):rmii_pch_sprngvlle_arb_out"
				( attribute "CDS_PHYS_NET_NAME" "RMII_PCH_SPRNGVLLE_ARB_OUT"
					( Origin gPackager )
				)
				( objectStatus "RMII_PCH_SPRNGVLLE_ARB_OUT" )
			)
			( signal "@baseboard_fab2_lib.baseboard_fab2(sch_1):rmii_pch_sprngvlle_arb_out_r"
				( attribute "CDS_PHYS_NET_NAME" "RMII_PCH_SPRNGVLLE_ARB_OUT_R"
					( Origin gPackager )
				)
				( objectStatus "RMII_PCH_SPRNGVLLE_ARB_OUT_R" )
			)
			( signal "@baseboard_fab2_lib.baseboard_fab2(sch_1):rmii_sprngvlle_bmc_pch_rxd0"
				( attribute "CDS_PHYS_NET_NAME" "RMII_SPRNGVLLE_BMC_PCH_RXD0"
					( Origin gPackager )
				)
				( objectStatus "RMII_SPRNGVLLE_BMC_PCH_RXD0" )
			)
			( signal "@baseboard_fab2_lib.baseboard_fab2(sch_1):rmii_sprngvlle_bmc_pch_rxd0_r1"
				( attribute "CDS_PHYS_NET_NAME" "RMII_SPRNGVLLE_BMC_PCH_RXD0_R1"
					( Origin gPackager )
				)
				( objectStatus "RMII_SPRNGVLLE_BMC_PCH_RXD0_R1" )
			)
			( signal "@baseboard_fab2_lib.baseboard_fab2(sch_1):rmii_sprngvlle_bmc_pch_rxd1"
				( attribute "CDS_PHYS_NET_NAME" "RMII_SPRNGVLLE_BMC_PCH_RXD1"
					( Origin gPackager )
				)
				( objectStatus "RMII_SPRNGVLLE_BMC_PCH_RXD1" )
			)
			( signal "@baseboard_fab2_lib.baseboard_fab2(sch_1):rmii_sprngvlle_bmc_pch_rxd1_r1"
				( attribute "CDS_PHYS_NET_NAME" "RMII_SPRNGVLLE_BMC_PCH_RXD1_R1"
					( Origin gPackager )
				)
				( objectStatus "RMII_SPRNGVLLE_BMC_PCH_RXD1_R1" )
			)
			( signal "@baseboard_fab2_lib.baseboard_fab2(sch_1):rst_pcie_pch_perst_n"
				( attribute "CDS_PHYS_NET_NAME" "RST_PCIE_PCH_PERST_N"
					( Origin gPackager )
				)
				( objectStatus "RST_PCIE_PCH_PERST_N" )
			)
			( signal "@baseboard_fab2_lib.baseboard_fab2(sch_1):rst_rtcrst_n"
				( attribute "CDS_PHYS_NET_NAME" "RST_RTCRST_N"
					( Origin gPackager )
				)
				( objectStatus "RST_RTCRST_N" )
			)
			( signal "@baseboard_fab2_lib.baseboard_fab2(sch_1):rst_srtcrst_n"
				( attribute "CDS_PHYS_NET_NAME" "RST_SRTCRST_N"
					( Origin gPackager )
				)
				( objectStatus "RST_SRTCRST_N" )
			)
			( signal "@baseboard_fab2_lib.baseboard_fab2(sch_1):spi_pch_clk"
				( attribute "CDS_PHYS_NET_NAME" "SPI_PCH_CLK"
					( Origin gPackager )
				)
				( objectStatus "SPI_PCH_CLK" )
			)
			( signal "@baseboard_fab2_lib.baseboard_fab2(sch_1):spi_pch_cs0_n"
				( attribute "CDS_PHYS_NET_NAME" "SPI_PCH_CS0_N"
					( Origin gPackager )
				)
				( objectStatus "SPI_PCH_CS0_N" )
			)
			( signal "@baseboard_fab2_lib.baseboard_fab2(sch_1):spi_pch_cs0_r_n"
				( attribute "CDS_PHYS_NET_NAME" "SPI_PCH_CS0_R_N"
					( Origin gPackager )
				)
				( objectStatus "SPI_PCH_CS0_R_N" )
			)
			( signal "@baseboard_fab2_lib.baseboard_fab2(sch_1):spi_pch_io3"
				( attribute "CDS_PHYS_NET_NAME" "SPI_PCH_IO3"
					( Origin gPackager )
				)
				( objectStatus "SPI_PCH_IO3" )
			)
			( signal "@baseboard_fab2_lib.baseboard_fab2(sch_1):spi_pch_miso"
				( attribute "CDS_PHYS_NET_NAME" "SPI_PCH_MISO"
					( Origin gPackager )
				)
				( objectStatus "SPI_PCH_MISO" )
			)
			( signal "@baseboard_fab2_lib.baseboard_fab2(sch_1):spi_pch_mosi_r"
				( attribute "CDS_PHYS_NET_NAME" "SPI_PCH_MOSI_R"
					( Origin gPackager )
				)
				( objectStatus "SPI_PCH_MOSI_R" )
			)
			( signal "@baseboard_fab2_lib.baseboard_fab2(sch_1):spi_pch_tpm_cs_n"
				( attribute "CDS_PHYS_NET_NAME" "SPI_PCH_TPM_CS_N"
					( Origin gPackager )
				)
				( objectStatus "SPI_PCH_TPM_CS_N" )
			)
			( signal "@baseboard_fab2_lib.baseboard_fab2(sch_1):tp_pch_dispa_bclk"
				( attribute "CDS_PHYS_NET_NAME" "TP_PCH_DISPA_BCLK"
					( Origin gPackager )
				)
				( objectStatus "TP_PCH_DISPA_BCLK" )
			)
			( signal "@baseboard_fab2_lib.baseboard_fab2(sch_1):tp_pch_dispa_sdi"
				( attribute "CDS_PHYS_NET_NAME" "TP_PCH_DISPA_SDI"
					( Origin gPackager )
				)
				( objectStatus "TP_PCH_DISPA_SDI" )
			)
			( signal "@baseboard_fab2_lib.baseboard_fab2(sch_1):tp_pch_dispa_sdo"
				( attribute "CDS_PHYS_NET_NAME" "TP_PCH_DISPA_SDO"
					( Origin gPackager )
				)
				( objectStatus "TP_PCH_DISPA_SDO" )
			)
			( signal "@baseboard_fab2_lib.baseboard_fab2(sch_1):tp_pch_gpp_l10"
				( attribute "CDS_PHYS_NET_NAME" "TP_PCH_GPP_L10"
					( Origin gPackager )
				)
				( objectStatus "TP_PCH_GPP_L10" )
			)
			( signal "@baseboard_fab2_lib.baseboard_fab2(sch_1):tp_pch_gpp_l11"
				( attribute "CDS_PHYS_NET_NAME" "TP_PCH_GPP_L11"
					( Origin gPackager )
				)
				( objectStatus "TP_PCH_GPP_L11" )
			)
			( signal "@baseboard_fab2_lib.baseboard_fab2(sch_1):tp_pch_hda_bclk"
				( attribute "CDS_PHYS_NET_NAME" "TP_PCH_HDA_BCLK"
					( Origin gPackager )
				)
				( objectStatus "TP_PCH_HDA_BCLK" )
			)
			( signal "@baseboard_fab2_lib.baseboard_fab2(sch_1):tp_pch_hda_sdi_0"
				( attribute "CDS_PHYS_NET_NAME" "TP_PCH_HDA_SDI_0"
					( Origin gPackager )
				)
				( objectStatus "TP_PCH_HDA_SDI_0" )
			)
			( signal "@baseboard_fab2_lib.baseboard_fab2(sch_1):tp_pch_hda_sdi_1"
				( attribute "CDS_PHYS_NET_NAME" "TP_PCH_HDA_SDI_1"
					( Origin gPackager )
				)
				( objectStatus "TP_PCH_HDA_SDI_1" )
			)
			( signal "@baseboard_fab2_lib.baseboard_fab2(sch_1):tp_pch_hda_sync"
				( attribute "CDS_PHYS_NET_NAME" "TP_PCH_HDA_SYNC"
					( Origin gPackager )
				)
				( objectStatus "TP_PCH_HDA_SYNC" )
			)
			( signal "@baseboard_fab2_lib.baseboard_fab2(sch_1):tp_pch_hsa_rst_n"
				( attribute "CDS_PHYS_NET_NAME" "TP_PCH_HSA_RST_N"
					( Origin gPackager )
				)
				( objectStatus "TP_PCH_HSA_RST_N" )
			)
			( signal "@baseboard_fab2_lib.baseboard_fab2(sch_1):tp_pch_rsvd0"
				( attribute "CDS_PHYS_NET_NAME" "TP_PCH_RSVD0"
					( Origin gPackager )
				)
				( objectStatus "TP_PCH_RSVD0" )
			)
			( signal "@baseboard_fab2_lib.baseboard_fab2(sch_1):tp_pch_rsvd1"
				( attribute "CDS_PHYS_NET_NAME" "TP_PCH_RSVD1"
					( Origin gPackager )
				)
				( objectStatus "TP_PCH_RSVD1" )
			)
			( signal "@baseboard_fab2_lib.baseboard_fab2(sch_1):tp_pch_rsvd12"
				( attribute "CDS_PHYS_NET_NAME" "TP_PCH_RSVD12"
					( Origin gPackager )
				)
				( objectStatus "TP_PCH_RSVD12" )
			)
			( signal "@baseboard_fab2_lib.baseboard_fab2(sch_1):tp_pch_rsvd13"
				( attribute "CDS_PHYS_NET_NAME" "TP_PCH_RSVD13"
					( Origin gPackager )
				)
				( objectStatus "TP_PCH_RSVD13" )
			)
			( signal "@baseboard_fab2_lib.baseboard_fab2(sch_1):tp_pch_rsvd14"
				( attribute "CDS_PHYS_NET_NAME" "TP_PCH_RSVD14"
					( Origin gPackager )
				)
				( objectStatus "TP_PCH_RSVD14" )
			)
			( signal "@baseboard_fab2_lib.baseboard_fab2(sch_1):tp_pch_rsvd15"
				( attribute "CDS_PHYS_NET_NAME" "TP_PCH_RSVD15"
					( Origin gPackager )
				)
				( objectStatus "TP_PCH_RSVD15" )
			)
			( signal "@baseboard_fab2_lib.baseboard_fab2(sch_1):tp_pch_rsvd16"
				( attribute "CDS_PHYS_NET_NAME" "TP_PCH_RSVD16"
					( Origin gPackager )
				)
				( objectStatus "TP_PCH_RSVD16" )
			)
			( signal "@baseboard_fab2_lib.baseboard_fab2(sch_1):tp_pch_rsvd17"
				( attribute "CDS_PHYS_NET_NAME" "TP_PCH_RSVD17"
					( Origin gPackager )
				)
				( objectStatus "TP_PCH_RSVD17" )
			)
			( signal "@baseboard_fab2_lib.baseboard_fab2(sch_1):tp_pch_rsvd18"
				( attribute "CDS_PHYS_NET_NAME" "TP_PCH_RSVD18"
					( Origin gPackager )
				)
				( objectStatus "TP_PCH_RSVD18" )
			)
			( signal "@baseboard_fab2_lib.baseboard_fab2(sch_1):tp_pch_rsvd19"
				( attribute "CDS_PHYS_NET_NAME" "TP_PCH_RSVD19"
					( Origin gPackager )
				)
				( objectStatus "TP_PCH_RSVD19" )
			)
			( signal "@baseboard_fab2_lib.baseboard_fab2(sch_1):tp_pch_rsvd2"
				( attribute "CDS_PHYS_NET_NAME" "TP_PCH_RSVD2"
					( Origin gPackager )
				)
				( objectStatus "TP_PCH_RSVD2" )
			)
			( signal "@baseboard_fab2_lib.baseboard_fab2(sch_1):tp_pch_rsvd20"
				( attribute "CDS_PHYS_NET_NAME" "TP_PCH_RSVD20"
					( Origin gPackager )
				)
				( objectStatus "TP_PCH_RSVD20" )
			)
			( signal "@baseboard_fab2_lib.baseboard_fab2(sch_1):tp_pch_rsvd21"
				( attribute "CDS_PHYS_NET_NAME" "TP_PCH_RSVD21"
					( Origin gPackager )
				)
				( objectStatus "TP_PCH_RSVD21" )
			)
			( signal "@baseboard_fab2_lib.baseboard_fab2(sch_1):tp_pch_rsvd22"
				( attribute "CDS_PHYS_NET_NAME" "TP_PCH_RSVD22"
					( Origin gPackager )
				)
				( objectStatus "TP_PCH_RSVD22" )
			)
			( signal "@baseboard_fab2_lib.baseboard_fab2(sch_1):tp_pch_rsvd23"
				( attribute "CDS_PHYS_NET_NAME" "TP_PCH_RSVD23"
					( Origin gPackager )
				)
				( objectStatus "TP_PCH_RSVD23" )
			)
			( signal "@baseboard_fab2_lib.baseboard_fab2(sch_1):tp_pch_rsvd24"
				( attribute "CDS_PHYS_NET_NAME" "TP_PCH_RSVD24"
					( Origin gPackager )
				)
				( objectStatus "TP_PCH_RSVD24" )
			)
			( signal "@baseboard_fab2_lib.baseboard_fab2(sch_1):tp_pch_rsvd25"
				( attribute "CDS_PHYS_NET_NAME" "TP_PCH_RSVD25"
					( Origin gPackager )
				)
				( objectStatus "TP_PCH_RSVD25" )
			)
			( signal "@baseboard_fab2_lib.baseboard_fab2(sch_1):tp_pch_rsvd26"
				( attribute "CDS_PHYS_NET_NAME" "TP_PCH_RSVD26"
					( Origin gPackager )
				)
				( objectStatus "TP_PCH_RSVD26" )
			)
			( signal "@baseboard_fab2_lib.baseboard_fab2(sch_1):tp_pch_rsvd27"
				( attribute "CDS_PHYS_NET_NAME" "TP_PCH_RSVD27"
					( Origin gPackager )
				)
				( objectStatus "TP_PCH_RSVD27" )
			)
			( signal "@baseboard_fab2_lib.baseboard_fab2(sch_1):tp_pch_rsvd3"
				( attribute "CDS_PHYS_NET_NAME" "TP_PCH_RSVD3"
					( Origin gPackager )
				)
				( objectStatus "TP_PCH_RSVD3" )
			)
			( signal "@baseboard_fab2_lib.baseboard_fab2(sch_1):tp_pch_rsvd4"
				( attribute "CDS_PHYS_NET_NAME" "TP_PCH_RSVD4"
					( Origin gPackager )
				)
				( objectStatus "TP_PCH_RSVD4" )
			)
			( signal "@baseboard_fab2_lib.baseboard_fab2(sch_1):tp_pch_rsvd46"
				( attribute "CDS_PHYS_NET_NAME" "TP_PCH_RSVD46"
					( Origin gPackager )
				)
				( objectStatus "TP_PCH_RSVD46" )
			)
			( signal "@baseboard_fab2_lib.baseboard_fab2(sch_1):tp_pch_rsvd5"
				( attribute "CDS_PHYS_NET_NAME" "TP_PCH_RSVD5"
					( Origin gPackager )
				)
				( objectStatus "TP_PCH_RSVD5" )
			)
			( signal "@baseboard_fab2_lib.baseboard_fab2(sch_1):tp_pch_rsvd6"
				( attribute "CDS_PHYS_NET_NAME" "TP_PCH_RSVD6"
					( Origin gPackager )
				)
				( objectStatus "TP_PCH_RSVD6" )
			)
			( signal "@baseboard_fab2_lib.baseboard_fab2(sch_1):tp_pch_rsvd7"
				( attribute "CDS_PHYS_NET_NAME" "TP_PCH_RSVD7"
					( Origin gPackager )
				)
				( objectStatus "TP_PCH_RSVD7" )
			)
			( signal "@baseboard_fab2_lib.baseboard_fab2(sch_1):tp_pch_rsvd8"
				( attribute "CDS_PHYS_NET_NAME" "TP_PCH_RSVD8"
					( Origin gPackager )
				)
				( objectStatus "TP_PCH_RSVD8" )
			)
			( signal "@baseboard_fab2_lib.baseboard_fab2(sch_1):tp_pch_rsvd9"
				( attribute "CDS_PHYS_NET_NAME" "TP_PCH_RSVD9"
					( Origin gPackager )
				)
				( objectStatus "TP_PCH_RSVD9" )
			)
			( signal "@baseboard_fab2_lib.baseboard_fab2(sch_1):tp_spi_pch_cs1_r1_n"
				( attribute "CDS_PHYS_NET_NAME" "TP_SPI_PCH_CS1_R1_N"
					( Origin gPackager )
				)
				( objectStatus "TP_SPI_PCH_CS1_R1_N" )
			)
			( signal "@baseboard_fab2_lib.baseboard_fab2(sch_1):a_pvccrtc_ext_cap"
				( attribute "CDS_PHYS_NET_NAME" "A_PVCCRTC_EXT_CAP"
					( Origin gPackager )
				)
				( objectStatus "A_PVCCRTC_EXT_CAP" )
			)
			( signal "@baseboard_fab2_lib.baseboard_fab2(sch_1):p1v05_pch_stby_isclk_pll"
				( alias ( signalRef "@baseboard_fab2_lib.baseboard_fab2(sch_1):page122_p1v05_pch_stby_isclk_pll") )
				( alias ( signalRef "@baseboard_fab2_lib.baseboard_fab2(sch_1):page127_p1v05_pch_stby_isclk_pll") )
				( attribute "VOLTAGE" "1.05V"
					( Units "uVoltage" "V" 1.000000)
					( Status sAliasFlattened )
					( Origin gFrontEnd )
				)
				( attribute "CDS_PHYS_NET_NAME" "P1V05_PCH_STBY_ISCLK_PLL"
					( Origin gPackager )
				)
				( objectStatus "P1V05_PCH_STBY_ISCLK_PLL" )
			)
			( signal "@baseboard_fab2_lib.baseboard_fab2(sch_1):page122_p1v05_pch_stby_isclk_pll"
				( attribute "VOLTAGE" "1.05V"
					( Units "uVoltage" "V" 1.000000)
					( Origin gFrontEnd )
				)
				( objectFlag fObjectAlias )
				( objectStatus "page122_p1v05_pch_stby_isclk_pll" )
			)
			( signal "@baseboard_fab2_lib.baseboard_fab2(sch_1):page127_p1v05_pch_stby_isclk_pll"
				( attribute "VOLTAGE" "1.05V"
					( Units "uVoltage" "V" 1.000000)
					( Origin gFrontEnd )
				)
				( objectFlag fObjectAlias )
				( objectStatus "page127_p1v05_pch_stby_isclk_pll" )
			)
			( signal "@baseboard_fab2_lib.baseboard_fab2(sch_1):p1v05_pch_stby_vcca_pll0"
				( alias ( signalRef "@baseboard_fab2_lib.baseboard_fab2(sch_1):page122_p1v05_pch_stby_vcca_pll0") )
				( alias ( signalRef "@baseboard_fab2_lib.baseboard_fab2(sch_1):page127_p1v05_pch_stby_vcca_pll0") )
				( attribute "VOLTAGE" "1.05V"
					( Units "uVoltage" "V" 1.000000)
					( Status sAliasFlattened )
					( Origin gFrontEnd )
				)
				( attribute "CDS_PHYS_NET_NAME" "P1V05_PCH_STBY_VCCA_PLL0"
					( Origin gPackager )
				)
				( objectStatus "P1V05_PCH_STBY_VCCA_PLL0" )
			)
			( signal "@baseboard_fab2_lib.baseboard_fab2(sch_1):page122_p1v05_pch_stby_vcca_pll0"
				( attribute "VOLTAGE" "1.05V"
					( Units "uVoltage" "V" 1.000000)
					( Origin gFrontEnd )
				)
				( objectFlag fObjectAlias )
				( objectStatus "page122_p1v05_pch_stby_vcca_pll0" )
			)
			( signal "@baseboard_fab2_lib.baseboard_fab2(sch_1):page127_p1v05_pch_stby_vcca_pll0"
				( attribute "VOLTAGE" "1.05V"
					( Units "uVoltage" "V" 1.000000)
					( Origin gFrontEnd )
				)
				( objectFlag fObjectAlias )
				( objectStatus "page127_p1v05_pch_stby_vcca_pll0" )
			)
			( signal "@baseboard_fab2_lib.baseboard_fab2(sch_1):p1v05_pch_stby_vcca_pll1"
				( alias ( signalRef "@baseboard_fab2_lib.baseboard_fab2(sch_1):page122_p1v05_pch_stby_vcca_pll1") )
				( alias ( signalRef "@baseboard_fab2_lib.baseboard_fab2(sch_1):page127_p1v05_pch_stby_vcca_pll1") )
				( attribute "VOLTAGE" "1.05V"
					( Units "uVoltage" "V" 1.000000)
					( Status sAliasFlattened )
					( Origin gFrontEnd )
				)
				( attribute "CDS_PHYS_NET_NAME" "P1V05_PCH_STBY_VCCA_PLL1"
					( Origin gPackager )
				)
				( objectStatus "P1V05_PCH_STBY_VCCA_PLL1" )
			)
			( signal "@baseboard_fab2_lib.baseboard_fab2(sch_1):page122_p1v05_pch_stby_vcca_pll1"
				( attribute "VOLTAGE" "1.05V"
					( Units "uVoltage" "V" 1.000000)
					( Origin gFrontEnd )
				)
				( objectFlag fObjectAlias )
				( objectStatus "page122_p1v05_pch_stby_vcca_pll1" )
			)
			( signal "@baseboard_fab2_lib.baseboard_fab2(sch_1):page127_p1v05_pch_stby_vcca_pll1"
				( attribute "VOLTAGE" "1.05V"
					( Units "uVoltage" "V" 1.000000)
					( Origin gFrontEnd )
				)
				( objectFlag fObjectAlias )
				( objectStatus "page127_p1v05_pch_stby_vcca_pll1" )
			)
			( signal "@baseboard_fab2_lib.baseboard_fab2(sch_1):p1v05_pch_stby_vcca_xtal"
				( alias ( signalRef "@baseboard_fab2_lib.baseboard_fab2(sch_1):page122_p1v05_pch_stby_vcca_xtal") )
				( alias ( signalRef "@baseboard_fab2_lib.baseboard_fab2(sch_1):page127_p1v05_pch_stby_vcca_xtal") )
				( attribute "VOLTAGE" "1.05V"
					( Units "uVoltage" "V" 1.000000)
					( Status sAliasFlattened )
					( Origin gFrontEnd )
				)
				( attribute "CDS_PHYS_NET_NAME" "P1V05_PCH_STBY_VCCA_XTAL"
					( Origin gPackager )
				)
				( objectStatus "P1V05_PCH_STBY_VCCA_XTAL" )
			)
			( signal "@baseboard_fab2_lib.baseboard_fab2(sch_1):page122_p1v05_pch_stby_vcca_xtal"
				( attribute "VOLTAGE" "1.05V"
					( Units "uVoltage" "V" 1.000000)
					( Origin gFrontEnd )
				)
				( objectFlag fObjectAlias )
				( objectStatus "page122_p1v05_pch_stby_vcca_xtal" )
			)
			( signal "@baseboard_fab2_lib.baseboard_fab2(sch_1):page127_p1v05_pch_stby_vcca_xtal"
				( attribute "VOLTAGE" "1.05V"
					( Units "uVoltage" "V" 1.000000)
					( Origin gFrontEnd )
				)
				( objectFlag fObjectAlias )
				( objectStatus "page127_p1v05_pch_stby_vcca_xtal" )
			)
			( signal "@baseboard_fab2_lib.baseboard_fab2(sch_1):p1v05_pch_stby_wm20_pll"
				( alias ( signalRef "@baseboard_fab2_lib.baseboard_fab2(sch_1):page122_p1v05_pch_stby_wm20_pll") )
				( alias ( signalRef "@baseboard_fab2_lib.baseboard_fab2(sch_1):page127_p1v05_pch_stby_wm20_pll") )
				( attribute "VOLTAGE" "1.05V"
					( Units "uVoltage" "V" 1.000000)
					( Status sAliasFlattened )
					( Origin gFrontEnd )
				)
				( attribute "CDS_PHYS_NET_NAME" "P1V05_PCH_STBY_WM20_PLL"
					( Origin gPackager )
				)
				( objectStatus "P1V05_PCH_STBY_WM20_PLL" )
			)
			( signal "@baseboard_fab2_lib.baseboard_fab2(sch_1):page122_p1v05_pch_stby_wm20_pll"
				( attribute "VOLTAGE" "1.05V"
					( Units "uVoltage" "V" 1.000000)
					( Origin gFrontEnd )
				)
				( objectFlag fObjectAlias )
				( objectStatus "page122_p1v05_pch_stby_wm20_pll" )
			)
			( signal "@baseboard_fab2_lib.baseboard_fab2(sch_1):page127_p1v05_pch_stby_wm20_pll"
				( attribute "VOLTAGE" "1.05V"
					( Units "uVoltage" "V" 1.000000)
					( Origin gFrontEnd )
				)
				( objectFlag fObjectAlias )
				( objectStatus "page127_p1v05_pch_stby_wm20_pll" )
			)
			( signal "@baseboard_fab2_lib.baseboard_fab2(sch_1):p1v05_pch_stby_wm26_pll"
				( alias ( signalRef "@baseboard_fab2_lib.baseboard_fab2(sch_1):page122_p1v05_pch_stby_wm26_pll") )
				( alias ( signalRef "@baseboard_fab2_lib.baseboard_fab2(sch_1):page127_p1v05_pch_stby_wm26_pll") )
				( attribute "VOLTAGE" "1.05V"
					( Units "uVoltage" "V" 1.000000)
					( Status sAliasFlattened )
					( Origin gFrontEnd )
				)
				( attribute "CDS_PHYS_NET_NAME" "P1V05_PCH_STBY_WM26_PLL"
					( Origin gPackager )
				)
				( objectStatus "P1V05_PCH_STBY_WM26_PLL" )
			)
			( signal "@baseboard_fab2_lib.baseboard_fab2(sch_1):page122_p1v05_pch_stby_wm26_pll"
				( attribute "VOLTAGE" "1.05V"
					( Units "uVoltage" "V" 1.000000)
					( Origin gFrontEnd )
				)
				( objectFlag fObjectAlias )
				( objectStatus "page122_p1v05_pch_stby_wm26_pll" )
			)
			( signal "@baseboard_fab2_lib.baseboard_fab2(sch_1):page127_p1v05_pch_stby_wm26_pll"
				( attribute "VOLTAGE" "1.05V"
					( Units "uVoltage" "V" 1.000000)
					( Origin gFrontEnd )
				)
				( objectFlag fObjectAlias )
				( objectStatus "page127_p1v05_pch_stby_wm26_pll" )
			)
			( signal "@baseboard_fab2_lib.baseboard_fab2(sch_1):p1v8_pch_stby"
				( alias ( signalRef "@baseboard_fab2_lib.baseboard_fab2(sch_1):page122_p1v8_pch_stby") )
				( alias ( signalRef "@baseboard_fab2_lib.baseboard_fab2(sch_1):page130_p1v8_pch_stby") )
				( alias ( signalRef "@baseboard_fab2_lib.baseboard_fab2(sch_1):page237_p1v8_pch_stby") )
				( attribute "CDS_PHYS_NET_NAME" "P1V8_PCH_STBY"
					( Origin gPackager )
				)
				( attribute "VOLTAGE" "1.8V"
					( Units "uVoltage" "V" 1.000000)
					( Status sAliasFlattened )
					( Origin gFrontEnd )
				)
				( objectStatus "P1V8_PCH_STBY" )
			)
			( signal "@baseboard_fab2_lib.baseboard_fab2(sch_1):page122_p1v8_pch_stby"
				( attribute "VOLTAGE" "1.8V"
					( Units "uVoltage" "V" 1.000000)
					( Origin gFrontEnd )
				)
				( objectFlag fObjectAlias )
				( objectStatus "page122_p1v8_pch_stby" )
			)
			( signal "@baseboard_fab2_lib.baseboard_fab2(sch_1):page130_p1v8_pch_stby"
				( attribute "VOLTAGE" "1.8V"
					( Units "uVoltage" "V" 1.000000)
					( Origin gFrontEnd )
				)
				( objectFlag fObjectAlias )
				( objectStatus "page130_p1v8_pch_stby" )
			)
			( signal "@baseboard_fab2_lib.baseboard_fab2(sch_1):page237_p1v8_pch_stby"
				( attribute "VOLTAGE" "1.8V"
					( Units "uVoltage" "V" 1.000000)
					( Origin gFrontEnd )
				)
				( objectFlag fObjectAlias )
				( objectStatus "page237_p1v8_pch_stby" )
			)
			( signal "@baseboard_fab2_lib.baseboard_fab2(sch_1):p3v3_rtc_stby"
				( alias ( signalRef "@baseboard_fab2_lib.baseboard_fab2(sch_1):page122_p3v3_rtc_stby") )
				( alias ( signalRef "@baseboard_fab2_lib.baseboard_fab2(sch_1):page137_p3v3_rtc_stby") )
				( alias ( signalRef "@baseboard_fab2_lib.baseboard_fab2(sch_1):page196_p3v3_rtc_stby") )
				( attribute "VOLTAGE" "3.3V"
					( Units "uVoltage" "V" 1.000000)
					( Status sAliasFlattened )
					( Origin gFrontEnd )
				)
				( attribute "CDS_PHYS_NET_NAME" "P3V3_RTC_STBY"
					( Origin gPackager )
				)
				( objectStatus "P3V3_RTC_STBY" )
			)
			( signal "@baseboard_fab2_lib.baseboard_fab2(sch_1):page122_p3v3_rtc_stby"
				( attribute "VOLTAGE" "3.3V"
					( Units "uVoltage" "V" 1.000000)
					( Origin gFrontEnd )
				)
				( objectFlag fObjectAlias )
				( objectStatus "page122_p3v3_rtc_stby" )
			)
			( signal "@baseboard_fab2_lib.baseboard_fab2(sch_1):page137_p3v3_rtc_stby"
				( attribute "VOLTAGE" "3.3V"
					( Units "uVoltage" "V" 1.000000)
					( Origin gFrontEnd )
				)
				( objectFlag fObjectAlias )
				( objectStatus "page137_p3v3_rtc_stby" )
			)
			( signal "@baseboard_fab2_lib.baseboard_fab2(sch_1):page196_p3v3_rtc_stby"
				( attribute "VOLTAGE" "3.3V"
					( Units "uVoltage" "V" 1.000000)
					( Origin gFrontEnd )
				)
				( objectFlag fObjectAlias )
				( objectStatus "page196_p3v3_rtc_stby" )
			)
			( signal "@baseboard_fab2_lib.baseboard_fab2(sch_1):tp_pch_rsvd28"
				( attribute "CDS_PHYS_NET_NAME" "TP_PCH_RSVD28"
					( Origin gPackager )
				)
				( objectStatus "TP_PCH_RSVD28" )
			)
			( signal "@baseboard_fab2_lib.baseboard_fab2(sch_1):tp_pch_rsvd29"
				( attribute "CDS_PHYS_NET_NAME" "TP_PCH_RSVD29"
					( Origin gPackager )
				)
				( objectStatus "TP_PCH_RSVD29" )
			)
			( signal "@baseboard_fab2_lib.baseboard_fab2(sch_1):tp_pch_rsvd30"
				( attribute "CDS_PHYS_NET_NAME" "TP_PCH_RSVD30"
					( Origin gPackager )
				)
				( objectStatus "TP_PCH_RSVD30" )
			)
			( signal "@baseboard_fab2_lib.baseboard_fab2(sch_1):tp_pch_rsvd31"
				( attribute "CDS_PHYS_NET_NAME" "TP_PCH_RSVD31"
					( Origin gPackager )
				)
				( objectStatus "TP_PCH_RSVD31" )
			)
			( signal "@baseboard_fab2_lib.baseboard_fab2(sch_1):tp_pch_rsvd58"
				( attribute "CDS_PHYS_NET_NAME" "TP_PCH_RSVD58"
					( Origin gPackager )
				)
				( objectStatus "TP_PCH_RSVD58" )
			)
			( signal "@baseboard_fab2_lib.baseboard_fab2(sch_1):tp_pch_rsvd59"
				( attribute "CDS_PHYS_NET_NAME" "TP_PCH_RSVD59"
					( Origin gPackager )
				)
				( objectStatus "TP_PCH_RSVD59" )
			)
			( signal "@baseboard_fab2_lib.baseboard_fab2(sch_1):pvnn_pch_stby"
				( alias ( signalRef "@baseboard_fab2_lib.baseboard_fab2(sch_1):page123_pvnn_pch_stby") )
				( alias ( signalRef "@baseboard_fab2_lib.baseboard_fab2(sch_1):page132_pvnn_pch_stby") )
				( alias ( signalRef "@baseboard_fab2_lib.baseboard_fab2(sch_1):page169_pvnn_pch_stby") )
				( alias ( signalRef "@baseboard_fab2_lib.baseboard_fab2(sch_1):page236_pvnn_pch_stby") )
				( attribute "VOLTAGE" "1.0V"
					( Units "uVoltage" "V" 1.000000)
					( Status sAliasFlattened )
					( Origin gFrontEnd )
				)
				( attribute "CDS_PHYS_NET_NAME" "PVNN_PCH_STBY"
					( Origin gPackager )
				)
				( objectStatus "PVNN_PCH_STBY" )
			)
			( signal "@baseboard_fab2_lib.baseboard_fab2(sch_1):page123_pvnn_pch_stby"
				( attribute "VOLTAGE" "1.0V"
					( Units "uVoltage" "V" 1.000000)
					( Origin gFrontEnd )
				)
				( objectFlag fObjectAlias )
				( objectStatus "page123_pvnn_pch_stby" )
			)
			( signal "@baseboard_fab2_lib.baseboard_fab2(sch_1):page132_pvnn_pch_stby"
				( attribute "VOLTAGE" "1.0V"
					( Units "uVoltage" "V" 1.000000)
					( Origin gFrontEnd )
				)
				( objectFlag fObjectAlias )
				( objectStatus "page132_pvnn_pch_stby" )
			)
			( signal "@baseboard_fab2_lib.baseboard_fab2(sch_1):page169_pvnn_pch_stby"
				( attribute "VOLTAGE" "1.0V"
					( Units "uVoltage" "V" 1.000000)
					( Origin gFrontEnd )
				)
				( objectFlag fObjectAlias )
				( objectStatus "page169_pvnn_pch_stby" )
			)
			( signal "@baseboard_fab2_lib.baseboard_fab2(sch_1):page236_pvnn_pch_stby"
				( attribute "VOLTAGE" "1.0V"
					( Units "uVoltage" "V" 1.000000)
					( Origin gFrontEnd )
				)
				( objectFlag fObjectAlias )
				( objectStatus "page236_pvnn_pch_stby" )
			)
			( signal "@baseboard_fab2_lib.baseboard_fab2(sch_1):vsense_pvnn_pch_stby_fpk"
				( attribute "CDS_PHYS_NET_NAME" "VSENSE_PVNN_PCH_STBY_FPK"
					( Origin gPackager )
				)
				( objectStatus "VSENSE_PVNN_PCH_STBY_FPK" )
			)
			( signal "@baseboard_fab2_lib.baseboard_fab2(sch_1):vsense_pvnn_pch_stby_qat"
				( attribute "CDS_PHYS_NET_NAME" "VSENSE_PVNN_PCH_STBY_QAT"
					( Origin gPackager )
				)
				( objectStatus "VSENSE_PVNN_PCH_STBY_QAT" )
			)
			( signal "@baseboard_fab2_lib.baseboard_fab2(sch_1):rst_rsmrst_dly"
				( attribute "CDS_PHYS_NET_NAME" "RST_RSMRST_DLY"
					( Origin gPackager )
				)
				( objectStatus "RST_RSMRST_DLY" )
			)
			( signal "@baseboard_fab2_lib.baseboard_fab2(sch_1):fm_thermtrip_dly"
				( attribute "CDS_PHYS_NET_NAME" "FM_THERMTRIP_DLY"
					( Origin gPackager )
				)
				( objectStatus "FM_THERMTRIP_DLY" )
			)
			( signal "@baseboard_fab2_lib.baseboard_fab2(sch_1):fm_thermtrip_dly_r"
				( attribute "CDS_PHYS_NET_NAME" "FM_THERMTRIP_DLY_R"
					( Origin gPackager )
				)
				( objectStatus "FM_THERMTRIP_DLY_R" )
			)
			( signal "@baseboard_fab2_lib.baseboard_fab2(sch_1):rst_pltrst_buf_n"
				( attribute "CDS_PHYS_NET_NAME" "RST_PLTRST_BUF_N"
					( Origin gPackager )
				)
				( objectStatus "RST_PLTRST_BUF_N" )
			)
			( signal "@baseboard_fab2_lib.baseboard_fab2(sch_1):fm_cpld_uart_ch_lock_n"
				( attribute "CDS_PHYS_NET_NAME" "FM_CPLD_UART_CH_LOCK_N"
					( Origin gPackager )
				)
				( objectStatus "FM_CPLD_UART_CH_LOCK_N" )
			)
			( signal "@baseboard_fab2_lib.baseboard_fab2(sch_1):fm_dis_adr_dly"
				( attribute "CDS_PHYS_NET_NAME" "FM_DIS_ADR_DLY"
					( Origin gPackager )
				)
				( objectStatus "FM_DIS_ADR_DLY" )
			)
			( signal "@baseboard_fab2_lib.baseboard_fab2(sch_1):fm_pch_sata_raid_key_r"
				( attribute "CDS_PHYS_NET_NAME" "FM_PCH_SATA_RAID_KEY_R"
					( Origin gPackager )
				)
				( objectStatus "FM_PCH_SATA_RAID_KEY_R" )
			)
			( signal "@baseboard_fab2_lib.baseboard_fab2(sch_1):pu_key_conn_pin2_r"
				( attribute "CDS_PHYS_NET_NAME" "PU_KEY_CONN_PIN2_R"
					( Origin gPackager )
				)
				( objectStatus "PU_KEY_CONN_PIN2_R" )
			)
			( signal "@baseboard_fab2_lib.baseboard_fab2(sch_1):\tp_jumper_block_ 1_7\"
				( attribute "CDS_PHYS_NET_NAME" "TP_JUMPER_BLOCK_1_7"
					( Origin gPackager )
				)
				( attribute "PNN" "TP_JUMPER_BLOCK_1_7"
					( Origin gPackager )
				)
				( objectStatus "TP_JUMPER_BLOCK_1_7" )
			)
			( signal "@baseboard_fab2_lib.baseboard_fab2(sch_1):tp_jumper_block_1_1"
				( attribute "CDS_PHYS_NET_NAME" "TP_JUMPER_BLOCK_1_1"
					( Origin gPackager )
				)
				( objectStatus "TP_JUMPER_BLOCK_1_1" )
			)
			( signal "@baseboard_fab2_lib.baseboard_fab2(sch_1):tp_jumper_block_1_2"
				( attribute "CDS_PHYS_NET_NAME" "TP_JUMPER_BLOCK_1_2"
					( Origin gPackager )
				)
				( objectStatus "TP_JUMPER_BLOCK_1_2" )
			)
			( signal "@baseboard_fab2_lib.baseboard_fab2(sch_1):tp_jumper_block_1_8"
				( attribute "CDS_PHYS_NET_NAME" "TP_JUMPER_BLOCK_1_8"
					( Origin gPackager )
				)
				( objectStatus "TP_JUMPER_BLOCK_1_8" )
			)
			( signal "@baseboard_fab2_lib.baseboard_fab2(sch_1):fm_bios_top_swap_spkr_r"
				( attribute "CDS_PHYS_NET_NAME" "FM_BIOS_TOP_SWAP_SPKR_R"
					( Origin gPackager )
				)
				( objectStatus "FM_BIOS_TOP_SWAP_SPKR_R" )
			)
			( signal "@baseboard_fab2_lib.baseboard_fab2(sch_1):pd_me_rcvr_n"
				( attribute "CDS_PHYS_NET_NAME" "PD_ME_RCVR_N"
					( Origin gPackager )
				)
				( objectStatus "PD_ME_RCVR_N" )
			)
			( signal "@baseboard_fab2_lib.baseboard_fab2(sch_1):pd_password_clear"
				( attribute "CDS_PHYS_NET_NAME" "PD_PASSWORD_CLEAR"
					( Origin gPackager )
				)
				( objectStatus "PD_PASSWORD_CLEAR" )
			)
			( signal "@baseboard_fab2_lib.baseboard_fab2(sch_1):pu_bios_recover_boot"
				( attribute "CDS_PHYS_NET_NAME" "PU_BIOS_RECOVER_BOOT"
					( Origin gPackager )
				)
				( objectStatus "PU_BIOS_RECOVER_BOOT" )
			)
			( signal "@baseboard_fab2_lib.baseboard_fab2(sch_1):pu_bios_usb_recovery"
				( attribute "CDS_PHYS_NET_NAME" "PU_BIOS_USB_RECOVERY"
					( Origin gPackager )
				)
				( objectStatus "PU_BIOS_USB_RECOVERY" )
			)
			( signal "@baseboard_fab2_lib.baseboard_fab2(sch_1):rst_pltrst_top_swap"
				( attribute "CDS_PHYS_NET_NAME" "RST_PLTRST_TOP_SWAP"
					( Origin gPackager )
				)
				( objectStatus "RST_PLTRST_TOP_SWAP" )
			)
			( signal "@baseboard_fab2_lib.baseboard_fab2(sch_1):tp_bios_recover_boot"
				( attribute "CDS_PHYS_NET_NAME" "TP_BIOS_RECOVER_BOOT"
					( Origin gPackager )
				)
				( objectStatus "TP_BIOS_RECOVER_BOOT" )
			)
			( signal "@baseboard_fab2_lib.baseboard_fab2(sch_1):tp_bios_usb_recovery"
				( attribute "CDS_PHYS_NET_NAME" "TP_BIOS_USB_RECOVERY"
					( Origin gPackager )
				)
				( objectStatus "TP_BIOS_USB_RECOVERY" )
			)
			( signal "@baseboard_fab2_lib.baseboard_fab2(sch_1):tp_me_rcvr_boot"
				( attribute "CDS_PHYS_NET_NAME" "TP_ME_RCVR_BOOT"
					( Origin gPackager )
				)
				( objectStatus "TP_ME_RCVR_BOOT" )
			)
			( signal "@baseboard_fab2_lib.baseboard_fab2(sch_1):tp_password_clear"
				( attribute "CDS_PHYS_NET_NAME" "TP_PASSWORD_CLEAR"
					( Origin gPackager )
				)
				( objectStatus "TP_PASSWORD_CLEAR" )
			)
			( signal "@baseboard_fab2_lib.baseboard_fab2(sch_1):fm_bmc_disable"
				( alias ( signalRef "@baseboard_fab2_lib.baseboard_fab2(sch_1):page143_fm_bmc_disable") )
				( attribute "CDS_PHYS_NET_NAME" "FM_BMC_DISABLE"
					( Origin gPackager )
				)
				( objectStatus "FM_BMC_DISABLE" )
			)
			( signal "@baseboard_fab2_lib.baseboard_fab2(sch_1):page143_fm_bmc_disable"
				( objectFlag fObjectAlias )
				( objectStatus "page143_fm_bmc_disable" )
			)
			( signal "@baseboard_fab2_lib.baseboard_fab2(sch_1):fm_roma(0)"
				( alias ( signalRef "@baseboard_fab2_lib.baseboard_fab2(sch_1):page143_fm_roma(0)") )
				( attribute "CDS_PHYS_NET_NAME" "FM_ROMA<0>"
					( Origin gPackager )
				)
				( attribute "PNN" "FM_ROMA<0>"
					( Origin gPackager )
				)
				( attribute "PHYS_NET_NAME" "FM_ROMA<0>"
					( Origin gPackager )
				)
				( objectStatus "FM_ROMA<0>" )
			)
			( signal "@baseboard_fab2_lib.baseboard_fab2(sch_1):page143_fm_roma(0)"
				( objectFlag fObjectAlias )
				( objectStatus "page143_fm_roma<0>" )
			)
			( signal "@baseboard_fab2_lib.baseboard_fab2(sch_1):pd_ie_debug_mode"
				( attribute "CDS_PHYS_NET_NAME" "PD_IE_DEBUG_MODE"
					( Origin gPackager )
				)
				( objectStatus "PD_IE_DEBUG_MODE" )
			)
			( signal "@baseboard_fab2_lib.baseboard_fab2(sch_1):pd_rst_rtcrst_n"
				( attribute "CDS_PHYS_NET_NAME" "PD_RST_RTCRST_N"
					( Origin gPackager )
				)
				( objectStatus "PD_RST_RTCRST_N" )
			)
			( signal "@baseboard_fab2_lib.baseboard_fab2(sch_1):tp_bmc_disable"
				( attribute "CDS_PHYS_NET_NAME" "TP_BMC_DISABLE"
					( Origin gPackager )
				)
				( objectStatus "TP_BMC_DISABLE" )
			)
			( signal "@baseboard_fab2_lib.baseboard_fab2(sch_1):tp_ie_debug_mode"
				( attribute "CDS_PHYS_NET_NAME" "TP_IE_DEBUG_MODE"
					( Origin gPackager )
				)
				( objectStatus "TP_IE_DEBUG_MODE" )
			)
			( signal "@baseboard_fab2_lib.baseboard_fab2(sch_1):tp_jumper_block_2_10"
				( attribute "CDS_PHYS_NET_NAME" "TP_JUMPER_BLOCK_2_10"
					( Origin gPackager )
				)
				( objectStatus "TP_JUMPER_BLOCK_2_10" )
			)
			( signal "@baseboard_fab2_lib.baseboard_fab2(sch_1):tp_jumper_block_2_12"
				( attribute "CDS_PHYS_NET_NAME" "TP_JUMPER_BLOCK_2_12"
					( Origin gPackager )
				)
				( objectStatus "TP_JUMPER_BLOCK_2_12" )
			)
			( signal "@baseboard_fab2_lib.baseboard_fab2(sch_1):tp_jumper_block_2_8"
				( attribute "CDS_PHYS_NET_NAME" "TP_JUMPER_BLOCK_2_8"
					( Origin gPackager )
				)
				( objectStatus "TP_JUMPER_BLOCK_2_8" )
			)
			( signal "@baseboard_fab2_lib.baseboard_fab2(sch_1):tp_rst_rtcrst_n"
				( attribute "CDS_PHYS_NET_NAME" "TP_RST_RTCRST_N"
					( Origin gPackager )
				)
				( objectStatus "TP_RST_RTCRST_N" )
			)
			( signal "@baseboard_fab2_lib.baseboard_fab2(sch_1):smb_bmc_pmbus_stby_lvc3_scl"
				( alias ( signalRef "@baseboard_fab2_lib.baseboard_fab2(sch_1):page247_smb_bmc_pmbus_stby_lvc3_scl") )
				( attribute "CDS_PHYS_NET_NAME" "SMB_BMC_PMBUS_STBY_LVC3_SCL"
					( Origin gPackager )
				)
				( objectStatus "SMB_BMC_PMBUS_STBY_LVC3_SCL" )
			)
			( signal "@baseboard_fab2_lib.baseboard_fab2(sch_1):page247_smb_bmc_pmbus_stby_lvc3_scl"
				( attribute "CDS_PHYS_NET_NAME" "SMB_BMC_PMBUS_STBY_LVC3_SCL"
					( Origin gPackager )
				)
				( objectFlag fObjectAlias )
				( objectStatus "page247_smb_bmc_pmbus_stby_lvc3_scl" )
			)
			( signal "@baseboard_fab2_lib.baseboard_fab2(sch_1):smb_bmc_pmbus_stby_lvc3_sda"
				( alias ( signalRef "@baseboard_fab2_lib.baseboard_fab2(sch_1):page247_smb_bmc_pmbus_stby_lvc3_sda") )
				( attribute "CDS_PHYS_NET_NAME" "SMB_BMC_PMBUS_STBY_LVC3_SDA"
					( Origin gPackager )
				)
				( objectStatus "SMB_BMC_PMBUS_STBY_LVC3_SDA" )
			)
			( signal "@baseboard_fab2_lib.baseboard_fab2(sch_1):page247_smb_bmc_pmbus_stby_lvc3_sda"
				( attribute "CDS_PHYS_NET_NAME" "SMB_BMC_PMBUS_STBY_LVC3_SDA"
					( Origin gPackager )
				)
				( objectFlag fObjectAlias )
				( objectStatus "page247_smb_bmc_pmbus_stby_lvc3_sda" )
			)
			( signal "@baseboard_fab2_lib.baseboard_fab2(sch_1):smb_lan_stby_lvc3_scl"
				( attribute "CDS_PHYS_NET_NAME" "SMB_LAN_STBY_LVC3_SCL"
					( Origin gPackager )
				)
				( objectStatus "SMB_LAN_STBY_LVC3_SCL" )
			)
			( signal "@baseboard_fab2_lib.baseboard_fab2(sch_1):smb_lan_stby_lvc3_sda"
				( attribute "CDS_PHYS_NET_NAME" "SMB_LAN_STBY_LVC3_SDA"
					( Origin gPackager )
				)
				( objectStatus "SMB_LAN_STBY_LVC3_SDA" )
			)
			( signal "@baseboard_fab2_lib.baseboard_fab2(sch_1):smb_sensor_pch_stby_lvc3_scl"
				( attribute "CDS_PHYS_NET_NAME" "SMB_SENSOR_PCH_STBY_LVC3_SCL"
					( Origin gPackager )
				)
				( objectStatus "SMB_SENSOR_PCH_STBY_LVC3_SCL" )
			)
			( signal "@baseboard_fab2_lib.baseboard_fab2(sch_1):smb_sensor_pch_stby_lvc3_sda"
				( attribute "CDS_PHYS_NET_NAME" "SMB_SENSOR_PCH_STBY_LVC3_SDA"
					( Origin gPackager )
				)
				( objectStatus "SMB_SENSOR_PCH_STBY_LVC3_SDA" )
			)
			( signal "@baseboard_fab2_lib.baseboard_fab2(sch_1):smb_smlink0_stby_lvc3_scl"
				( attribute "CDS_PHYS_NET_NAME" "SMB_SMLINK0_STBY_LVC3_SCL"
					( Origin gPackager )
				)
				( objectStatus "SMB_SMLINK0_STBY_LVC3_SCL" )
			)
			( signal "@baseboard_fab2_lib.baseboard_fab2(sch_1):smb_smlink0_stby_lvc3_sda"
				( attribute "CDS_PHYS_NET_NAME" "SMB_SMLINK0_STBY_LVC3_SDA"
					( Origin gPackager )
				)
				( objectStatus "SMB_SMLINK0_STBY_LVC3_SDA" )
			)
			( signal "@baseboard_fab2_lib.baseboard_fab2(sch_1):smb_vr_stby_lvc3_scl"
				( attribute "CDS_PHYS_NET_NAME" "SMB_VR_STBY_LVC3_SCL"
					( Origin gPackager )
				)
				( objectStatus "SMB_VR_STBY_LVC3_SCL" )
			)
			( signal "@baseboard_fab2_lib.baseboard_fab2(sch_1):smb_vr_stby_lvc3_sda"
				( attribute "CDS_PHYS_NET_NAME" "SMB_VR_STBY_LVC3_SDA"
					( Origin gPackager )
				)
				( objectStatus "SMB_VR_STBY_LVC3_SDA" )
			)
			( signal "@baseboard_fab2_lib.baseboard_fab2(sch_1):a_cbot"
				( attribute "CDS_PHYS_NET_NAME" "A_CBOT"
					( Origin gPackager )
				)
				( objectStatus "A_CBOT" )
			)
			( signal "@baseboard_fab2_lib.baseboard_fab2(sch_1):a_ctop"
				( attribute "CDS_PHYS_NET_NAME" "A_CTOP"
					( Origin gPackager )
				)
				( objectStatus "A_CTOP" )
			)
			( signal "@baseboard_fab2_lib.baseboard_fab2(sch_1):fm_pe_sprv_wake_n"
				( attribute "CDS_PHYS_NET_NAME" "FM_PE_SPRV_WAKE_N"
					( Origin gPackager )
				)
				( objectStatus "FM_PE_SPRV_WAKE_N" )
			)
			( signal "@baseboard_fab2_lib.baseboard_fab2(sch_1):led_lan_0_n"
				( attribute "CDS_PHYS_NET_NAME" "LED_LAN_0_N"
					( Origin gPackager )
				)
				( objectStatus "LED_LAN_0_N" )
			)
			( signal "@baseboard_fab2_lib.baseboard_fab2(sch_1):led_lan_1_n"
				( attribute "CDS_PHYS_NET_NAME" "LED_LAN_1_N"
					( Origin gPackager )
				)
				( objectStatus "LED_LAN_1_N" )
			)
			( signal "@baseboard_fab2_lib.baseboard_fab2(sch_1):led_lan_2_n"
				( attribute "CDS_PHYS_NET_NAME" "LED_LAN_2_N"
					( Origin gPackager )
				)
				( objectStatus "LED_LAN_2_N" )
			)
			( signal "@baseboard_fab2_lib.baseboard_fab2(sch_1):nc_sprngvlle_22"
				( attribute "CDS_PHYS_NET_NAME" "NC_SPRNGVLLE_22"
					( Origin gPackager )
				)
				( objectStatus "NC_SPRNGVLLE_22" )
			)
			( signal "@baseboard_fab2_lib.baseboard_fab2(sch_1):nic_mdi_sprv_rj45_0_dn"
				( attribute "CDS_PHYS_NET_NAME" "NIC_MDI_SPRV_RJ45_0_DN"
					( Origin gPackager )
				)
				( objectStatus "NIC_MDI_SPRV_RJ45_0_DN" )
			)
			( signal "@baseboard_fab2_lib.baseboard_fab2(sch_1):nic_mdi_sprv_rj45_0_dp"
				( attribute "CDS_PHYS_NET_NAME" "NIC_MDI_SPRV_RJ45_0_DP"
					( Origin gPackager )
				)
				( objectStatus "NIC_MDI_SPRV_RJ45_0_DP" )
			)
			( signal "@baseboard_fab2_lib.baseboard_fab2(sch_1):nic_mdi_sprv_rj45_1_dn"
				( attribute "CDS_PHYS_NET_NAME" "NIC_MDI_SPRV_RJ45_1_DN"
					( Origin gPackager )
				)
				( objectStatus "NIC_MDI_SPRV_RJ45_1_DN" )
			)
			( signal "@baseboard_fab2_lib.baseboard_fab2(sch_1):nic_mdi_sprv_rj45_1_dp"
				( attribute "CDS_PHYS_NET_NAME" "NIC_MDI_SPRV_RJ45_1_DP"
					( Origin gPackager )
				)
				( objectStatus "NIC_MDI_SPRV_RJ45_1_DP" )
			)
			( signal "@baseboard_fab2_lib.baseboard_fab2(sch_1):nic_ser_n_mdi_3_dn"
				( attribute "CDS_PHYS_NET_NAME" "NIC_SER_N_MDI_3_DN"
					( Origin gPackager )
				)
				( objectStatus "NIC_SER_N_MDI_3_DN" )
			)
			( signal "@baseboard_fab2_lib.baseboard_fab2(sch_1):nic_ser_p_mdi_3_dp"
				( attribute "CDS_PHYS_NET_NAME" "NIC_SER_P_MDI_3_DP"
					( Origin gPackager )
				)
				( objectStatus "NIC_SER_P_MDI_3_DP" )
			)
			( signal "@baseboard_fab2_lib.baseboard_fab2(sch_1):nic_set_n_mdi_2_dn"
				( attribute "CDS_PHYS_NET_NAME" "NIC_SET_N_MDI_2_DN"
					( Origin gPackager )
				)
				( objectStatus "NIC_SET_N_MDI_2_DN" )
			)
			( signal "@baseboard_fab2_lib.baseboard_fab2(sch_1):nic_set_p_mdi_2_dp"
				( attribute "CDS_PHYS_NET_NAME" "NIC_SET_P_MDI_2_DP"
					( Origin gPackager )
				)
				( objectStatus "NIC_SET_P_MDI_2_DP" )
			)
			( signal "@baseboard_fab2_lib.baseboard_fab2(sch_1):p0v9_lan"
				( alias ( signalRef "@baseboard_fab2_lib.baseboard_fab2(sch_1):page139_p0v9_lan") )
				( attribute "VOLTAGE" "0.9V"
					( Units "uVoltage" "V" 1.000000)
					( Status sAliasFlattened )
					( Origin gFrontEnd )
				)
				( attribute "CDS_PHYS_NET_NAME" "P0V9_LAN"
					( Origin gPackager )
				)
				( objectStatus "P0V9_LAN" )
			)
			( signal "@baseboard_fab2_lib.baseboard_fab2(sch_1):page139_p0v9_lan"
				( attribute "VOLTAGE" "0.9V"
					( Units "uVoltage" "V" 1.000000)
					( Origin gFrontEnd )
				)
				( objectFlag fObjectAlias )
				( objectStatus "page139_p0v9_lan" )
			)
			( signal "@baseboard_fab2_lib.baseboard_fab2(sch_1):p0v9_lan_i210"
				( alias ( signalRef "@baseboard_fab2_lib.baseboard_fab2(sch_1):page139_p0v9_lan_i210") )
				( attribute "VOLTAGE" "0.9"
					( Units "uVoltage" "V" 1.000000)
					( Status sAliasFlattened )
					( Origin gFrontEnd )
				)
				( attribute "CDS_PHYS_NET_NAME" "P0V9_LAN_I210"
					( Origin gPackager )
				)
				( objectStatus "P0V9_LAN_I210" )
			)
			( signal "@baseboard_fab2_lib.baseboard_fab2(sch_1):page139_p0v9_lan_i210"
				( attribute "VOLTAGE" "0.9"
					( Units "uVoltage" "V" 1.000000)
					( Origin gFrontEnd )
				)
				( objectFlag fObjectAlias )
				( objectStatus "page139_p0v9_lan_i210" )
			)
			( signal "@baseboard_fab2_lib.baseboard_fab2(sch_1):p1v5_lan"
				( alias ( signalRef "@baseboard_fab2_lib.baseboard_fab2(sch_1):page139_p1v5_lan") )
				( attribute "VOLTAGE" "1.5V"
					( Units "uVoltage" "V" 1.000000)
					( Status sAliasFlattened )
					( Origin gFrontEnd )
				)
				( attribute "CDS_PHYS_NET_NAME" "P1V5_LAN"
					( Origin gPackager )
				)
				( objectStatus "P1V5_LAN" )
			)
			( signal "@baseboard_fab2_lib.baseboard_fab2(sch_1):page139_p1v5_lan"
				( attribute "VOLTAGE" "1.5V"
					( Units "uVoltage" "V" 1.000000)
					( Origin gFrontEnd )
				)
				( objectFlag fObjectAlias )
				( objectStatus "page139_p1v5_lan" )
			)
			( signal "@baseboard_fab2_lib.baseboard_fab2(sch_1):p1v5_lan_i210"
				( alias ( signalRef "@baseboard_fab2_lib.baseboard_fab2(sch_1):page139_p1v5_lan_i210") )
				( attribute "VOLTAGE" "1.5"
					( Units "uVoltage" "V" 1.000000)
					( Status sAliasFlattened )
					( Origin gFrontEnd )
				)
				( attribute "CDS_PHYS_NET_NAME" "P1V5_LAN_I210"
					( Origin gPackager )
				)
				( objectStatus "P1V5_LAN_I210" )
			)
			( signal "@baseboard_fab2_lib.baseboard_fab2(sch_1):page139_p1v5_lan_i210"
				( attribute "VOLTAGE" "1.5"
					( Units "uVoltage" "V" 1.000000)
					( Origin gFrontEnd )
				)
				( objectFlag fObjectAlias )
				( objectStatus "page139_p1v5_lan_i210" )
			)
			( signal "@baseboard_fab2_lib.baseboard_fab2(sch_1):p3v3_stby_p1v5_lan_i210"
				( alias ( signalRef "@baseboard_fab2_lib.baseboard_fab2(sch_1):page139_p3v3_stby_p1v5_lan_i210") )
				( attribute "VOLTAGE" "3.3"
					( Units "uVoltage" "V" 1.000000)
					( Status sAliasFlattened )
					( Origin gFrontEnd )
				)
				( attribute "CDS_PHYS_NET_NAME" "P3V3_STBY_P1V5_LAN_I210"
					( Origin gPackager )
				)
				( objectStatus "P3V3_STBY_P1V5_LAN_I210" )
			)
			( signal "@baseboard_fab2_lib.baseboard_fab2(sch_1):page139_p3v3_stby_p1v5_lan_i210"
				( attribute "VOLTAGE" "3.3"
					( Units "uVoltage" "V" 1.000000)
					( Origin gFrontEnd )
				)
				( objectFlag fObjectAlias )
				( objectStatus "page139_p3v3_stby_p1v5_lan_i210" )
			)
			( signal "@baseboard_fab2_lib.baseboard_fab2(sch_1):pd_sprv_rset"
				( attribute "CDS_PHYS_NET_NAME" "PD_SPRV_RSET"
					( Origin gPackager )
				)
				( objectStatus "PD_SPRV_RSET" )
			)
			( signal "@baseboard_fab2_lib.baseboard_fab2(sch_1):pe_pch_sprv_rx_dn"
				( attribute "CDS_PHYS_NET_NAME" "PE_PCH_SPRV_RX_DN"
					( Origin gPackager )
				)
				( objectStatus "PE_PCH_SPRV_RX_DN" )
			)
			( signal "@baseboard_fab2_lib.baseboard_fab2(sch_1):pe_pch_sprv_rx_dp"
				( attribute "CDS_PHYS_NET_NAME" "PE_PCH_SPRV_RX_DP"
					( Origin gPackager )
				)
				( objectStatus "PE_PCH_SPRV_RX_DP" )
			)
			( signal "@baseboard_fab2_lib.baseboard_fab2(sch_1):pe_pch_sprv_tx_c_dn"
				( attribute "CDS_PHYS_NET_NAME" "PE_PCH_SPRV_TX_C_DN"
					( Origin gPackager )
				)
				( objectStatus "PE_PCH_SPRV_TX_C_DN" )
			)
			( signal "@baseboard_fab2_lib.baseboard_fab2(sch_1):pe_pch_sprv_tx_c_dp"
				( attribute "CDS_PHYS_NET_NAME" "PE_PCH_SPRV_TX_C_DP"
					( Origin gPackager )
				)
				( objectStatus "PE_PCH_SPRV_TX_C_DP" )
			)
			( signal "@baseboard_fab2_lib.baseboard_fab2(sch_1):pu_jtag_sprv_tck"
				( attribute "CDS_PHYS_NET_NAME" "PU_JTAG_SPRV_TCK"
					( Origin gPackager )
				)
				( objectStatus "PU_JTAG_SPRV_TCK" )
			)
			( signal "@baseboard_fab2_lib.baseboard_fab2(sch_1):pu_jtag_sprv_tdi"
				( attribute "CDS_PHYS_NET_NAME" "PU_JTAG_SPRV_TDI"
					( Origin gPackager )
				)
				( objectStatus "PU_JTAG_SPRV_TDI" )
			)
			( signal "@baseboard_fab2_lib.baseboard_fab2(sch_1):pu_jtag_sprv_tdo"
				( attribute "CDS_PHYS_NET_NAME" "PU_JTAG_SPRV_TDO"
					( Origin gPackager )
				)
				( objectStatus "PU_JTAG_SPRV_TDO" )
			)
			( signal "@baseboard_fab2_lib.baseboard_fab2(sch_1):pu_jtag_sprv_tms"
				( attribute "CDS_PHYS_NET_NAME" "PU_JTAG_SPRV_TMS"
					( Origin gPackager )
				)
				( objectStatus "PU_JTAG_SPRV_TMS" )
			)
			( signal "@baseboard_fab2_lib.baseboard_fab2(sch_1):pu_sprv_lan_pwr_good"
				( attribute "CDS_PHYS_NET_NAME" "PU_SPRV_LAN_PWR_GOOD"
					( Origin gPackager )
				)
				( objectStatus "PU_SPRV_LAN_PWR_GOOD" )
			)
			( signal "@baseboard_fab2_lib.baseboard_fab2(sch_1):rmii_bmc_pch_sprngvlle_crsdv_r"
				( attribute "CDS_PHYS_NET_NAME" "RMII_BMC_PCH_SPRNGVLLE_CRSDV_R"
					( Origin gPackager )
				)
				( objectStatus "RMII_BMC_PCH_SPRNGVLLE_CRSDV_R" )
			)
			( signal "@baseboard_fab2_lib.baseboard_fab2(sch_1):rmii_pch_sprngvlle_arb_in_r"
				( attribute "CDS_PHYS_NET_NAME" "RMII_PCH_SPRNGVLLE_ARB_IN_R"
					( Origin gPackager )
				)
				( objectStatus "RMII_PCH_SPRNGVLLE_ARB_IN_R" )
			)
			( signal "@baseboard_fab2_lib.baseboard_fab2(sch_1):rmii_sprngvlle_bmc_pch_rxd0_r"
				( attribute "CDS_PHYS_NET_NAME" "RMII_SPRNGVLLE_BMC_PCH_RXD0_R"
					( Origin gPackager )
				)
				( objectStatus "RMII_SPRNGVLLE_BMC_PCH_RXD0_R" )
			)
			( signal "@baseboard_fab2_lib.baseboard_fab2(sch_1):rmii_sprngvlle_bmc_pch_rxd1_r"
				( attribute "CDS_PHYS_NET_NAME" "RMII_SPRNGVLLE_BMC_PCH_RXD1_R"
					( Origin gPackager )
				)
				( objectStatus "RMII_SPRNGVLLE_BMC_PCH_RXD1_R" )
			)
			( signal "@baseboard_fab2_lib.baseboard_fab2(sch_1):rst_pltrst_sprv_r_n"
				( attribute "CDS_PHYS_NET_NAME" "RST_PLTRST_SPRV_R_N"
					( Origin gPackager )
				)
				( objectStatus "RST_PLTRST_SPRV_R_N" )
			)
			( signal "@baseboard_fab2_lib.baseboard_fab2(sch_1):smb_springville_stby_lvc3_scl"
				( attribute "CDS_PHYS_NET_NAME" "SMB_SPRINGVILLE_STBY_LVC3_SCL"
					( Origin gPackager )
				)
				( objectStatus "SMB_SPRINGVILLE_STBY_LVC3_SCL" )
			)
			( signal "@baseboard_fab2_lib.baseboard_fab2(sch_1):smb_springville_stby_lvc3_sda"
				( attribute "CDS_PHYS_NET_NAME" "SMB_SPRINGVILLE_STBY_LVC3_SDA"
					( Origin gPackager )
				)
				( objectStatus "SMB_SPRINGVILLE_STBY_LVC3_SDA" )
			)
			( signal "@baseboard_fab2_lib.baseboard_fab2(sch_1):spi_nic_cs_n"
				( attribute "CDS_PHYS_NET_NAME" "SPI_NIC_CS_N"
					( Origin gPackager )
				)
				( objectStatus "SPI_NIC_CS_N" )
			)
			( signal "@baseboard_fab2_lib.baseboard_fab2(sch_1):spi_nic_cs_r_n"
				( attribute "CDS_PHYS_NET_NAME" "SPI_NIC_CS_R_N"
					( Origin gPackager )
				)
				( objectStatus "SPI_NIC_CS_R_N" )
			)
			( signal "@baseboard_fab2_lib.baseboard_fab2(sch_1):spi_nic_miso"
				( attribute "CDS_PHYS_NET_NAME" "SPI_NIC_MISO"
					( Origin gPackager )
				)
				( objectStatus "SPI_NIC_MISO" )
			)
			( signal "@baseboard_fab2_lib.baseboard_fab2(sch_1):spi_nic_mosi"
				( attribute "CDS_PHYS_NET_NAME" "SPI_NIC_MOSI"
					( Origin gPackager )
				)
				( objectStatus "SPI_NIC_MOSI" )
			)
			( signal "@baseboard_fab2_lib.baseboard_fab2(sch_1):spi_nic_mosi_r"
				( attribute "CDS_PHYS_NET_NAME" "SPI_NIC_MOSI_R"
					( Origin gPackager )
				)
				( objectStatus "SPI_NIC_MOSI_R" )
			)
			( signal "@baseboard_fab2_lib.baseboard_fab2(sch_1):spi_nic_sclk"
				( attribute "CDS_PHYS_NET_NAME" "SPI_NIC_SCLK"
					( Origin gPackager )
				)
				( objectStatus "SPI_NIC_SCLK" )
			)
			( signal "@baseboard_fab2_lib.baseboard_fab2(sch_1):spi_nic_sclk_r"
				( attribute "CDS_PHYS_NET_NAME" "SPI_NIC_SCLK_R"
					( Origin gPackager )
				)
				( objectStatus "SPI_NIC_SCLK_R" )
			)
			( signal "@baseboard_fab2_lib.baseboard_fab2(sch_1):tp_sprv_sdp0"
				( attribute "CDS_PHYS_NET_NAME" "TP_SPRV_SDP0"
					( Origin gPackager )
				)
				( objectStatus "TP_SPRV_SDP0" )
			)
			( signal "@baseboard_fab2_lib.baseboard_fab2(sch_1):tp_sprv_sdp1"
				( attribute "CDS_PHYS_NET_NAME" "TP_SPRV_SDP1"
					( Origin gPackager )
				)
				( objectStatus "TP_SPRV_SDP1" )
			)
			( signal "@baseboard_fab2_lib.baseboard_fab2(sch_1):tp_sprv_sdp2"
				( attribute "CDS_PHYS_NET_NAME" "TP_SPRV_SDP2"
					( Origin gPackager )
				)
				( objectStatus "TP_SPRV_SDP2" )
			)
			( signal "@baseboard_fab2_lib.baseboard_fab2(sch_1):tp_sprv_sdp3"
				( attribute "CDS_PHYS_NET_NAME" "TP_SPRV_SDP3"
					( Origin gPackager )
				)
				( objectStatus "TP_SPRV_SDP3" )
			)
			( signal "@baseboard_fab2_lib.baseboard_fab2(sch_1):xtal_25mhz_in"
				( attribute "CDS_PHYS_NET_NAME" "XTAL_25MHZ_IN"
					( Origin gPackager )
				)
				( objectStatus "XTAL_25MHZ_IN" )
			)
			( signal "@baseboard_fab2_lib.baseboard_fab2(sch_1):xtal_25mhz_in_r"
				( attribute "CDS_PHYS_NET_NAME" "XTAL_25MHZ_IN_R"
					( Origin gPackager )
				)
				( objectStatus "XTAL_25MHZ_IN_R" )
			)
			( signal "@baseboard_fab2_lib.baseboard_fab2(sch_1):xtal_25mhz_out"
				( attribute "CDS_PHYS_NET_NAME" "XTAL_25MHZ_OUT"
					( Origin gPackager )
				)
				( objectStatus "XTAL_25MHZ_OUT" )
			)
			( signal "@baseboard_fab2_lib.baseboard_fab2(sch_1):xtal_25mhz_out_r"
				( attribute "CDS_PHYS_NET_NAME" "XTAL_25MHZ_OUT_R"
					( Origin gPackager )
				)
				( objectStatus "XTAL_25MHZ_OUT_R" )
			)
			( signal "@baseboard_fab2_lib.baseboard_fab2(sch_1):pu_nv_hold_n"
				( attribute "CDS_PHYS_NET_NAME" "PU_NV_HOLD_N"
					( Origin gPackager )
				)
				( objectStatus "PU_NV_HOLD_N" )
			)
			( signal "@baseboard_fab2_lib.baseboard_fab2(sch_1):pu_nv_wp_n"
				( attribute "CDS_PHYS_NET_NAME" "PU_NV_WP_N"
					( Origin gPackager )
				)
				( objectStatus "PU_NV_WP_N" )
			)
			( signal "@baseboard_fab2_lib.baseboard_fab2(sch_1):spi_nic_miso_r"
				( attribute "CDS_PHYS_NET_NAME" "SPI_NIC_MISO_R"
					( Origin gPackager )
				)
				( objectStatus "SPI_NIC_MISO_R" )
			)
			( signal "@baseboard_fab2_lib.baseboard_fab2(sch_1):gnd_lan_trct1234_c"
				( alias ( signalRef "@baseboard_fab2_lib.baseboard_fab2(sch_1):page141_gnd_lan_trct1234_c") )
				( attribute "VOLTAGE" "0"
					( Units "uVoltage" "V" 1.000000)
					( Status sAliasFlattened )
					( Origin gFrontEnd )
				)
				( attribute "CDS_PHYS_NET_NAME" "GND_LAN_TRCT1234_C"
					( Origin gPackager )
				)
				( objectStatus "GND_LAN_TRCT1234_C" )
			)
			( signal "@baseboard_fab2_lib.baseboard_fab2(sch_1):page141_gnd_lan_trct1234_c"
				( attribute "VOLTAGE" "0"
					( Units "uVoltage" "V" 1.000000)
					( Origin gFrontEnd )
				)
				( objectFlag fObjectAlias )
				( objectStatus "page141_gnd_lan_trct1234_c" )
			)
			( signal "@baseboard_fab2_lib.baseboard_fab2(sch_1):gnd_nic"
				( alias ( signalRef "@baseboard_fab2_lib.baseboard_fab2(sch_1):page141_gnd_nic") )
				( attribute "VOLTAGE" "0.0V"
					( Units "uVoltage" "V" 1.000000)
					( Status sAliasFlattened )
					( Origin gFrontEnd )
				)
				( attribute "CDS_PHYS_NET_NAME" "GND_NIC"
					( Origin gPackager )
				)
				( objectStatus "GND_NIC" )
			)
			( signal "@baseboard_fab2_lib.baseboard_fab2(sch_1):page141_gnd_nic"
				( attribute "VOLTAGE" "0.0V"
					( Units "uVoltage" "V" 1.000000)
					( Origin gFrontEnd )
				)
				( objectFlag fObjectAlias )
				( objectStatus "page141_gnd_nic" )
			)
			( signal "@baseboard_fab2_lib.baseboard_fab2(sch_1):led_lan_0_r_n"
				( attribute "CDS_PHYS_NET_NAME" "LED_LAN_0_R_N"
					( Origin gPackager )
				)
				( objectStatus "LED_LAN_0_R_N" )
			)
			( signal "@baseboard_fab2_lib.baseboard_fab2(sch_1):led_lan_1_r_n"
				( attribute "CDS_PHYS_NET_NAME" "LED_LAN_1_R_N"
					( Origin gPackager )
				)
				( objectStatus "LED_LAN_1_R_N" )
			)
			( signal "@baseboard_fab2_lib.baseboard_fab2(sch_1):led_lan_2_r_n"
				( attribute "CDS_PHYS_NET_NAME" "LED_LAN_2_R_N"
					( Origin gPackager )
				)
				( objectStatus "LED_LAN_2_R_N" )
			)
			( signal "@baseboard_fab2_lib.baseboard_fab2(sch_1):nic_led_act_anode_r"
				( attribute "CDS_PHYS_NET_NAME" "NIC_LED_ACT_ANODE_R"
					( Origin gPackager )
				)
				( objectStatus "NIC_LED_ACT_ANODE_R" )
			)
			( signal "@baseboard_fab2_lib.baseboard_fab2(sch_1):nic_mdi_mng_rx_dn"
				( attribute "CDS_PHYS_NET_NAME" "NIC_MDI_MNG_RX_DN"
					( Origin gPackager )
				)
				( objectStatus "NIC_MDI_MNG_RX_DN" )
			)
			( signal "@baseboard_fab2_lib.baseboard_fab2(sch_1):nic_mdi_mng_rx_dp"
				( attribute "CDS_PHYS_NET_NAME" "NIC_MDI_MNG_RX_DP"
					( Origin gPackager )
				)
				( objectStatus "NIC_MDI_MNG_RX_DP" )
			)
			( signal "@baseboard_fab2_lib.baseboard_fab2(sch_1):nic_mdi_mng_tx_dn"
				( attribute "CDS_PHYS_NET_NAME" "NIC_MDI_MNG_TX_DN"
					( Origin gPackager )
				)
				( objectStatus "NIC_MDI_MNG_TX_DN" )
			)
			( signal "@baseboard_fab2_lib.baseboard_fab2(sch_1):nic_mdi_mng_tx_dp"
				( attribute "CDS_PHYS_NET_NAME" "NIC_MDI_MNG_TX_DP"
					( Origin gPackager )
				)
				( objectStatus "NIC_MDI_MNG_TX_DP" )
			)
			( signal "@baseboard_fab2_lib.baseboard_fab2(sch_1):nic_mdi_sprv_rj45_0_r_dn"
				( attribute "CDS_PHYS_NET_NAME" "NIC_MDI_SPRV_RJ45_0_R_DN"
					( Origin gPackager )
				)
				( objectStatus "NIC_MDI_SPRV_RJ45_0_R_DN" )
			)
			( signal "@baseboard_fab2_lib.baseboard_fab2(sch_1):nic_mdi_sprv_rj45_0_r_dp"
				( attribute "CDS_PHYS_NET_NAME" "NIC_MDI_SPRV_RJ45_0_R_DP"
					( Origin gPackager )
				)
				( objectStatus "NIC_MDI_SPRV_RJ45_0_R_DP" )
			)
			( signal "@baseboard_fab2_lib.baseboard_fab2(sch_1):nic_mdi_sprv_rj45_1_r_dn"
				( attribute "CDS_PHYS_NET_NAME" "NIC_MDI_SPRV_RJ45_1_R_DN"
					( Origin gPackager )
				)
				( objectStatus "NIC_MDI_SPRV_RJ45_1_R_DN" )
			)
			( signal "@baseboard_fab2_lib.baseboard_fab2(sch_1):nic_mdi_sprv_rj45_1_r_dp"
				( attribute "CDS_PHYS_NET_NAME" "NIC_MDI_SPRV_RJ45_1_R_DP"
					( Origin gPackager )
				)
				( objectStatus "NIC_MDI_SPRV_RJ45_1_R_DP" )
			)
			( signal "@baseboard_fab2_lib.baseboard_fab2(sch_1):nic_mdi_sprv_rj45_2_r_dn"
				( attribute "CDS_PHYS_NET_NAME" "NIC_MDI_SPRV_RJ45_2_R_DN"
					( Origin gPackager )
				)
				( objectStatus "NIC_MDI_SPRV_RJ45_2_R_DN" )
			)
			( signal "@baseboard_fab2_lib.baseboard_fab2(sch_1):nic_mdi_sprv_rj45_2_r_dp"
				( attribute "CDS_PHYS_NET_NAME" "NIC_MDI_SPRV_RJ45_2_R_DP"
					( Origin gPackager )
				)
				( objectStatus "NIC_MDI_SPRV_RJ45_2_R_DP" )
			)
			( signal "@baseboard_fab2_lib.baseboard_fab2(sch_1):nic_mdi_sprv_rj45_3_r_dn"
				( attribute "CDS_PHYS_NET_NAME" "NIC_MDI_SPRV_RJ45_3_R_DN"
					( Origin gPackager )
				)
				( objectStatus "NIC_MDI_SPRV_RJ45_3_R_DN" )
			)
			( signal "@baseboard_fab2_lib.baseboard_fab2(sch_1):nic_mdi_sprv_rj45_3_r_dp"
				( attribute "CDS_PHYS_NET_NAME" "NIC_MDI_SPRV_RJ45_3_R_DP"
					( Origin gPackager )
				)
				( objectStatus "NIC_MDI_SPRV_RJ45_3_R_DP" )
			)
			( signal "@baseboard_fab2_lib.baseboard_fab2(sch_1):fm_all_wake_n"
				( attribute "CDS_PHYS_NET_NAME" "FM_ALL_WAKE_N"
					( Origin gPackager )
				)
				( objectStatus "FM_ALL_WAKE_N" )
			)
			( signal "@baseboard_fab2_lib.baseboard_fab2(sch_1):fm_pe_bmc_wake_n"
				( attribute "CDS_PHYS_NET_NAME" "FM_PE_BMC_WAKE_N"
					( Origin gPackager )
				)
				( objectStatus "FM_PE_BMC_WAKE_N" )
			)
			( signal "@baseboard_fab2_lib.baseboard_fab2(sch_1):fm_pe_m2_wake_n"
				( attribute "CDS_PHYS_NET_NAME" "FM_PE_M2_WAKE_N"
					( Origin gPackager )
				)
				( objectStatus "FM_PE_M2_WAKE_N" )
			)
			( signal "@baseboard_fab2_lib.baseboard_fab2(sch_1):fm_pe_ocp_wake_n"
				( attribute "CDS_PHYS_NET_NAME" "FM_PE_OCP_WAKE_N"
					( Origin gPackager )
				)
				( objectStatus "FM_PE_OCP_WAKE_N" )
			)
			( signal "@baseboard_fab2_lib.baseboard_fab2(sch_1):irq_lvc3_wake_r_n"
				( attribute "CDS_PHYS_NET_NAME" "IRQ_LVC3_WAKE_R_N"
					( Origin gPackager )
				)
				( objectStatus "IRQ_LVC3_WAKE_R_N" )
			)
			( signal "@baseboard_fab2_lib.baseboard_fab2(sch_1):pu_tri_state_en"
				( attribute "CDS_PHYS_NET_NAME" "PU_TRI_STATE_EN"
					( Origin gPackager )
				)
				( objectStatus "PU_TRI_STATE_EN" )
			)
			( signal "@baseboard_fab2_lib.baseboard_fab2(sch_1):jtag_bmc_tck"
				( attribute "CDS_PHYS_NET_NAME" "JTAG_BMC_TCK"
					( Origin gPackager )
				)
				( objectStatus "JTAG_BMC_TCK" )
			)
			( signal "@baseboard_fab2_lib.baseboard_fab2(sch_1):tp_vgavs_gpioj5"
				( attribute "CDS_PHYS_NET_NAME" "TP_VGAVS_GPIOJ5"
					( Origin gPackager )
				)
				( objectStatus "TP_VGAVS_GPIOJ5" )
			)
			( signal "@baseboard_fab2_lib.baseboard_fab2(sch_1):jtag_bmc_tdi"
				( attribute "CDS_PHYS_NET_NAME" "JTAG_BMC_TDI"
					( Origin gPackager )
				)
				( objectStatus "JTAG_BMC_TDI" )
			)
			( signal "@baseboard_fab2_lib.baseboard_fab2(sch_1):tp_vgahs_gpioj4"
				( attribute "CDS_PHYS_NET_NAME" "TP_VGAHS_GPIOJ4"
					( Origin gPackager )
				)
				( objectStatus "TP_VGAHS_GPIOJ4" )
			)
			( signal "@baseboard_fab2_lib.baseboard_fab2(sch_1):jtag_bmc_tdo"
				( attribute "CDS_PHYS_NET_NAME" "JTAG_BMC_TDO"
					( Origin gPackager )
				)
				( objectStatus "JTAG_BMC_TDO" )
			)
			( signal "@baseboard_fab2_lib.baseboard_fab2(sch_1):tp_ddcdat_gpioj7"
				( attribute "CDS_PHYS_NET_NAME" "TP_DDCDAT_GPIOJ7"
					( Origin gPackager )
				)
				( objectStatus "TP_DDCDAT_GPIOJ7" )
			)
			( signal "@baseboard_fab2_lib.baseboard_fab2(sch_1):jtag_bmc_tms"
				( attribute "CDS_PHYS_NET_NAME" "JTAG_BMC_TMS"
					( Origin gPackager )
				)
				( objectStatus "JTAG_BMC_TMS" )
			)
			( signal "@baseboard_fab2_lib.baseboard_fab2(sch_1):tp_ddcclk_gpioj6"
				( attribute "CDS_PHYS_NET_NAME" "TP_DDCCLK_GPIOJ6"
					( Origin gPackager )
				)
				( objectStatus "TP_DDCCLK_GPIOJ6" )
			)
			( signal "@baseboard_fab2_lib.baseboard_fab2(sch_1):jtag_bmc_trst_n"
				( attribute "CDS_PHYS_NET_NAME" "JTAG_BMC_TRST_N"
					( Origin gPackager )
				)
				( objectStatus "JTAG_BMC_TRST_N" )
			)
			( signal "@baseboard_fab2_lib.baseboard_fab2(sch_1):tp_dacr"
				( attribute "CDS_PHYS_NET_NAME" "TP_DACR"
					( Origin gPackager )
				)
				( objectStatus "TP_DACR" )
			)
			( signal "@baseboard_fab2_lib.baseboard_fab2(sch_1):sgpio_bmc_clk"
				( attribute "CDS_PHYS_NET_NAME" "SGPIO_BMC_CLK"
					( Origin gPackager )
				)
				( objectStatus "SGPIO_BMC_CLK" )
			)
			( signal "@baseboard_fab2_lib.baseboard_fab2(sch_1):sgpio_bmc_din"
				( attribute "CDS_PHYS_NET_NAME" "SGPIO_BMC_DIN"
					( Origin gPackager )
				)
				( objectStatus "SGPIO_BMC_DIN" )
			)
			( signal "@baseboard_fab2_lib.baseboard_fab2(sch_1):sgpio_bmc_dout"
				( attribute "CDS_PHYS_NET_NAME" "SGPIO_BMC_DOUT"
					( Origin gPackager )
				)
				( objectStatus "SGPIO_BMC_DOUT" )
			)
			( signal "@baseboard_fab2_lib.baseboard_fab2(sch_1):sgpio_bmc_ld_n"
				( attribute "CDS_PHYS_NET_NAME" "SGPIO_BMC_LD_N"
					( Origin gPackager )
				)
				( objectStatus "SGPIO_BMC_LD_N" )
			)
			( signal "@baseboard_fab2_lib.baseboard_fab2(sch_1):smb_bmc_pmbus_stby_lvc3_scl_r"
				( attribute "CDS_PHYS_NET_NAME" "SMB_BMC_PMBUS_STBY_LVC3_SCL_R"
					( Origin gPackager )
				)
				( objectStatus "SMB_BMC_PMBUS_STBY_LVC3_SCL_R" )
			)
			( signal "@baseboard_fab2_lib.baseboard_fab2(sch_1):smb_bmc_pmbus_stby_lvc3_sda_r"
				( attribute "CDS_PHYS_NET_NAME" "SMB_BMC_PMBUS_STBY_LVC3_SDA_R"
					( Origin gPackager )
				)
				( objectStatus "SMB_BMC_PMBUS_STBY_LVC3_SDA_R" )
			)
			( signal "@baseboard_fab2_lib.baseboard_fab2(sch_1):smb_host_stby_lvc3_scl_r"
				( attribute "CDS_PHYS_NET_NAME" "SMB_HOST_STBY_LVC3_SCL_R"
					( Origin gPackager )
				)
				( attribute "PHYS_NET_NAME" "SMB_HOST_STBY_LVC3_SCL_R"
					( Origin gPackager )
				)
				( objectStatus "SMB_HOST_STBY_LVC3_SCL_R" )
			)
			( signal "@baseboard_fab2_lib.baseboard_fab2(sch_1):smb_host_stby_lvc3_sda_r"
				( attribute "CDS_PHYS_NET_NAME" "SMB_HOST_STBY_LVC3_SDA_R"
					( Origin gPackager )
				)
				( attribute "PHYS_NET_NAME" "SMB_HOST_STBY_LVC3_SDA_R"
					( Origin gPackager )
				)
				( objectStatus "SMB_HOST_STBY_LVC3_SDA_R" )
			)
			( signal "@baseboard_fab2_lib.baseboard_fab2(sch_1):smb_lan_stby_lvc3_scl_r"
				( attribute "CDS_PHYS_NET_NAME" "SMB_LAN_STBY_LVC3_SCL_R"
					( Origin gPackager )
				)
				( objectStatus "SMB_LAN_STBY_LVC3_SCL_R" )
			)
			( signal "@baseboard_fab2_lib.baseboard_fab2(sch_1):smb_lan_stby_lvc3_sda_r"
				( attribute "CDS_PHYS_NET_NAME" "SMB_LAN_STBY_LVC3_SDA_R"
					( Origin gPackager )
				)
				( objectStatus "SMB_LAN_STBY_LVC3_SDA_R" )
			)
			( signal "@baseboard_fab2_lib.baseboard_fab2(sch_1):smb_ocp_fru_stby_lvc3_scl_r"
				( attribute "CDS_PHYS_NET_NAME" "SMB_OCP_FRU_STBY_LVC3_SCL_R"
					( Origin gPackager )
				)
				( objectStatus "SMB_OCP_FRU_STBY_LVC3_SCL_R" )
			)
			( signal "@baseboard_fab2_lib.baseboard_fab2(sch_1):smb_ocp_fru_stby_lvc3_sda_r"
				( attribute "CDS_PHYS_NET_NAME" "SMB_OCP_FRU_STBY_LVC3_SDA_R"
					( Origin gPackager )
				)
				( objectStatus "SMB_OCP_FRU_STBY_LVC3_SDA_R" )
			)
			( signal "@baseboard_fab2_lib.baseboard_fab2(sch_1):smb_ocp_lan_stby_lvc3_scl_r"
				( attribute "CDS_PHYS_NET_NAME" "SMB_OCP_LAN_STBY_LVC3_SCL_R"
					( Origin gPackager )
				)
				( objectStatus "SMB_OCP_LAN_STBY_LVC3_SCL_R" )
			)
			( signal "@baseboard_fab2_lib.baseboard_fab2(sch_1):smb_ocp_lan_stby_lvc3_sda_r"
				( attribute "CDS_PHYS_NET_NAME" "SMB_OCP_LAN_STBY_LVC3_SDA_R"
					( Origin gPackager )
				)
				( objectStatus "SMB_OCP_LAN_STBY_LVC3_SDA_R" )
			)
			( signal "@baseboard_fab2_lib.baseboard_fab2(sch_1):smb_sensor_bmc_stby_lvc3_scl"
				( attribute "CDS_PHYS_NET_NAME" "SMB_SENSOR_BMC_STBY_LVC3_SCL"
					( Origin gPackager )
				)
				( attribute "PHYS_NET_NAME" "SMB_SENSOR_BMC_STBY_LVC3_SCL"
					( Origin gPackager )
				)
				( objectStatus "SMB_SENSOR_BMC_STBY_LVC3_SCL" )
			)
			( signal "@baseboard_fab2_lib.baseboard_fab2(sch_1):smb_sensor_bmc_stby_lvc3_sda"
				( attribute "CDS_PHYS_NET_NAME" "SMB_SENSOR_BMC_STBY_LVC3_SDA"
					( Origin gPackager )
				)
				( attribute "PHYS_NET_NAME" "SMB_SENSOR_BMC_STBY_LVC3_SDA"
					( Origin gPackager )
				)
				( objectStatus "SMB_SENSOR_BMC_STBY_LVC3_SDA" )
			)
			( signal "@baseboard_fab2_lib.baseboard_fab2(sch_1):smb_slotx24_stby_lvc3_scl_r"
				( attribute "CDS_PHYS_NET_NAME" "SMB_SLOTX24_STBY_LVC3_SCL_R"
					( Origin gPackager )
				)
				( objectStatus "SMB_SLOTX24_STBY_LVC3_SCL_R" )
			)
			( signal "@baseboard_fab2_lib.baseboard_fab2(sch_1):smb_slotx24_stby_lvc3_sda_r"
				( attribute "CDS_PHYS_NET_NAME" "SMB_SLOTX24_STBY_LVC3_SDA_R"
					( Origin gPackager )
				)
				( objectStatus "SMB_SLOTX24_STBY_LVC3_SDA_R" )
			)
			( signal "@baseboard_fab2_lib.baseboard_fab2(sch_1):smb_smlink0_stby_lvc3_scl_r"
				( attribute "CDS_PHYS_NET_NAME" "SMB_SMLINK0_STBY_LVC3_SCL_R"
					( Origin gPackager )
				)
				( attribute "PHYS_NET_NAME" "SMB_SMLINK0_STBY_LVC3_SCL_R"
					( Origin gPackager )
				)
				( objectStatus "SMB_SMLINK0_STBY_LVC3_SCL_R" )
			)
			( signal "@baseboard_fab2_lib.baseboard_fab2(sch_1):smb_smlink0_stby_lvc3_sda_r"
				( attribute "CDS_PHYS_NET_NAME" "SMB_SMLINK0_STBY_LVC3_SDA_R"
					( Origin gPackager )
				)
				( attribute "PHYS_NET_NAME" "SMB_SMLINK0_STBY_LVC3_SDA_R"
					( Origin gPackager )
				)
				( objectStatus "SMB_SMLINK0_STBY_LVC3_SDA_R" )
			)
			( signal "@baseboard_fab2_lib.baseboard_fab2(sch_1):smb_vr_stby_lvc3_scl_r"
				( attribute "CDS_PHYS_NET_NAME" "SMB_VR_STBY_LVC3_SCL_R"
					( Origin gPackager )
				)
				( attribute "PHYS_NET_NAME" "SMB_VR_STBY_LVC3_SCL_R"
					( Origin gPackager )
				)
				( objectStatus "SMB_VR_STBY_LVC3_SCL_R" )
			)
			( signal "@baseboard_fab2_lib.baseboard_fab2(sch_1):smb_vr_stby_lvc3_sda_r"
				( attribute "CDS_PHYS_NET_NAME" "SMB_VR_STBY_LVC3_SDA_R"
					( Origin gPackager )
				)
				( attribute "PHYS_NET_NAME" "SMB_VR_STBY_LVC3_SDA_R"
					( Origin gPackager )
				)
				( objectStatus "SMB_VR_STBY_LVC3_SDA_R" )
			)
			( signal "@baseboard_fab2_lib.baseboard_fab2(sch_1):spi_bmc_clk"
				( attribute "CDS_PHYS_NET_NAME" "SPI_BMC_CLK"
					( Origin gPackager )
				)
				( objectStatus "SPI_BMC_CLK" )
			)
			( signal "@baseboard_fab2_lib.baseboard_fab2(sch_1):spi_bmc_cs0_n"
				( attribute "CDS_PHYS_NET_NAME" "SPI_BMC_CS0_N"
					( Origin gPackager )
				)
				( objectStatus "SPI_BMC_CS0_N" )
			)
			( signal "@baseboard_fab2_lib.baseboard_fab2(sch_1):spi_bmc_di"
				( attribute "CDS_PHYS_NET_NAME" "SPI_BMC_DI"
					( Origin gPackager )
				)
				( objectStatus "SPI_BMC_DI" )
			)
			( signal "@baseboard_fab2_lib.baseboard_fab2(sch_1):spi_bmc_do"
				( attribute "CDS_PHYS_NET_NAME" "SPI_BMC_DO"
					( Origin gPackager )
				)
				( objectStatus "SPI_BMC_DO" )
			)
			( signal "@baseboard_fab2_lib.baseboard_fab2(sch_1):page149_p2v5_aux_bmc"
				( objectFlag fObjectAlias )
				( objectStatus "page149_p2v5_aux_bmc" )
			)
			( signal "@baseboard_fab2_lib.baseboard_fab2(sch_1):fm_bmc_onctl_n"
				( attribute "CDS_PHYS_NET_NAME" "FM_BMC_ONCTL_N"
					( Origin gPackager )
				)
				( objectStatus "FM_BMC_ONCTL_N" )
			)
			( signal "@baseboard_fab2_lib.baseboard_fab2(sch_1):fm_bmc_pwrbtn_out_n"
				( attribute "CDS_PHYS_NET_NAME" "FM_BMC_PWRBTN_OUT_N"
					( Origin gPackager )
				)
				( attribute "PHYS_NET_NAME" "FM_BMC_PWRBTN_OUT_N"
					( Origin gPackager )
				)
				( objectStatus "FM_BMC_PWRBTN_OUT_N" )
			)
			( signal "@baseboard_fab2_lib.baseboard_fab2(sch_1):h_cpu0_memabc_memhot_lvt3_bmc_n"
				( attribute "CDS_PHYS_NET_NAME" "H_CPU0_MEMABC_MEMHOT_LVT3_BMC_N"
					( Origin gPackager )
				)
				( attribute "PHYS_NET_NAME" "H_CPU0_MEMABC_MEMHOT_LVT3_BMC_N"
					( Origin gPackager )
				)
				( objectStatus "H_CPU0_MEMABC_MEMHOT_LVT3_BMC_N" )
			)
			( signal "@baseboard_fab2_lib.baseboard_fab2(sch_1):h_cpu0_memdef_memhot_lvt3_bmc_n"
				( attribute "CDS_PHYS_NET_NAME" "H_CPU0_MEMDEF_MEMHOT_LVT3_BMC_N"
					( Origin gPackager )
				)
				( attribute "PHYS_NET_NAME" "H_CPU0_MEMDEF_MEMHOT_LVT3_BMC_N"
					( Origin gPackager )
				)
				( objectStatus "H_CPU0_MEMDEF_MEMHOT_LVT3_BMC_N" )
			)
			( signal "@baseboard_fab2_lib.baseboard_fab2(sch_1):fm_cpu1_fivr_fault_lvt3_r_n"
				( attribute "CDS_PHYS_NET_NAME" "FM_CPU1_FIVR_FAULT_LVT3_R_N"
					( Origin gPackager )
				)
				( objectStatus "FM_CPU1_FIVR_FAULT_LVT3_R_N" )
			)
			( signal "@baseboard_fab2_lib.baseboard_fab2(sch_1):h_cpu1_memghj_memhot_lvt3_bmc_n"
				( attribute "CDS_PHYS_NET_NAME" "H_CPU1_MEMGHJ_MEMHOT_LVT3_BMC_N"
					( Origin gPackager )
				)
				( attribute "PHYS_NET_NAME" "H_CPU1_MEMGHJ_MEMHOT_LVT3_BMC_N"
					( Origin gPackager )
				)
				( objectStatus "H_CPU1_MEMGHJ_MEMHOT_LVT3_BMC_N" )
			)
			( signal "@baseboard_fab2_lib.baseboard_fab2(sch_1):fm_cpu0_fivr_fault_lvt3_r_n"
				( attribute "CDS_PHYS_NET_NAME" "FM_CPU0_FIVR_FAULT_LVT3_R_N"
					( Origin gPackager )
				)
				( objectStatus "FM_CPU0_FIVR_FAULT_LVT3_R_N" )
			)
			( signal "@baseboard_fab2_lib.baseboard_fab2(sch_1):h_cpu1_memklm_memhot_lvt3_bmc_n"
				( attribute "CDS_PHYS_NET_NAME" "H_CPU1_MEMKLM_MEMHOT_LVT3_BMC_N"
					( Origin gPackager )
				)
				( attribute "PHYS_NET_NAME" "H_CPU1_MEMKLM_MEMHOT_LVT3_BMC_N"
					( Origin gPackager )
				)
				( objectStatus "H_CPU1_MEMKLM_MEMHOT_LVT3_BMC_N" )
			)
			( signal "@baseboard_fab2_lib.baseboard_fab2(sch_1):p2e_ssb_bmc_rx_dn"
				( attribute "CDS_PHYS_NET_NAME" "P2E_SSB_BMC_RX_DN"
					( Origin gPackager )
				)
				( objectStatus "P2E_SSB_BMC_RX_DN" )
			)
			( signal "@baseboard_fab2_lib.baseboard_fab2(sch_1):p2e_ssb_bmc_rx_dp"
				( attribute "CDS_PHYS_NET_NAME" "P2E_SSB_BMC_RX_DP"
					( Origin gPackager )
				)
				( objectStatus "P2E_SSB_BMC_RX_DP" )
			)
			( signal "@baseboard_fab2_lib.baseboard_fab2(sch_1):pd_perext"
				( attribute "CDS_PHYS_NET_NAME" "PD_PEREXT"
					( Origin gPackager )
				)
				( objectStatus "PD_PEREXT" )
			)
			( signal "@baseboard_fab2_lib.baseboard_fab2(sch_1):clk_24m_bmc_clkin_r"
				( attribute "CDS_PHYS_NET_NAME" "CLK_24M_BMC_CLKIN_R"
					( Origin gPackager )
				)
				( objectStatus "CLK_24M_BMC_CLKIN_R" )
			)
			( signal "@baseboard_fab2_lib.baseboard_fab2(sch_1):peci_bmc"
				( attribute "CDS_PHYS_NET_NAME" "PECI_BMC"
					( Origin gPackager )
				)
				( objectStatus "PECI_BMC" )
			)
			( signal "@baseboard_fab2_lib.baseboard_fab2(sch_1):pd_sp_entest"
				( attribute "CDS_PHYS_NET_NAME" "PD_SP_ENTEST"
					( Origin gPackager )
				)
				( objectStatus "PD_SP_ENTEST" )
			)
			( signal "@baseboard_fab2_lib.baseboard_fab2(sch_1):clk_24m_25m_bmc_clkin"
				( attribute "CDS_PHYS_NET_NAME" "CLK_24M_25M_BMC_CLKIN"
					( Origin gPackager )
				)
				( objectStatus "CLK_24M_25M_BMC_CLKIN" )
			)
			( signal "@baseboard_fab2_lib.baseboard_fab2(sch_1):rst_bmc_sysrst_btn_out_n"
				( attribute "CDS_PHYS_NET_NAME" "RST_BMC_SYSRST_BTN_OUT_N"
					( Origin gPackager )
				)
				( attribute "PHYS_NET_NAME" "RST_BMC_SYSRST_BTN_OUT_N"
					( Origin gPackager )
				)
				( objectStatus "RST_BMC_SYSRST_BTN_OUT_N" )
			)
			( signal "@baseboard_fab2_lib.baseboard_fab2(sch_1):sp1_bmc_host_uart_rx"
				( attribute "CDS_PHYS_NET_NAME" "SP1_BMC_HOST_UART_RX"
					( Origin gPackager )
				)
				( attribute "PHYS_NET_NAME" "SP1_BMC_HOST_UART_RX"
					( Origin gPackager )
				)
				( objectStatus "SP1_BMC_HOST_UART_RX" )
			)
			( signal "@baseboard_fab2_lib.baseboard_fab2(sch_1):sp1_bmc_host_uart_tx"
				( attribute "CDS_PHYS_NET_NAME" "SP1_BMC_HOST_UART_TX"
					( Origin gPackager )
				)
				( attribute "PHYS_NET_NAME" "SP1_BMC_HOST_UART_TX"
					( Origin gPackager )
				)
				( objectStatus "SP1_BMC_HOST_UART_TX" )
			)
			( signal "@baseboard_fab2_lib.baseboard_fab2(sch_1):uart_bmc_rxd5"
				( attribute "CDS_PHYS_NET_NAME" "UART_BMC_RXD5"
					( Origin gPackager )
				)
				( objectStatus "UART_BMC_RXD5" )
			)
			( signal "@baseboard_fab2_lib.baseboard_fab2(sch_1):uart_bmc_txd5"
				( attribute "CDS_PHYS_NET_NAME" "UART_BMC_TXD5"
					( Origin gPackager )
				)
				( attribute "PHYS_NET_NAME" "UART_BMC_TXD5"
					( Origin gPackager )
				)
				( objectStatus "UART_BMC_TXD5" )
			)
			( signal "@baseboard_fab2_lib.baseboard_fab2(sch_1):tp_tpm_spi_6"
				( attribute "CDS_PHYS_NET_NAME" "TP_TPM_SPI_6"
					( Origin gPackager )
				)
				( objectStatus "TP_TPM_SPI_6" )
			)
			( signal "@baseboard_fab2_lib.baseboard_fab2(sch_1):tp_tpm_spi_5"
				( attribute "CDS_PHYS_NET_NAME" "TP_TPM_SPI_5"
					( Origin gPackager )
				)
				( objectStatus "TP_TPM_SPI_5" )
			)
			( signal "@baseboard_fab2_lib.baseboard_fab2(sch_1):tp_tpm_spi_4"
				( attribute "CDS_PHYS_NET_NAME" "TP_TPM_SPI_4"
					( Origin gPackager )
				)
				( objectStatus "TP_TPM_SPI_4" )
			)
			( signal "@baseboard_fab2_lib.baseboard_fab2(sch_1):tp_tpm_spi_3"
				( attribute "CDS_PHYS_NET_NAME" "TP_TPM_SPI_3"
					( Origin gPackager )
				)
				( objectStatus "TP_TPM_SPI_3" )
			)
			( signal "@baseboard_fab2_lib.baseboard_fab2(sch_1):tp_tpm_spi_2"
				( attribute "CDS_PHYS_NET_NAME" "TP_TPM_SPI_2"
					( Origin gPackager )
				)
				( objectStatus "TP_TPM_SPI_2" )
			)
			( signal "@baseboard_fab2_lib.baseboard_fab2(sch_1):tp_tpm_spi_1"
				( attribute "CDS_PHYS_NET_NAME" "TP_TPM_SPI_1"
					( Origin gPackager )
				)
				( objectStatus "TP_TPM_SPI_1" )
			)
			( signal "@baseboard_fab2_lib.baseboard_fab2(sch_1):tp_tpm_spi_0"
				( attribute "CDS_PHYS_NET_NAME" "TP_TPM_SPI_0"
					( Origin gPackager )
				)
				( objectStatus "TP_TPM_SPI_0" )
			)
			( signal "@baseboard_fab2_lib.baseboard_fab2(sch_1):\spi_tpm_bmc_di_r_\"
				( attribute "CDS_PHYS_NET_NAME" "SPI_TPM_BMC_DI_R_"
					( Origin gPackager )
				)
				( objectStatus "SPI_TPM_BMC_DI_R_" )
			)
			( signal "@baseboard_fab2_lib.baseboard_fab2(sch_1):pu_tpm_spi_flash_reset_2_n"
				( attribute "CDS_PHYS_NET_NAME" "PU_TPM_SPI_FLASH_RESET_2_N"
					( Origin gPackager )
				)
				( objectStatus "PU_TPM_SPI_FLASH_RESET_2_N" )
			)
			( signal "@baseboard_fab2_lib.baseboard_fab2(sch_1):pu_tpm_spi_bmc_wp_n"
				( attribute "CDS_PHYS_NET_NAME" "PU_TPM_SPI_BMC_WP_N"
					( Origin gPackager )
				)
				( objectStatus "PU_TPM_SPI_BMC_WP_N" )
			)
			( signal "@baseboard_fab2_lib.baseboard_fab2(sch_1):p3v3_usb2a_alg"
				( alias ( signalRef "@baseboard_fab2_lib.baseboard_fab2(sch_1):page150_p3v3_usb2a_alg") )
				( alias ( signalRef "@baseboard_fab2_lib.baseboard_fab2(sch_1):page148_p3v3_usb2a_alg") )
				( attribute "CDS_PHYS_NET_NAME" "P3V3_USB2A_ALG"
					( Origin gPackager )
				)
				( objectStatus "P3V3_USB2A_ALG" )
			)
			( signal "@baseboard_fab2_lib.baseboard_fab2(sch_1):page150_p3v3_usb2a_alg"
				( objectFlag fObjectAlias )
				( objectStatus "page150_p3v3_usb2a_alg" )
			)
			( signal "@baseboard_fab2_lib.baseboard_fab2(sch_1):pu_tpm_spi_bmc_hold_n"
				( attribute "CDS_PHYS_NET_NAME" "PU_TPM_SPI_BMC_HOLD_N"
					( Origin gPackager )
				)
				( objectStatus "PU_TPM_SPI_BMC_HOLD_N" )
			)
			( signal "@baseboard_fab2_lib.baseboard_fab2(sch_1):spi_bmc_bt_clk"
				( attribute "CDS_PHYS_NET_NAME" "SPI_BMC_BT_CLK"
					( Origin gPackager )
				)
				( objectStatus "SPI_BMC_BT_CLK" )
			)
			( signal "@baseboard_fab2_lib.baseboard_fab2(sch_1):spi_bmc_bt_clk_r"
				( attribute "CDS_PHYS_NET_NAME" "SPI_BMC_BT_CLK_R"
					( Origin gPackager )
				)
				( objectStatus "SPI_BMC_BT_CLK_R" )
			)
			( signal "@baseboard_fab2_lib.baseboard_fab2(sch_1):spi_bmc_bt_cs_n"
				( attribute "CDS_PHYS_NET_NAME" "SPI_BMC_BT_CS_N"
					( Origin gPackager )
				)
				( objectStatus "SPI_BMC_BT_CS_N" )
			)
			( signal "@baseboard_fab2_lib.baseboard_fab2(sch_1):spi_bmc_bt_cs_r_n"
				( attribute "CDS_PHYS_NET_NAME" "SPI_BMC_BT_CS_R_N"
					( Origin gPackager )
				)
				( objectStatus "SPI_BMC_BT_CS_R_N" )
			)
			( signal "@baseboard_fab2_lib.baseboard_fab2(sch_1):spi_bmc_bt_di"
				( attribute "CDS_PHYS_NET_NAME" "SPI_BMC_BT_DI"
					( Origin gPackager )
				)
				( attribute "PHYS_NET_NAME" "SPI_BMC_BT_DI"
					( Origin gPackager )
				)
				( objectStatus "SPI_BMC_BT_DI" )
			)
			( signal "@baseboard_fab2_lib.baseboard_fab2(sch_1):spi_bmc_bt_do"
				( attribute "CDS_PHYS_NET_NAME" "SPI_BMC_BT_DO"
					( Origin gPackager )
				)
				( objectStatus "SPI_BMC_BT_DO" )
			)
			( signal "@baseboard_fab2_lib.baseboard_fab2(sch_1):spi_bmc_bt_do_r"
				( attribute "CDS_PHYS_NET_NAME" "SPI_BMC_BT_DO_R"
					( Origin gPackager )
				)
				( objectStatus "SPI_BMC_BT_DO_R" )
			)
			( signal "@baseboard_fab2_lib.baseboard_fab2(sch_1):a_p12v_stby_scaled"
				( alias ( signalRef "@baseboard_fab2_lib.baseboard_fab2(sch_1):page169_a_p12v_stby_scaled") )
				( attribute "CDS_PHYS_NET_NAME" "A_P12V_STBY_SCALED"
					( Origin gPackager )
				)
				( attribute "PHYS_NET_NAME" "A_P12V_STBY_SCALED"
					( Origin gPackager )
				)
				( attribute "VOLTAGE" "+2V"
					( Units "uVoltage" "V" 1.000000)
					( Status sAliasFlattened )
					( Origin gFrontEnd )
				)
				( objectStatus "A_P12V_STBY_SCALED" )
			)
			( signal "@baseboard_fab2_lib.baseboard_fab2(sch_1):page169_a_p12v_stby_scaled"
				( attribute "VOLTAGE" "+2V"
					( Units "uVoltage" "V" 1.000000)
					( Origin gFrontEnd )
				)
				( objectFlag fObjectAlias )
				( objectStatus "page169_a_p12v_stby_scaled" )
			)
			( signal "@baseboard_fab2_lib.baseboard_fab2(sch_1):a_p1v05_stby_pch_sensor"
				( alias ( signalRef "@baseboard_fab2_lib.baseboard_fab2(sch_1):page169_a_p1v05_stby_pch_sensor") )
				( attribute "CDS_PHYS_NET_NAME" "A_P1V05_STBY_PCH_SENSOR"
					( Origin gPackager )
				)
				( attribute "PHYS_NET_NAME" "A_P1V05_STBY_PCH_SENSOR"
					( Origin gPackager )
				)
				( attribute "VOLTAGE" "+1.2V"
					( Units "uVoltage" "V" 1.000000)
					( Status sAliasFlattened )
					( Origin gFrontEnd )
				)
				( objectStatus "A_P1V05_STBY_PCH_SENSOR" )
			)
			( signal "@baseboard_fab2_lib.baseboard_fab2(sch_1):page169_a_p1v05_stby_pch_sensor"
				( attribute "VOLTAGE" "+1.2V"
					( Units "uVoltage" "V" 1.000000)
					( Origin gFrontEnd )
				)
				( objectFlag fObjectAlias )
				( objectStatus "page169_a_p1v05_stby_pch_sensor" )
			)
			( signal "@baseboard_fab2_lib.baseboard_fab2(sch_1):a_p3v3_scaled"
				( alias ( signalRef "@baseboard_fab2_lib.baseboard_fab2(sch_1):page169_a_p3v3_scaled") )
				( attribute "CDS_PHYS_NET_NAME" "A_P3V3_SCALED"
					( Origin gPackager )
				)
				( attribute "PHYS_NET_NAME" "A_P3V3_SCALED"
					( Origin gPackager )
				)
				( attribute "VOLTAGE" "+2V"
					( Units "uVoltage" "V" 1.000000)
					( Status sAliasFlattened )
					( Origin gFrontEnd )
				)
				( objectStatus "A_P3V3_SCALED" )
			)
			( signal "@baseboard_fab2_lib.baseboard_fab2(sch_1):page169_a_p3v3_scaled"
				( attribute "VOLTAGE" "+2V"
					( Units "uVoltage" "V" 1.000000)
					( Origin gFrontEnd )
				)
				( objectFlag fObjectAlias )
				( objectStatus "page169_a_p3v3_scaled" )
			)
			( signal "@baseboard_fab2_lib.baseboard_fab2(sch_1):a_p3v3_stby_scaled"
				( alias ( signalRef "@baseboard_fab2_lib.baseboard_fab2(sch_1):page169_a_p3v3_stby_scaled") )
				( attribute "CDS_PHYS_NET_NAME" "A_P3V3_STBY_SCALED"
					( Origin gPackager )
				)
				( attribute "PHYS_NET_NAME" "A_P3V3_STBY_SCALED"
					( Origin gPackager )
				)
				( attribute "VOLTAGE" "+1.8V"
					( Units "uVoltage" "V" 1.000000)
					( Status sAliasFlattened )
					( Origin gFrontEnd )
				)
				( objectStatus "A_P3V3_STBY_SCALED" )
			)
			( signal "@baseboard_fab2_lib.baseboard_fab2(sch_1):page169_a_p3v3_stby_scaled"
				( attribute "VOLTAGE" "+1.8V"
					( Units "uVoltage" "V" 1.000000)
					( Origin gFrontEnd )
				)
				( objectFlag fObjectAlias )
				( objectStatus "page169_a_p3v3_stby_scaled" )
			)
			( signal "@baseboard_fab2_lib.baseboard_fab2(sch_1):a_p3v_bat_scaled"
				( alias ( signalRef "@baseboard_fab2_lib.baseboard_fab2(sch_1):page169_a_p3v_bat_scaled") )
				( attribute "CDS_PHYS_NET_NAME" "A_P3V_BAT_SCALED"
					( Origin gPackager )
				)
				( attribute "PHYS_NET_NAME" "A_P3V_BAT_SCALED"
					( Origin gPackager )
				)
				( attribute "VOLTAGE" "+1V"
					( Units "uVoltage" "V" 1.000000)
					( Status sAliasFlattened )
					( Origin gFrontEnd )
				)
				( objectStatus "A_P3V_BAT_SCALED" )
			)
			( signal "@baseboard_fab2_lib.baseboard_fab2(sch_1):page169_a_p3v_bat_scaled"
				( attribute "VOLTAGE" "+1V"
					( Units "uVoltage" "V" 1.000000)
					( Origin gFrontEnd )
				)
				( objectFlag fObjectAlias )
				( objectStatus "page169_a_p3v_bat_scaled" )
			)
			( signal "@baseboard_fab2_lib.baseboard_fab2(sch_1):a_p5v_scaled"
				( alias ( signalRef "@baseboard_fab2_lib.baseboard_fab2(sch_1):page169_a_p5v_scaled") )
				( attribute "CDS_PHYS_NET_NAME" "A_P5V_SCALED"
					( Origin gPackager )
				)
				( attribute "PHYS_NET_NAME" "A_P5V_SCALED"
					( Origin gPackager )
				)
				( attribute "VOLTAGE" "+2V"
					( Units "uVoltage" "V" 1.000000)
					( Status sAliasFlattened )
					( Origin gFrontEnd )
				)
				( objectStatus "A_P5V_SCALED" )
			)
			( signal "@baseboard_fab2_lib.baseboard_fab2(sch_1):page169_a_p5v_scaled"
				( attribute "VOLTAGE" "+2V"
					( Units "uVoltage" "V" 1.000000)
					( Origin gFrontEnd )
				)
				( objectFlag fObjectAlias )
				( objectStatus "page169_a_p5v_scaled" )
			)
			( signal "@baseboard_fab2_lib.baseboard_fab2(sch_1):a_p5v_stby_scaled"
				( alias ( signalRef "@baseboard_fab2_lib.baseboard_fab2(sch_1):page169_a_p5v_stby_scaled") )
				( attribute "CDS_PHYS_NET_NAME" "A_P5V_STBY_SCALED"
					( Origin gPackager )
				)
				( attribute "PHYS_NET_NAME" "A_P5V_STBY_SCALED"
					( Origin gPackager )
				)
				( attribute "VOLTAGE" "+2V"
					( Units "uVoltage" "V" 1.000000)
					( Status sAliasFlattened )
					( Origin gFrontEnd )
				)
				( objectStatus "A_P5V_STBY_SCALED" )
			)
			( signal "@baseboard_fab2_lib.baseboard_fab2(sch_1):page169_a_p5v_stby_scaled"
				( attribute "VOLTAGE" "+2V"
					( Units "uVoltage" "V" 1.000000)
					( Origin gFrontEnd )
				)
				( objectFlag fObjectAlias )
				( objectStatus "page169_a_p5v_stby_scaled" )
			)
			( signal "@baseboard_fab2_lib.baseboard_fab2(sch_1):a_pvnn_stby_pch_sensor"
				( alias ( signalRef "@baseboard_fab2_lib.baseboard_fab2(sch_1):page169_a_pvnn_stby_pch_sensor") )
				( attribute "CDS_PHYS_NET_NAME" "A_PVNN_STBY_PCH_SENSOR"
					( Origin gPackager )
				)
				( attribute "PHYS_NET_NAME" "A_PVNN_STBY_PCH_SENSOR"
					( Origin gPackager )
				)
				( attribute "VOLTAGE" "+1.2V"
					( Units "uVoltage" "V" 1.000000)
					( Status sAliasFlattened )
					( Origin gFrontEnd )
				)
				( objectStatus "A_PVNN_STBY_PCH_SENSOR" )
			)
			( signal "@baseboard_fab2_lib.baseboard_fab2(sch_1):page169_a_pvnn_stby_pch_sensor"
				( attribute "VOLTAGE" "+1.2V"
					( Units "uVoltage" "V" 1.000000)
					( Origin gFrontEnd )
				)
				( objectFlag fObjectAlias )
				( objectStatus "page169_a_pvnn_stby_pch_sensor" )
			)
			( signal "@baseboard_fab2_lib.baseboard_fab2(sch_1):fm_bios_spi_bmc_ctrl"
				( attribute "CDS_PHYS_NET_NAME" "FM_BIOS_SPI_BMC_CTRL"
					( Origin gPackager )
				)
				( attribute "PHYS_NET_NAME" "FM_BIOS_SPI_BMC_CTRL"
					( Origin gPackager )
				)
				( objectStatus "FM_BIOS_SPI_BMC_CTRL" )
			)
			( signal "@baseboard_fab2_lib.baseboard_fab2(sch_1):fm_heartbeat_led"
				( attribute "CDS_PHYS_NET_NAME" "FM_HEARTBEAT_LED"
					( Origin gPackager )
				)
				( objectStatus "FM_HEARTBEAT_LED" )
			)
			( signal "@baseboard_fab2_lib.baseboard_fab2(sch_1):fm_heartbeat_led_a"
				( attribute "CDS_PHYS_NET_NAME" "FM_HEARTBEAT_LED_A"
					( Origin gPackager )
				)
				( objectStatus "FM_HEARTBEAT_LED_A" )
			)
			( signal "@baseboard_fab2_lib.baseboard_fab2(sch_1):fm_heartbeat_led_k"
				( attribute "CDS_PHYS_NET_NAME" "FM_HEARTBEAT_LED_K"
					( Origin gPackager )
				)
				( objectStatus "FM_HEARTBEAT_LED_K" )
			)
			( signal "@baseboard_fab2_lib.baseboard_fab2(sch_1):p3v3_stby_bmc_adcvrefn"
				( alias ( signalRef "@baseboard_fab2_lib.baseboard_fab2(sch_1):page147_p3v3_stby_bmc_adcvrefn") )
				( attribute "CDS_PHYS_NET_NAME" "P3V3_STBY_BMC_ADCVREFN"
					( Origin gPackager )
				)
				( attribute "VOLTAGE" "+3.3V"
					( Units "uVoltage" "V" 1.000000)
					( Status sAliasFlattened )
					( Origin gFrontEnd )
				)
				( objectStatus "P3V3_STBY_BMC_ADCVREFN" )
			)
			( signal "@baseboard_fab2_lib.baseboard_fab2(sch_1):p3v3_stby_bmc_adcvrefp"
				( alias ( signalRef "@baseboard_fab2_lib.baseboard_fab2(sch_1):page147_p3v3_stby_bmc_adcvrefp") )
				( attribute "CDS_PHYS_NET_NAME" "P3V3_STBY_BMC_ADCVREFP"
					( Origin gPackager )
				)
				( attribute "VOLTAGE" "+3.3V"
					( Units "uVoltage" "V" 1.000000)
					( Status sAliasFlattened )
					( Origin gFrontEnd )
				)
				( objectStatus "P3V3_STBY_BMC_ADCVREFP" )
			)
			( signal "@baseboard_fab2_lib.baseboard_fab2(sch_1):pd_adcrext"
				( alias ( signalRef "@baseboard_fab2_lib.baseboard_fab2(sch_1):page147_pd_adcrext") )
				( attribute "CDS_PHYS_NET_NAME" "PD_ADCREXT"
					( Origin gPackager )
				)
				( objectStatus "PD_ADCREXT" )
			)
			( signal "@baseboard_fab2_lib.baseboard_fab2(sch_1):page150_vcc_adcav3v3"
				( objectFlag fObjectAlias )
				( objectStatus "page150_vcc_adcav3v3" )
			)
			( signal "@baseboard_fab2_lib.baseboard_fab2(sch_1):rmii_bmc_ocp_crsdv"
				( attribute "CDS_PHYS_NET_NAME" "RMII_BMC_OCP_CRSDV"
					( Origin gPackager )
				)
				( attribute "PHYS_NET_NAME" "RMII_BMC_OCP_CRSDV"
					( Origin gPackager )
				)
				( objectStatus "RMII_BMC_OCP_CRSDV" )
			)
			( signal "@baseboard_fab2_lib.baseboard_fab2(sch_1):rmii_bmc_ocp_rxd0"
				( attribute "CDS_PHYS_NET_NAME" "RMII_BMC_OCP_RXD0"
					( Origin gPackager )
				)
				( attribute "PHYS_NET_NAME" "RMII_BMC_OCP_RXD0"
					( Origin gPackager )
				)
				( objectStatus "RMII_BMC_OCP_RXD0" )
			)
			( signal "@baseboard_fab2_lib.baseboard_fab2(sch_1):rmii_bmc_ocp_rxd1"
				( attribute "CDS_PHYS_NET_NAME" "RMII_BMC_OCP_RXD1"
					( Origin gPackager )
				)
				( attribute "PHYS_NET_NAME" "RMII_BMC_OCP_RXD1"
					( Origin gPackager )
				)
				( objectStatus "RMII_BMC_OCP_RXD1" )
			)
			( signal "@baseboard_fab2_lib.baseboard_fab2(sch_1):rmii_bmc_ocp_rxer"
				( attribute "CDS_PHYS_NET_NAME" "RMII_BMC_OCP_RXER"
					( Origin gPackager )
				)
				( attribute "PHYS_NET_NAME" "RMII_BMC_OCP_RXER"
					( Origin gPackager )
				)
				( objectStatus "RMII_BMC_OCP_RXER" )
			)
			( signal "@baseboard_fab2_lib.baseboard_fab2(sch_1):rmii_bmc_ocp_txd0"
				( attribute "CDS_PHYS_NET_NAME" "RMII_BMC_OCP_TXD0"
					( Origin gPackager )
				)
				( objectStatus "RMII_BMC_OCP_TXD0" )
			)
			( signal "@baseboard_fab2_lib.baseboard_fab2(sch_1):rmii_bmc_ocp_txd0_r"
				( attribute "CDS_PHYS_NET_NAME" "RMII_BMC_OCP_TXD0_R"
					( Origin gPackager )
				)
				( objectStatus "RMII_BMC_OCP_TXD0_R" )
			)
			( signal "@baseboard_fab2_lib.baseboard_fab2(sch_1):rmii_bmc_ocp_txd1"
				( attribute "CDS_PHYS_NET_NAME" "RMII_BMC_OCP_TXD1"
					( Origin gPackager )
				)
				( objectStatus "RMII_BMC_OCP_TXD1" )
			)
			( signal "@baseboard_fab2_lib.baseboard_fab2(sch_1):rmii_bmc_ocp_txd1_r"
				( attribute "CDS_PHYS_NET_NAME" "RMII_BMC_OCP_TXD1_R"
					( Origin gPackager )
				)
				( objectStatus "RMII_BMC_OCP_TXD1_R" )
			)
			( signal "@baseboard_fab2_lib.baseboard_fab2(sch_1):rmii_bmc_ocp_txen"
				( attribute "CDS_PHYS_NET_NAME" "RMII_BMC_OCP_TXEN"
					( Origin gPackager )
				)
				( objectStatus "RMII_BMC_OCP_TXEN" )
			)
			( signal "@baseboard_fab2_lib.baseboard_fab2(sch_1):rmii_bmc_ocp_txen_r"
				( attribute "CDS_PHYS_NET_NAME" "RMII_BMC_OCP_TXEN_R"
					( Origin gPackager )
				)
				( objectStatus "RMII_BMC_OCP_TXEN_R" )
			)
			( signal "@baseboard_fab2_lib.baseboard_fab2(sch_1):rmii_bmc_pch_sprngvlle_txd0_r"
				( attribute "CDS_PHYS_NET_NAME" "RMII_BMC_PCH_SPRNGVLLE_TXD0_R"
					( Origin gPackager )
				)
				( objectStatus "RMII_BMC_PCH_SPRNGVLLE_TXD0_R" )
			)
			( signal "@baseboard_fab2_lib.baseboard_fab2(sch_1):rmii_bmc_pch_sprngvlle_txd1_r"
				( attribute "CDS_PHYS_NET_NAME" "RMII_BMC_PCH_SPRNGVLLE_TXD1_R"
					( Origin gPackager )
				)
				( objectStatus "RMII_BMC_PCH_SPRNGVLLE_TXD1_R" )
			)
			( signal "@baseboard_fab2_lib.baseboard_fab2(sch_1):rmii_bmc_sprngvlle_txen_r"
				( attribute "CDS_PHYS_NET_NAME" "RMII_BMC_SPRNGVLLE_TXEN_R"
					( Origin gPackager )
				)
				( objectStatus "RMII_BMC_SPRNGVLLE_TXEN_R" )
			)
			( signal "@baseboard_fab2_lib.baseboard_fab2(sch_1):tp_rgmii1txd2_gpiot4"
				( attribute "CDS_PHYS_NET_NAME" "TP_RGMII1TXD2_GPIOT4"
					( Origin gPackager )
				)
				( attribute "PHYS_NET_NAME" "TP_RGMII1TXD2_GPIOT4"
					( Origin gPackager )
				)
				( objectStatus "TP_RGMII1TXD2_GPIOT4" )
			)
			( signal "@baseboard_fab2_lib.baseboard_fab2(sch_1):tp_rgmii1txd3_gpiot5"
				( attribute "CDS_PHYS_NET_NAME" "TP_RGMII1TXD3_GPIOT5"
					( Origin gPackager )
				)
				( attribute "PHYS_NET_NAME" "TP_RGMII1TXD3_GPIOT5"
					( Origin gPackager )
				)
				( objectStatus "TP_RGMII1TXD3_GPIOT5" )
			)
			( signal "@baseboard_fab2_lib.baseboard_fab2(sch_1):tp_rgmii2txd2_gpiot4"
				( attribute "CDS_PHYS_NET_NAME" "TP_RGMII2TXD2_GPIOT4"
					( Origin gPackager )
				)
				( attribute "PHYS_NET_NAME" "TP_RGMII2TXD2_GPIOT4"
					( Origin gPackager )
				)
				( objectStatus "TP_RGMII2TXD2_GPIOT4" )
			)
			( signal "@baseboard_fab2_lib.baseboard_fab2(sch_1):tp_rgmii2txd3_gpiot5"
				( attribute "CDS_PHYS_NET_NAME" "TP_RGMII2TXD3_GPIOT5"
					( Origin gPackager )
				)
				( attribute "PHYS_NET_NAME" "TP_RGMII2TXD3_GPIOT5"
					( Origin gPackager )
				)
				( objectStatus "TP_RGMII2TXD3_GPIOT5" )
			)
			( signal "@baseboard_fab2_lib.baseboard_fab2(sch_1):page239_p1v2_aux_bmc"
				( attribute "VOLTAGE" "1.5"
					( Units "uVoltage" "V" 1.000000)
					( Origin gFrontEnd )
				)
				( objectFlag fObjectAlias )
				( objectStatus "page239_p1v2_aux_bmc" )
			)
			( signal "@baseboard_fab2_lib.baseboard_fab2(sch_1):vcc_dacav3v3"
				( alias ( signalRef "@baseboard_fab2_lib.baseboard_fab2(sch_1):page150_vcc_dacav3v3") )
				( alias ( signalRef "@baseboard_fab2_lib.baseboard_fab2(sch_1):page148_vcc_dacav3v3") )
				( attribute "CDS_PHYS_NET_NAME" "VCC_DACAV3V3"
					( Origin gPackager )
				)
				( objectStatus "VCC_DACAV3V3" )
			)
			( signal "@baseboard_fab2_lib.baseboard_fab2(sch_1):rst_bmc_ddr3_buf_in_n"
				( attribute "CDS_PHYS_NET_NAME" "RST_BMC_DDR3_BUF_IN_N"
					( Origin gPackager )
				)
				( objectStatus "RST_BMC_DDR3_BUF_IN_N" )
			)
			( signal "@baseboard_fab2_lib.baseboard_fab2(sch_1):vcc_adcav3v3"
				( alias ( signalRef "@baseboard_fab2_lib.baseboard_fab2(sch_1):page150_vcc_adcav3v3") )
				( alias ( signalRef "@baseboard_fab2_lib.baseboard_fab2(sch_1):page147_vcc_adcav3v3") )
				( alias ( signalRef "@baseboard_fab2_lib.baseboard_fab2(sch_1):page148_vcc_adcav3v3") )
				( attribute "VOLTAGE" "+3.3V"
					( Units "uVoltage" "V" 1.000000)
					( Status sAliasFlattened )
					( Origin gFrontEnd )
				)
				( attribute "CDS_PHYS_NET_NAME" "VCC_ADCAV3V3"
					( Origin gPackager )
				)
				( objectStatus "VCC_ADCAV3V3" )
			)
			( signal "@baseboard_fab2_lib.baseboard_fab2(sch_1):page148_vcc_adcav3v3"
				( objectFlag fObjectAlias )
				( objectStatus "page148_vcc_adcav3v3" )
			)
			( signal "@baseboard_fab2_lib.baseboard_fab2(sch_1):rst_bmc_ddr3_r_n"
				( attribute "CDS_PHYS_NET_NAME" "RST_BMC_DDR3_R_N"
					( Origin gPackager )
				)
				( objectStatus "RST_BMC_DDR3_R_N" )
			)
			( signal "@baseboard_fab2_lib.baseboard_fab2(sch_1):h_cpu0_abc_memhot_lvt3_r_n"
				( attribute "CDS_PHYS_NET_NAME" "H_CPU0_ABC_MEMHOT_LVT3_R_N"
					( Origin gPackager )
				)
				( objectStatus "H_CPU0_ABC_MEMHOT_LVT3_R_N" )
			)
			( signal "@baseboard_fab2_lib.baseboard_fab2(sch_1):h_cpu0_def_memhot_lvt3_r_n"
				( attribute "CDS_PHYS_NET_NAME" "H_CPU0_DEF_MEMHOT_LVT3_R_N"
					( Origin gPackager )
				)
				( objectStatus "H_CPU0_DEF_MEMHOT_LVT3_R_N" )
			)
			( signal "@baseboard_fab2_lib.baseboard_fab2(sch_1):h_cpu0_memabc_memhot_g_pch_n"
				( attribute "CDS_PHYS_NET_NAME" "H_CPU0_MEMABC_MEMHOT_G_PCH_N"
					( Origin gPackager )
				)
				( objectStatus "H_CPU0_MEMABC_MEMHOT_G_PCH_N" )
			)
			( signal "@baseboard_fab2_lib.baseboard_fab2(sch_1):h_cpu0_memabc_memhot_g_r_n"
				( attribute "CDS_PHYS_NET_NAME" "H_CPU0_MEMABC_MEMHOT_G_R_N"
					( Origin gPackager )
				)
				( objectStatus "H_CPU0_MEMABC_MEMHOT_G_R_N" )
			)
			( signal "@baseboard_fab2_lib.baseboard_fab2(sch_1):h_cpu0_memabc_memhot_lvt3_k_n"
				( attribute "CDS_PHYS_NET_NAME" "H_CPU0_MEMABC_MEMHOT_LVT3_K_N"
					( Origin gPackager )
				)
				( objectStatus "H_CPU0_MEMABC_MEMHOT_LVT3_K_N" )
			)
			( signal "@baseboard_fab2_lib.baseboard_fab2(sch_1):h_cpu0_memabc_memhot_lvt3_n"
				( attribute "CDS_PHYS_NET_NAME" "H_CPU0_MEMABC_MEMHOT_LVT3_N"
					( Origin gPackager )
				)
				( objectStatus "H_CPU0_MEMABC_MEMHOT_LVT3_N" )
			)
			( signal "@baseboard_fab2_lib.baseboard_fab2(sch_1):h_cpu0_memdef_memhot_g_pch_n"
				( attribute "CDS_PHYS_NET_NAME" "H_CPU0_MEMDEF_MEMHOT_G_PCH_N"
					( Origin gPackager )
				)
				( objectStatus "H_CPU0_MEMDEF_MEMHOT_G_PCH_N" )
			)
			( signal "@baseboard_fab2_lib.baseboard_fab2(sch_1):h_cpu0_memdef_memhot_g_r_n"
				( attribute "CDS_PHYS_NET_NAME" "H_CPU0_MEMDEF_MEMHOT_G_R_N"
					( Origin gPackager )
				)
				( objectStatus "H_CPU0_MEMDEF_MEMHOT_G_R_N" )
			)
			( signal "@baseboard_fab2_lib.baseboard_fab2(sch_1):h_cpu0_memdef_memhot_lvt3_k_n"
				( attribute "CDS_PHYS_NET_NAME" "H_CPU0_MEMDEF_MEMHOT_LVT3_K_N"
					( Origin gPackager )
				)
				( objectStatus "H_CPU0_MEMDEF_MEMHOT_LVT3_K_N" )
			)
			( signal "@baseboard_fab2_lib.baseboard_fab2(sch_1):h_cpu0_memdef_memhot_lvt3_n"
				( attribute "CDS_PHYS_NET_NAME" "H_CPU0_MEMDEF_MEMHOT_LVT3_N"
					( Origin gPackager )
				)
				( objectStatus "H_CPU0_MEMDEF_MEMHOT_LVT3_N" )
			)
			( signal "@baseboard_fab2_lib.baseboard_fab2(sch_1):h_cpu1_ghj_memhot_lvt3_r_n"
				( attribute "CDS_PHYS_NET_NAME" "H_CPU1_GHJ_MEMHOT_LVT3_R_N"
					( Origin gPackager )
				)
				( objectStatus "H_CPU1_GHJ_MEMHOT_LVT3_R_N" )
			)
			( signal "@baseboard_fab2_lib.baseboard_fab2(sch_1):h_cpu1_klm_memhot_lvt3_r_n"
				( attribute "CDS_PHYS_NET_NAME" "H_CPU1_KLM_MEMHOT_LVT3_R_N"
					( Origin gPackager )
				)
				( objectStatus "H_CPU1_KLM_MEMHOT_LVT3_R_N" )
			)
			( signal "@baseboard_fab2_lib.baseboard_fab2(sch_1):h_cpu1_memghj_memhot_g_pch_n"
				( attribute "CDS_PHYS_NET_NAME" "H_CPU1_MEMGHJ_MEMHOT_G_PCH_N"
					( Origin gPackager )
				)
				( objectStatus "H_CPU1_MEMGHJ_MEMHOT_G_PCH_N" )
			)
			( signal "@baseboard_fab2_lib.baseboard_fab2(sch_1):h_cpu1_memghj_memhot_g_r_n"
				( attribute "CDS_PHYS_NET_NAME" "H_CPU1_MEMGHJ_MEMHOT_G_R_N"
					( Origin gPackager )
				)
				( objectStatus "H_CPU1_MEMGHJ_MEMHOT_G_R_N" )
			)
			( signal "@baseboard_fab2_lib.baseboard_fab2(sch_1):h_cpu1_memghj_memhot_lvt3_k_n"
				( attribute "CDS_PHYS_NET_NAME" "H_CPU1_MEMGHJ_MEMHOT_LVT3_K_N"
					( Origin gPackager )
				)
				( objectStatus "H_CPU1_MEMGHJ_MEMHOT_LVT3_K_N" )
			)
			( signal "@baseboard_fab2_lib.baseboard_fab2(sch_1):h_cpu1_memghj_memhot_lvt3_n"
				( attribute "CDS_PHYS_NET_NAME" "H_CPU1_MEMGHJ_MEMHOT_LVT3_N"
					( Origin gPackager )
				)
				( objectStatus "H_CPU1_MEMGHJ_MEMHOT_LVT3_N" )
			)
			( signal "@baseboard_fab2_lib.baseboard_fab2(sch_1):h_cpu1_memklm_memhot_g_pch_n"
				( attribute "CDS_PHYS_NET_NAME" "H_CPU1_MEMKLM_MEMHOT_G_PCH_N"
					( Origin gPackager )
				)
				( objectStatus "H_CPU1_MEMKLM_MEMHOT_G_PCH_N" )
			)
			( signal "@baseboard_fab2_lib.baseboard_fab2(sch_1):h_cpu1_memklm_memhot_g_r_n"
				( attribute "CDS_PHYS_NET_NAME" "H_CPU1_MEMKLM_MEMHOT_G_R_N"
					( Origin gPackager )
				)
				( objectStatus "H_CPU1_MEMKLM_MEMHOT_G_R_N" )
			)
			( signal "@baseboard_fab2_lib.baseboard_fab2(sch_1):h_cpu1_memklm_memhot_lvt3_k_n"
				( attribute "CDS_PHYS_NET_NAME" "H_CPU1_MEMKLM_MEMHOT_LVT3_K_N"
					( Origin gPackager )
				)
				( objectStatus "H_CPU1_MEMKLM_MEMHOT_LVT3_K_N" )
			)
			( signal "@baseboard_fab2_lib.baseboard_fab2(sch_1):h_cpu1_memklm_memhot_lvt3_n"
				( attribute "CDS_PHYS_NET_NAME" "H_CPU1_MEMKLM_MEMHOT_LVT3_N"
					( Origin gPackager )
				)
				( objectStatus "H_CPU1_MEMKLM_MEMHOT_LVT3_N" )
			)
			( signal "@baseboard_fab2_lib.baseboard_fab2(sch_1):p0v7_gtl2014_2"
				( alias ( signalRef "@baseboard_fab2_lib.baseboard_fab2(sch_1):page152_p0v7_gtl2014_2") )
				( attribute "VOLTAGE" "+0.7"
					( Units "uVoltage" "V" 1.000000)
					( Status sAliasFlattened )
					( Origin gFrontEnd )
				)
				( attribute "CDS_PHYS_NET_NAME" "P0V7_GTL2014_2"
					( Origin gPackager )
				)
				( objectStatus "P0V7_GTL2014_2" )
			)
			( signal "@baseboard_fab2_lib.baseboard_fab2(sch_1):page152_p0v7_gtl2014_2"
				( attribute "VOLTAGE" "+0.7"
					( Units "uVoltage" "V" 1.000000)
					( Origin gFrontEnd )
				)
				( objectFlag fObjectAlias )
				( objectStatus "page152_p0v7_gtl2014_2" )
			)
			( signal "@baseboard_fab2_lib.baseboard_fab2(sch_1):pd_dir_2"
				( attribute "CDS_PHYS_NET_NAME" "PD_DIR_2"
					( Origin gPackager )
				)
				( objectStatus "PD_DIR_2" )
			)
			( signal "@baseboard_fab2_lib.baseboard_fab2(sch_1):pu_bios_spi_hold0_n"
				( attribute "CDS_PHYS_NET_NAME" "PU_BIOS_SPI_HOLD0_N"
					( Origin gPackager )
				)
				( objectStatus "PU_BIOS_SPI_HOLD0_N" )
			)
			( signal "@baseboard_fab2_lib.baseboard_fab2(sch_1):pu_bios_spi_hold1_n"
				( attribute "CDS_PHYS_NET_NAME" "PU_BIOS_SPI_HOLD1_N"
					( Origin gPackager )
				)
				( objectStatus "PU_BIOS_SPI_HOLD1_N" )
			)
			( signal "@baseboard_fab2_lib.baseboard_fab2(sch_1):pu_bios_spi_wp0_n"
				( attribute "CDS_PHYS_NET_NAME" "PU_BIOS_SPI_WP0_N"
					( Origin gPackager )
				)
				( objectStatus "PU_BIOS_SPI_WP0_N" )
			)
			( signal "@baseboard_fab2_lib.baseboard_fab2(sch_1):pu_bios_spi_wp1_n"
				( attribute "CDS_PHYS_NET_NAME" "PU_BIOS_SPI_WP1_N"
					( Origin gPackager )
				)
				( objectStatus "PU_BIOS_SPI_WP1_N" )
			)
			( signal "@baseboard_fab2_lib.baseboard_fab2(sch_1):pu_spi0_rst"
				( attribute "CDS_PHYS_NET_NAME" "PU_SPI0_RST"
					( Origin gPackager )
				)
				( objectStatus "PU_SPI0_RST" )
			)
			( signal "@baseboard_fab2_lib.baseboard_fab2(sch_1):pu_spi1_rst"
				( attribute "CDS_PHYS_NET_NAME" "PU_SPI1_RST"
					( Origin gPackager )
				)
				( objectStatus "PU_SPI1_RST" )
			)
			( signal "@baseboard_fab2_lib.baseboard_fab2(sch_1):spi_bios_socket_io2"
				( attribute "CDS_PHYS_NET_NAME" "SPI_BIOS_SOCKET_IO2"
					( Origin gPackager )
				)
				( objectStatus "SPI_BIOS_SOCKET_IO2" )
			)
			( signal "@baseboard_fab2_lib.baseboard_fab2(sch_1):spi_bios_socket_io3"
				( attribute "CDS_PHYS_NET_NAME" "SPI_BIOS_SOCKET_IO3"
					( Origin gPackager )
				)
				( objectStatus "SPI_BIOS_SOCKET_IO3" )
			)
			( signal "@baseboard_fab2_lib.baseboard_fab2(sch_1):spi_clk_r0"
				( attribute "CDS_PHYS_NET_NAME" "SPI_CLK_R0"
					( Origin gPackager )
				)
				( objectStatus "SPI_CLK_R0" )
			)
			( signal "@baseboard_fab2_lib.baseboard_fab2(sch_1):spi_clk_r1"
				( attribute "CDS_PHYS_NET_NAME" "SPI_CLK_R1"
					( Origin gPackager )
				)
				( objectStatus "SPI_CLK_R1" )
			)
			( signal "@baseboard_fab2_lib.baseboard_fab2(sch_1):spi_cs0_primary_r_n"
				( attribute "CDS_PHYS_NET_NAME" "SPI_CS0_PRIMARY_R_N"
					( Origin gPackager )
				)
				( objectStatus "SPI_CS0_PRIMARY_R_N" )
			)
			( signal "@baseboard_fab2_lib.baseboard_fab2(sch_1):spi_cs0_secondary_r_n"
				( attribute "CDS_PHYS_NET_NAME" "SPI_CS0_SECONDARY_R_N"
					( Origin gPackager )
				)
				( objectStatus "SPI_CS0_SECONDARY_R_N" )
			)
			( signal "@baseboard_fab2_lib.baseboard_fab2(sch_1):spi_miso_r0"
				( attribute "CDS_PHYS_NET_NAME" "SPI_MISO_R0"
					( Origin gPackager )
				)
				( objectStatus "SPI_MISO_R0" )
			)
			( signal "@baseboard_fab2_lib.baseboard_fab2(sch_1):spi_miso_r1"
				( attribute "CDS_PHYS_NET_NAME" "SPI_MISO_R1"
					( Origin gPackager )
				)
				( objectStatus "SPI_MISO_R1" )
			)
			( signal "@baseboard_fab2_lib.baseboard_fab2(sch_1):spi_switch_clk"
				( attribute "CDS_PHYS_NET_NAME" "SPI_SWITCH_CLK"
					( Origin gPackager )
				)
				( objectStatus "SPI_SWITCH_CLK" )
			)
			( signal "@baseboard_fab2_lib.baseboard_fab2(sch_1):spi_switch_miso"
				( attribute "CDS_PHYS_NET_NAME" "SPI_SWITCH_MISO"
					( Origin gPackager )
				)
				( objectStatus "SPI_SWITCH_MISO" )
			)
			( signal "@baseboard_fab2_lib.baseboard_fab2(sch_1):spi_switch_mosi"
				( attribute "CDS_PHYS_NET_NAME" "SPI_SWITCH_MOSI"
					( Origin gPackager )
				)
				( objectStatus "SPI_SWITCH_MOSI" )
			)
			( signal "@baseboard_fab2_lib.baseboard_fab2(sch_1):spi_switch_mosi_r0"
				( attribute "CDS_PHYS_NET_NAME" "SPI_SWITCH_MOSI_R0"
					( Origin gPackager )
				)
				( objectStatus "SPI_SWITCH_MOSI_R0" )
			)
			( signal "@baseboard_fab2_lib.baseboard_fab2(sch_1):spi_switch_mosi_r1"
				( attribute "CDS_PHYS_NET_NAME" "SPI_SWITCH_MOSI_R1"
					( Origin gPackager )
				)
				( objectStatus "SPI_SWITCH_MOSI_R1" )
			)
			( signal "@baseboard_fab2_lib.baseboard_fab2(sch_1):tp_spi_0_0"
				( attribute "CDS_PHYS_NET_NAME" "TP_SPI_0_0"
					( Origin gPackager )
				)
				( objectStatus "TP_SPI_0_0" )
			)
			( signal "@baseboard_fab2_lib.baseboard_fab2(sch_1):tp_spi_0_1"
				( attribute "CDS_PHYS_NET_NAME" "TP_SPI_0_1"
					( Origin gPackager )
				)
				( objectStatus "TP_SPI_0_1" )
			)
			( signal "@baseboard_fab2_lib.baseboard_fab2(sch_1):tp_spi_0_2"
				( attribute "CDS_PHYS_NET_NAME" "TP_SPI_0_2"
					( Origin gPackager )
				)
				( objectStatus "TP_SPI_0_2" )
			)
			( signal "@baseboard_fab2_lib.baseboard_fab2(sch_1):tp_spi_0_3"
				( attribute "CDS_PHYS_NET_NAME" "TP_SPI_0_3"
					( Origin gPackager )
				)
				( objectStatus "TP_SPI_0_3" )
			)
			( signal "@baseboard_fab2_lib.baseboard_fab2(sch_1):tp_spi_0_4"
				( attribute "CDS_PHYS_NET_NAME" "TP_SPI_0_4"
					( Origin gPackager )
				)
				( objectStatus "TP_SPI_0_4" )
			)
			( signal "@baseboard_fab2_lib.baseboard_fab2(sch_1):tp_spi_0_5"
				( attribute "CDS_PHYS_NET_NAME" "TP_SPI_0_5"
					( Origin gPackager )
				)
				( objectStatus "TP_SPI_0_5" )
			)
			( signal "@baseboard_fab2_lib.baseboard_fab2(sch_1):tp_spi_0_6"
				( attribute "CDS_PHYS_NET_NAME" "TP_SPI_0_6"
					( Origin gPackager )
				)
				( objectStatus "TP_SPI_0_6" )
			)
			( signal "@baseboard_fab2_lib.baseboard_fab2(sch_1):tp_spi_1_0"
				( attribute "CDS_PHYS_NET_NAME" "TP_SPI_1_0"
					( Origin gPackager )
				)
				( objectStatus "TP_SPI_1_0" )
			)
			( signal "@baseboard_fab2_lib.baseboard_fab2(sch_1):tp_spi_1_1"
				( attribute "CDS_PHYS_NET_NAME" "TP_SPI_1_1"
					( Origin gPackager )
				)
				( objectStatus "TP_SPI_1_1" )
			)
			( signal "@baseboard_fab2_lib.baseboard_fab2(sch_1):tp_spi_1_2"
				( attribute "CDS_PHYS_NET_NAME" "TP_SPI_1_2"
					( Origin gPackager )
				)
				( objectStatus "TP_SPI_1_2" )
			)
			( signal "@baseboard_fab2_lib.baseboard_fab2(sch_1):tp_spi_1_3"
				( attribute "CDS_PHYS_NET_NAME" "TP_SPI_1_3"
					( Origin gPackager )
				)
				( objectStatus "TP_SPI_1_3" )
			)
			( signal "@baseboard_fab2_lib.baseboard_fab2(sch_1):tp_spi_1_4"
				( attribute "CDS_PHYS_NET_NAME" "TP_SPI_1_4"
					( Origin gPackager )
				)
				( objectStatus "TP_SPI_1_4" )
			)
			( signal "@baseboard_fab2_lib.baseboard_fab2(sch_1):tp_spi_1_5"
				( attribute "CDS_PHYS_NET_NAME" "TP_SPI_1_5"
					( Origin gPackager )
				)
				( objectStatus "TP_SPI_1_5" )
			)
			( signal "@baseboard_fab2_lib.baseboard_fab2(sch_1):tp_spi_1_6"
				( attribute "CDS_PHYS_NET_NAME" "TP_SPI_1_6"
					( Origin gPackager )
				)
				( objectStatus "TP_SPI_1_6" )
			)
			( signal "@baseboard_fab2_lib.baseboard_fab2(sch_1):fm_dual_bios_sel_n"
				( attribute "CDS_PHYS_NET_NAME" "FM_DUAL_BIOS_SEL_N"
					( Origin gPackager )
				)
				( objectStatus "FM_DUAL_BIOS_SEL_N" )
			)
			( signal "@baseboard_fab2_lib.baseboard_fab2(sch_1):spi_cs0_primary_n"
				( attribute "CDS_PHYS_NET_NAME" "SPI_CS0_PRIMARY_N"
					( Origin gPackager )
				)
				( objectStatus "SPI_CS0_PRIMARY_N" )
			)
			( signal "@baseboard_fab2_lib.baseboard_fab2(sch_1):spi_cs0_secondary_n"
				( attribute "CDS_PHYS_NET_NAME" "SPI_CS0_SECONDARY_N"
					( Origin gPackager )
				)
				( objectStatus "SPI_CS0_SECONDARY_N" )
			)
			( signal "@baseboard_fab2_lib.baseboard_fab2(sch_1):spi_pch_io2_r1"
				( attribute "CDS_PHYS_NET_NAME" "SPI_PCH_IO2_R1"
					( Origin gPackager )
				)
				( objectStatus "SPI_PCH_IO2_R1" )
			)
			( signal "@baseboard_fab2_lib.baseboard_fab2(sch_1):spi_pch_io3_r1"
				( attribute "CDS_PHYS_NET_NAME" "SPI_PCH_IO3_R1"
					( Origin gPackager )
				)
				( objectStatus "SPI_PCH_IO3_R1" )
			)
			( signal "@baseboard_fab2_lib.baseboard_fab2(sch_1):spi_pch_miso_r"
				( attribute "CDS_PHYS_NET_NAME" "SPI_PCH_MISO_R"
					( Origin gPackager )
				)
				( objectStatus "SPI_PCH_MISO_R" )
			)
			( signal "@baseboard_fab2_lib.baseboard_fab2(sch_1):spi_switch_cs0_n"
				( attribute "CDS_PHYS_NET_NAME" "SPI_SWITCH_CS0_N"
					( Origin gPackager )
				)
				( objectStatus "SPI_SWITCH_CS0_N" )
			)
			( signal "@baseboard_fab2_lib.baseboard_fab2(sch_1):tp_spi_switch1_10"
				( attribute "CDS_PHYS_NET_NAME" "TP_SPI_SWITCH1_10"
					( Origin gPackager )
				)
				( objectStatus "TP_SPI_SWITCH1_10" )
			)
			( signal "@baseboard_fab2_lib.baseboard_fab2(sch_1):tp_spi_switch1_11"
				( attribute "CDS_PHYS_NET_NAME" "TP_SPI_SWITCH1_11"
					( Origin gPackager )
				)
				( objectStatus "TP_SPI_SWITCH1_11" )
			)
			( signal "@baseboard_fab2_lib.baseboard_fab2(sch_1):tp_spi_switch1_12"
				( attribute "CDS_PHYS_NET_NAME" "TP_SPI_SWITCH1_12"
					( Origin gPackager )
				)
				( objectStatus "TP_SPI_SWITCH1_12" )
			)
			( signal "@baseboard_fab2_lib.baseboard_fab2(sch_1):tp_spi_switch1_13"
				( attribute "CDS_PHYS_NET_NAME" "TP_SPI_SWITCH1_13"
					( Origin gPackager )
				)
				( objectStatus "TP_SPI_SWITCH1_13" )
			)
			( signal "@baseboard_fab2_lib.baseboard_fab2(sch_1):tp_spi_switch1_14"
				( attribute "CDS_PHYS_NET_NAME" "TP_SPI_SWITCH1_14"
					( Origin gPackager )
				)
				( objectStatus "TP_SPI_SWITCH1_14" )
			)
			( signal "@baseboard_fab2_lib.baseboard_fab2(sch_1):tp_spi_switch1_3"
				( attribute "CDS_PHYS_NET_NAME" "TP_SPI_SWITCH1_3"
					( Origin gPackager )
				)
				( objectStatus "TP_SPI_SWITCH1_3" )
			)
			( signal "@baseboard_fab2_lib.baseboard_fab2(sch_1):tp_spi_switch1_6"
				( attribute "CDS_PHYS_NET_NAME" "TP_SPI_SWITCH1_6"
					( Origin gPackager )
				)
				( objectStatus "TP_SPI_SWITCH1_6" )
			)
			( signal "@baseboard_fab2_lib.baseboard_fab2(sch_1):tp_spi_switch1_9"
				( attribute "CDS_PHYS_NET_NAME" "TP_SPI_SWITCH1_9"
					( Origin gPackager )
				)
				( objectStatus "TP_SPI_SWITCH1_9" )
			)
			( signal "@baseboard_fab2_lib.baseboard_fab2(sch_1):fm_cpld_dbg_pwr_en"
				( attribute "CDS_PHYS_NET_NAME" "FM_CPLD_DBG_PWR_EN"
					( Origin gPackager )
				)
				( objectStatus "FM_CPLD_DBG_PWR_EN" )
			)
			( signal "@baseboard_fab2_lib.baseboard_fab2(sch_1):fm_cpld_dbg_pwr_en_n"
				( attribute "CDS_PHYS_NET_NAME" "FM_CPLD_DBG_PWR_EN_N"
					( Origin gPackager )
				)
				( objectStatus "FM_CPLD_DBG_PWR_EN_N" )
			)
			( signal "@baseboard_fab2_lib.baseboard_fab2(sch_1):fm_cpld_dbg_pwr_en_r_n"
				( attribute "CDS_PHYS_NET_NAME" "FM_CPLD_DBG_PWR_EN_R_N"
					( Origin gPackager )
				)
				( objectStatus "FM_CPLD_DBG_PWR_EN_R_N" )
			)
			( signal "@baseboard_fab2_lib.baseboard_fab2(sch_1):fm_uart_switch_n"
				( attribute "CDS_PHYS_NET_NAME" "FM_UART_SWITCH_N"
					( Origin gPackager )
				)
				( objectStatus "FM_UART_SWITCH_N" )
			)
			( signal "@baseboard_fab2_lib.baseboard_fab2(sch_1):led_postcode_0_r"
				( attribute "CDS_PHYS_NET_NAME" "LED_POSTCODE_0_R"
					( Origin gPackager )
				)
				( objectStatus "LED_POSTCODE_0_R" )
			)
			( signal "@baseboard_fab2_lib.baseboard_fab2(sch_1):led_postcode_1_r"
				( attribute "CDS_PHYS_NET_NAME" "LED_POSTCODE_1_R"
					( Origin gPackager )
				)
				( objectStatus "LED_POSTCODE_1_R" )
			)
			( signal "@baseboard_fab2_lib.baseboard_fab2(sch_1):led_postcode_2_r"
				( attribute "CDS_PHYS_NET_NAME" "LED_POSTCODE_2_R"
					( Origin gPackager )
				)
				( objectStatus "LED_POSTCODE_2_R" )
			)
			( signal "@baseboard_fab2_lib.baseboard_fab2(sch_1):led_postcode_3_r"
				( attribute "CDS_PHYS_NET_NAME" "LED_POSTCODE_3_R"
					( Origin gPackager )
				)
				( objectStatus "LED_POSTCODE_3_R" )
			)
			( signal "@baseboard_fab2_lib.baseboard_fab2(sch_1):led_postcode_4_r"
				( attribute "CDS_PHYS_NET_NAME" "LED_POSTCODE_4_R"
					( Origin gPackager )
				)
				( objectStatus "LED_POSTCODE_4_R" )
			)
			( signal "@baseboard_fab2_lib.baseboard_fab2(sch_1):led_postcode_5_r"
				( attribute "CDS_PHYS_NET_NAME" "LED_POSTCODE_5_R"
					( Origin gPackager )
				)
				( objectStatus "LED_POSTCODE_5_R" )
			)
			( signal "@baseboard_fab2_lib.baseboard_fab2(sch_1):led_postcode_6_r"
				( attribute "CDS_PHYS_NET_NAME" "LED_POSTCODE_6_R"
					( Origin gPackager )
				)
				( objectStatus "LED_POSTCODE_6_R" )
			)
			( signal "@baseboard_fab2_lib.baseboard_fab2(sch_1):led_postcode_7_r"
				( attribute "CDS_PHYS_NET_NAME" "LED_POSTCODE_7_R"
					( Origin gPackager )
				)
				( objectStatus "LED_POSTCODE_7_R" )
			)
			( signal "@baseboard_fab2_lib.baseboard_fab2(sch_1):p12v_stby"
				( alias ( signalRef "@baseboard_fab2_lib.baseboard_fab2(sch_1):page155_p12v_stby") )
				( alias ( signalRef "@baseboard_fab2_lib.baseboard_fab2(sch_1):page169_p12v_stby") )
				( alias ( signalRef "@baseboard_fab2_lib.baseboard_fab2(sch_1):page186_p12v_stby") )
				( alias ( signalRef "@baseboard_fab2_lib.baseboard_fab2(sch_1):page187_p12v_stby") )
				( alias ( signalRef "@baseboard_fab2_lib.baseboard_fab2(sch_1):page188_p12v_stby") )
				( alias ( signalRef "@baseboard_fab2_lib.baseboard_fab2(sch_1):page193_p12v_stby") )
				( alias ( signalRef "@baseboard_fab2_lib.baseboard_fab2(sch_1):page194_p12v_stby") )
				( alias ( signalRef "@baseboard_fab2_lib.baseboard_fab2(sch_1):page195_p12v_stby") )
				( alias ( signalRef "@baseboard_fab2_lib.baseboard_fab2(sch_1):page196_p12v_stby") )
				( alias ( signalRef "@baseboard_fab2_lib.baseboard_fab2(sch_1):page197_p12v_stby") )
				( alias ( signalRef "@baseboard_fab2_lib.baseboard_fab2(sch_1):page198_p12v_stby") )
				( alias ( signalRef "@baseboard_fab2_lib.baseboard_fab2(sch_1):page199_p12v_stby") )
				( alias ( signalRef "@baseboard_fab2_lib.baseboard_fab2(sch_1):page200_p12v_stby") )
				( alias ( signalRef "@baseboard_fab2_lib.baseboard_fab2(sch_1):page204_p12v_stby") )
				( alias ( signalRef "@baseboard_fab2_lib.baseboard_fab2(sch_1):page209_p12v_stby") )
				( alias ( signalRef "@baseboard_fab2_lib.baseboard_fab2(sch_1):page212_p12v_stby") )
				( alias ( signalRef "@baseboard_fab2_lib.baseboard_fab2(sch_1):page217_p12v_stby") )
				( alias ( signalRef "@baseboard_fab2_lib.baseboard_fab2(sch_1):page220_p12v_stby") )
				( alias ( signalRef "@baseboard_fab2_lib.baseboard_fab2(sch_1):page225_p12v_stby") )
				( alias ( signalRef "@baseboard_fab2_lib.baseboard_fab2(sch_1):page228_p12v_stby") )
				( alias ( signalRef "@baseboard_fab2_lib.baseboard_fab2(sch_1):page231_p12v_stby") )
				( alias ( signalRef "@baseboard_fab2_lib.baseboard_fab2(sch_1):page232_p12v_stby") )
				( alias ( signalRef "@baseboard_fab2_lib.baseboard_fab2(sch_1):page233_p12v_stby") )
				( alias ( signalRef "@baseboard_fab2_lib.baseboard_fab2(sch_1):page234_p12v_stby") )
				( alias ( signalRef "@baseboard_fab2_lib.baseboard_fab2(sch_1):page240_p12v_stby") )
				( alias ( signalRef "@baseboard_fab2_lib.baseboard_fab2(sch_1):page241_p12v_stby") )
				( attribute "CDS_PHYS_NET_NAME" "P12V_STBY"
					( Origin gPackager )
				)
				( attribute "VOLTAGE" "12.0V"
					( Units "uVoltage" "V" 1.000000)
					( Status sAliasFlattened )
					( Origin gFrontEnd )
				)
				( objectStatus "P12V_STBY" )
			)
			( signal "@baseboard_fab2_lib.baseboard_fab2(sch_1):page155_p12v_stby"
				( attribute "VOLTAGE" "12.0V"
					( Units "uVoltage" "V" 1.000000)
					( Origin gFrontEnd )
				)
				( objectFlag fObjectAlias )
				( objectStatus "page155_p12v_stby" )
			)
			( signal "@baseboard_fab2_lib.baseboard_fab2(sch_1):page169_p12v_stby"
				( attribute "VOLTAGE" "12.0V"
					( Units "uVoltage" "V" 1.000000)
					( Origin gFrontEnd )
				)
				( objectFlag fObjectAlias )
				( objectStatus "page169_p12v_stby" )
			)
			( signal "@baseboard_fab2_lib.baseboard_fab2(sch_1):page186_p12v_stby"
				( attribute "VOLTAGE" "12.0V"
					( Units "uVoltage" "V" 1.000000)
					( Origin gFrontEnd )
				)
				( objectFlag fObjectAlias )
				( objectStatus "page186_p12v_stby" )
			)
			( signal "@baseboard_fab2_lib.baseboard_fab2(sch_1):page187_p12v_stby"
				( attribute "VOLTAGE" "12.0V"
					( Units "uVoltage" "V" 1.000000)
					( Origin gFrontEnd )
				)
				( objectFlag fObjectAlias )
				( objectStatus "page187_p12v_stby" )
			)
			( signal "@baseboard_fab2_lib.baseboard_fab2(sch_1):page188_p12v_stby"
				( attribute "VOLTAGE" "12.0V"
					( Units "uVoltage" "V" 1.000000)
					( Origin gFrontEnd )
				)
				( objectFlag fObjectAlias )
				( objectStatus "page188_p12v_stby" )
			)
			( signal "@baseboard_fab2_lib.baseboard_fab2(sch_1):page193_p12v_stby"
				( attribute "VOLTAGE" "12.0V"
					( Units "uVoltage" "V" 1.000000)
					( Origin gFrontEnd )
				)
				( objectFlag fObjectAlias )
				( objectStatus "page193_p12v_stby" )
			)
			( signal "@baseboard_fab2_lib.baseboard_fab2(sch_1):page194_p12v_stby"
				( attribute "VOLTAGE" "12.0V"
					( Units "uVoltage" "V" 1.000000)
					( Origin gFrontEnd )
				)
				( objectFlag fObjectAlias )
				( objectStatus "page194_p12v_stby" )
			)
			( signal "@baseboard_fab2_lib.baseboard_fab2(sch_1):page195_p12v_stby"
				( attribute "VOLTAGE" "12.0V"
					( Units "uVoltage" "V" 1.000000)
					( Origin gFrontEnd )
				)
				( objectFlag fObjectAlias )
				( objectStatus "page195_p12v_stby" )
			)
			( signal "@baseboard_fab2_lib.baseboard_fab2(sch_1):page196_p12v_stby"
				( attribute "VOLTAGE" "12.0V"
					( Units "uVoltage" "V" 1.000000)
					( Origin gFrontEnd )
				)
				( objectFlag fObjectAlias )
				( objectStatus "page196_p12v_stby" )
			)
			( signal "@baseboard_fab2_lib.baseboard_fab2(sch_1):page197_p12v_stby"
				( attribute "VOLTAGE" "12.0V"
					( Units "uVoltage" "V" 1.000000)
					( Origin gFrontEnd )
				)
				( objectFlag fObjectAlias )
				( objectStatus "page197_p12v_stby" )
			)
			( signal "@baseboard_fab2_lib.baseboard_fab2(sch_1):page198_p12v_stby"
				( attribute "VOLTAGE" "12.0V"
					( Units "uVoltage" "V" 1.000000)
					( Origin gFrontEnd )
				)
				( objectFlag fObjectAlias )
				( objectStatus "page198_p12v_stby" )
			)
			( signal "@baseboard_fab2_lib.baseboard_fab2(sch_1):page199_p12v_stby"
				( attribute "VOLTAGE" "12.0V"
					( Units "uVoltage" "V" 1.000000)
					( Origin gFrontEnd )
				)
				( objectFlag fObjectAlias )
				( objectStatus "page199_p12v_stby" )
			)
			( signal "@baseboard_fab2_lib.baseboard_fab2(sch_1):page200_p12v_stby"
				( attribute "VOLTAGE" "12.0V"
					( Units "uVoltage" "V" 1.000000)
					( Origin gFrontEnd )
				)
				( objectFlag fObjectAlias )
				( objectStatus "page200_p12v_stby" )
			)
			( signal "@baseboard_fab2_lib.baseboard_fab2(sch_1):page204_p12v_stby"
				( attribute "VOLTAGE" "12.0V"
					( Units "uVoltage" "V" 1.000000)
					( Origin gFrontEnd )
				)
				( objectFlag fObjectAlias )
				( objectStatus "page204_p12v_stby" )
			)
			( signal "@baseboard_fab2_lib.baseboard_fab2(sch_1):page209_p12v_stby"
				( attribute "VOLTAGE" "12.0V"
					( Units "uVoltage" "V" 1.000000)
					( Origin gFrontEnd )
				)
				( objectFlag fObjectAlias )
				( objectStatus "page209_p12v_stby" )
			)
			( signal "@baseboard_fab2_lib.baseboard_fab2(sch_1):page212_p12v_stby"
				( attribute "VOLTAGE" "12.0V"
					( Units "uVoltage" "V" 1.000000)
					( Origin gFrontEnd )
				)
				( objectFlag fObjectAlias )
				( objectStatus "page212_p12v_stby" )
			)
			( signal "@baseboard_fab2_lib.baseboard_fab2(sch_1):page217_p12v_stby"
				( attribute "VOLTAGE" "12.0V"
					( Units "uVoltage" "V" 1.000000)
					( Origin gFrontEnd )
				)
				( objectFlag fObjectAlias )
				( objectStatus "page217_p12v_stby" )
			)
			( signal "@baseboard_fab2_lib.baseboard_fab2(sch_1):page220_p12v_stby"
				( attribute "VOLTAGE" "12.0V"
					( Units "uVoltage" "V" 1.000000)
					( Origin gFrontEnd )
				)
				( objectFlag fObjectAlias )
				( objectStatus "page220_p12v_stby" )
			)
			( signal "@baseboard_fab2_lib.baseboard_fab2(sch_1):page225_p12v_stby"
				( attribute "VOLTAGE" "12.0V"
					( Units "uVoltage" "V" 1.000000)
					( Origin gFrontEnd )
				)
				( objectFlag fObjectAlias )
				( objectStatus "page225_p12v_stby" )
			)
			( signal "@baseboard_fab2_lib.baseboard_fab2(sch_1):page228_p12v_stby"
				( attribute "VOLTAGE" "12.0V"
					( Units "uVoltage" "V" 1.000000)
					( Origin gFrontEnd )
				)
				( objectFlag fObjectAlias )
				( objectStatus "page228_p12v_stby" )
			)
			( signal "@baseboard_fab2_lib.baseboard_fab2(sch_1):page231_p12v_stby"
				( attribute "VOLTAGE" "12.0V"
					( Units "uVoltage" "V" 1.000000)
					( Origin gFrontEnd )
				)
				( objectFlag fObjectAlias )
				( objectStatus "page231_p12v_stby" )
			)
			( signal "@baseboard_fab2_lib.baseboard_fab2(sch_1):page232_p12v_stby"
				( attribute "VOLTAGE" "12.0V"
					( Units "uVoltage" "V" 1.000000)
					( Origin gFrontEnd )
				)
				( objectFlag fObjectAlias )
				( objectStatus "page232_p12v_stby" )
			)
			( signal "@baseboard_fab2_lib.baseboard_fab2(sch_1):page233_p12v_stby"
				( attribute "VOLTAGE" "12.0V"
					( Units "uVoltage" "V" 1.000000)
					( Origin gFrontEnd )
				)
				( objectFlag fObjectAlias )
				( objectStatus "page233_p12v_stby" )
			)
			( signal "@baseboard_fab2_lib.baseboard_fab2(sch_1):page234_p12v_stby"
				( attribute "VOLTAGE" "12.0V"
					( Units "uVoltage" "V" 1.000000)
					( Origin gFrontEnd )
				)
				( objectFlag fObjectAlias )
				( objectStatus "page234_p12v_stby" )
			)
			( signal "@baseboard_fab2_lib.baseboard_fab2(sch_1):page240_p12v_stby"
				( attribute "VOLTAGE" "12.0V"
					( Units "uVoltage" "V" 1.000000)
					( Origin gFrontEnd )
				)
				( objectFlag fObjectAlias )
				( objectStatus "page240_p12v_stby" )
			)
			( signal "@baseboard_fab2_lib.baseboard_fab2(sch_1):page241_p12v_stby"
				( attribute "VOLTAGE" "12.0V"
					( Units "uVoltage" "V" 1.000000)
					( Origin gFrontEnd )
				)
				( objectFlag fObjectAlias )
				( objectStatus "page241_p12v_stby" )
			)
			( signal "@baseboard_fab2_lib.baseboard_fab2(sch_1):p5v_stby"
				( alias ( signalRef "@baseboard_fab2_lib.baseboard_fab2(sch_1):page155_p5v_stby") )
				( alias ( signalRef "@baseboard_fab2_lib.baseboard_fab2(sch_1):page161_p5v_stby") )
				( alias ( signalRef "@baseboard_fab2_lib.baseboard_fab2(sch_1):page169_p5v_stby") )
				( alias ( signalRef "@baseboard_fab2_lib.baseboard_fab2(sch_1):page175_p5v_stby") )
				( alias ( signalRef "@baseboard_fab2_lib.baseboard_fab2(sch_1):page177_p5v_stby") )
				( alias ( signalRef "@baseboard_fab2_lib.baseboard_fab2(sch_1):page186_p5v_stby") )
				( alias ( signalRef "@baseboard_fab2_lib.baseboard_fab2(sch_1):page193_p5v_stby") )
				( alias ( signalRef "@baseboard_fab2_lib.baseboard_fab2(sch_1):page194_p5v_stby") )
				( alias ( signalRef "@baseboard_fab2_lib.baseboard_fab2(sch_1):page198_p5v_stby") )
				( alias ( signalRef "@baseboard_fab2_lib.baseboard_fab2(sch_1):page202_p5v_stby") )
				( alias ( signalRef "@baseboard_fab2_lib.baseboard_fab2(sch_1):page203_p5v_stby") )
				( alias ( signalRef "@baseboard_fab2_lib.baseboard_fab2(sch_1):page204_p5v_stby") )
				( alias ( signalRef "@baseboard_fab2_lib.baseboard_fab2(sch_1):page205_p5v_stby") )
				( alias ( signalRef "@baseboard_fab2_lib.baseboard_fab2(sch_1):page207_p5v_stby") )
				( alias ( signalRef "@baseboard_fab2_lib.baseboard_fab2(sch_1):page208_p5v_stby") )
				( alias ( signalRef "@baseboard_fab2_lib.baseboard_fab2(sch_1):page209_p5v_stby") )
				( alias ( signalRef "@baseboard_fab2_lib.baseboard_fab2(sch_1):page210_p5v_stby") )
				( alias ( signalRef "@baseboard_fab2_lib.baseboard_fab2(sch_1):page212_p5v_stby") )
				( alias ( signalRef "@baseboard_fab2_lib.baseboard_fab2(sch_1):page214_p5v_stby") )
				( alias ( signalRef "@baseboard_fab2_lib.baseboard_fab2(sch_1):page216_p5v_stby") )
				( alias ( signalRef "@baseboard_fab2_lib.baseboard_fab2(sch_1):page219_p5v_stby") )
				( alias ( signalRef "@baseboard_fab2_lib.baseboard_fab2(sch_1):page224_p5v_stby") )
				( alias ( signalRef "@baseboard_fab2_lib.baseboard_fab2(sch_1):page227_p5v_stby") )
				( alias ( signalRef "@baseboard_fab2_lib.baseboard_fab2(sch_1):page236_p5v_stby") )
				( alias ( signalRef "@baseboard_fab2_lib.baseboard_fab2(sch_1):page240_p5v_stby") )
				( alias ( signalRef "@baseboard_fab2_lib.baseboard_fab2(sch_1):page241_p5v_stby") )
				( alias ( signalRef "@baseboard_fab2_lib.baseboard_fab2(sch_1):page168_p5v_stby") )
				( attribute "CDS_PHYS_NET_NAME" "P5V_STBY"
					( Origin gPackager )
				)
				( attribute "VOLTAGE" "5.0V"
					( Units "uVoltage" "V" 1.000000)
					( Status sAliasFlattened )
					( Status sAliasConflict )
					( Origin gFrontEnd )
				)
				( objectStatus "P5V_STBY" )
			)
			( signal "@baseboard_fab2_lib.baseboard_fab2(sch_1):page155_p5v_stby"
				( attribute "VOLTAGE" "5.0V"
					( Units "uVoltage" "V" 1.000000)
					( Origin gFrontEnd )
				)
				( objectFlag fObjectAlias )
				( objectStatus "page155_p5v_stby" )
			)
			( signal "@baseboard_fab2_lib.baseboard_fab2(sch_1):page161_p5v_stby"
				( attribute "VOLTAGE" "5.0V"
					( Units "uVoltage" "V" 1.000000)
					( Origin gFrontEnd )
				)
				( objectFlag fObjectAlias )
				( objectStatus "page161_p5v_stby" )
			)
			( signal "@baseboard_fab2_lib.baseboard_fab2(sch_1):page169_p5v_stby"
				( attribute "VOLTAGE" "5.0V"
					( Units "uVoltage" "V" 1.000000)
					( Origin gFrontEnd )
				)
				( objectFlag fObjectAlias )
				( objectStatus "page169_p5v_stby" )
			)
			( signal "@baseboard_fab2_lib.baseboard_fab2(sch_1):page175_p5v_stby"
				( attribute "VOLTAGE" "5.0V"
					( Units "uVoltage" "V" 1.000000)
					( Origin gFrontEnd )
				)
				( objectFlag fObjectAlias )
				( objectStatus "page175_p5v_stby" )
			)
			( signal "@baseboard_fab2_lib.baseboard_fab2(sch_1):page177_p5v_stby"
				( attribute "VOLTAGE" "5.0V"
					( Units "uVoltage" "V" 1.000000)
					( Origin gFrontEnd )
				)
				( objectFlag fObjectAlias )
				( objectStatus "page177_p5v_stby" )
			)
			( signal "@baseboard_fab2_lib.baseboard_fab2(sch_1):page186_p5v_stby"
				( attribute "VOLTAGE" "5.0V"
					( Units "uVoltage" "V" 1.000000)
					( Origin gFrontEnd )
				)
				( objectFlag fObjectAlias )
				( objectStatus "page186_p5v_stby" )
			)
			( signal "@baseboard_fab2_lib.baseboard_fab2(sch_1):page193_p5v_stby"
				( attribute "VOLTAGE" "+5.0V"
					( Units "uVoltage" "V" 1.000000)
					( Origin gFrontEnd )
				)
				( objectFlag fObjectAlias )
				( objectStatus "page193_p5v_stby" )
			)
			( signal "@baseboard_fab2_lib.baseboard_fab2(sch_1):page194_p5v_stby"
				( attribute "VOLTAGE" "+5.0V"
					( Units "uVoltage" "V" 1.000000)
					( Origin gFrontEnd )
				)
				( objectFlag fObjectAlias )
				( objectStatus "page194_p5v_stby" )
			)
			( signal "@baseboard_fab2_lib.baseboard_fab2(sch_1):page198_p5v_stby"
				( attribute "VOLTAGE" "5.0V"
					( Units "uVoltage" "V" 1.000000)
					( Origin gFrontEnd )
				)
				( objectFlag fObjectAlias )
				( objectStatus "page198_p5v_stby" )
			)
			( signal "@baseboard_fab2_lib.baseboard_fab2(sch_1):page202_p5v_stby"
				( attribute "VOLTAGE" "5.0V"
					( Units "uVoltage" "V" 1.000000)
					( Origin gFrontEnd )
				)
				( objectFlag fObjectAlias )
				( objectStatus "page202_p5v_stby" )
			)
			( signal "@baseboard_fab2_lib.baseboard_fab2(sch_1):page203_p5v_stby"
				( attribute "VOLTAGE" "5.0V"
					( Units "uVoltage" "V" 1.000000)
					( Origin gFrontEnd )
				)
				( objectFlag fObjectAlias )
				( objectStatus "page203_p5v_stby" )
			)
			( signal "@baseboard_fab2_lib.baseboard_fab2(sch_1):page204_p5v_stby"
				( attribute "VOLTAGE" "5.0V"
					( Units "uVoltage" "V" 1.000000)
					( Origin gFrontEnd )
				)
				( objectFlag fObjectAlias )
				( objectStatus "page204_p5v_stby" )
			)
			( signal "@baseboard_fab2_lib.baseboard_fab2(sch_1):page205_p5v_stby"
				( attribute "VOLTAGE" "5.0V"
					( Units "uVoltage" "V" 1.000000)
					( Origin gFrontEnd )
				)
				( objectFlag fObjectAlias )
				( objectStatus "page205_p5v_stby" )
			)
			( signal "@baseboard_fab2_lib.baseboard_fab2(sch_1):page207_p5v_stby"
				( attribute "VOLTAGE" "5.0V"
					( Units "uVoltage" "V" 1.000000)
					( Origin gFrontEnd )
				)
				( objectFlag fObjectAlias )
				( objectStatus "page207_p5v_stby" )
			)
			( signal "@baseboard_fab2_lib.baseboard_fab2(sch_1):page208_p5v_stby"
				( attribute "VOLTAGE" "5.0V"
					( Units "uVoltage" "V" 1.000000)
					( Origin gFrontEnd )
				)
				( objectFlag fObjectAlias )
				( objectStatus "page208_p5v_stby" )
			)
			( signal "@baseboard_fab2_lib.baseboard_fab2(sch_1):page209_p5v_stby"
				( attribute "VOLTAGE" "5.0V"
					( Units "uVoltage" "V" 1.000000)
					( Origin gFrontEnd )
				)
				( objectFlag fObjectAlias )
				( objectStatus "page209_p5v_stby" )
			)
			( signal "@baseboard_fab2_lib.baseboard_fab2(sch_1):page210_p5v_stby"
				( attribute "VOLTAGE" "5.0V"
					( Units "uVoltage" "V" 1.000000)
					( Origin gFrontEnd )
				)
				( objectFlag fObjectAlias )
				( objectStatus "page210_p5v_stby" )
			)
			( signal "@baseboard_fab2_lib.baseboard_fab2(sch_1):page212_p5v_stby"
				( attribute "VOLTAGE" "5.0V"
					( Units "uVoltage" "V" 1.000000)
					( Origin gFrontEnd )
				)
				( objectFlag fObjectAlias )
				( objectStatus "page212_p5v_stby" )
			)
			( signal "@baseboard_fab2_lib.baseboard_fab2(sch_1):page214_p5v_stby"
				( attribute "VOLTAGE" "5.0V"
					( Units "uVoltage" "V" 1.000000)
					( Origin gFrontEnd )
				)
				( objectFlag fObjectAlias )
				( objectStatus "page214_p5v_stby" )
			)
			( signal "@baseboard_fab2_lib.baseboard_fab2(sch_1):page216_p5v_stby"
				( attribute "VOLTAGE" "5.0V"
					( Units "uVoltage" "V" 1.000000)
					( Origin gFrontEnd )
				)
				( objectFlag fObjectAlias )
				( objectStatus "page216_p5v_stby" )
			)
			( signal "@baseboard_fab2_lib.baseboard_fab2(sch_1):page219_p5v_stby"
				( attribute "VOLTAGE" "5.0V"
					( Units "uVoltage" "V" 1.000000)
					( Origin gFrontEnd )
				)
				( objectFlag fObjectAlias )
				( objectStatus "page219_p5v_stby" )
			)
			( signal "@baseboard_fab2_lib.baseboard_fab2(sch_1):page224_p5v_stby"
				( attribute "VOLTAGE" "5.0V"
					( Units "uVoltage" "V" 1.000000)
					( Origin gFrontEnd )
				)
				( objectFlag fObjectAlias )
				( objectStatus "page224_p5v_stby" )
			)
			( signal "@baseboard_fab2_lib.baseboard_fab2(sch_1):page227_p5v_stby"
				( attribute "VOLTAGE" "5.0V"
					( Units "uVoltage" "V" 1.000000)
					( Origin gFrontEnd )
				)
				( objectFlag fObjectAlias )
				( objectStatus "page227_p5v_stby" )
			)
			( signal "@baseboard_fab2_lib.baseboard_fab2(sch_1):page236_p5v_stby"
				( attribute "VOLTAGE" "5.0V"
					( Units "uVoltage" "V" 1.000000)
					( Origin gFrontEnd )
				)
				( objectFlag fObjectAlias )
				( objectStatus "page236_p5v_stby" )
			)
			( signal "@baseboard_fab2_lib.baseboard_fab2(sch_1):page240_p5v_stby"
				( attribute "VOLTAGE" "+5.0V"
					( Units "uVoltage" "V" 1.000000)
					( Origin gFrontEnd )
				)
				( objectFlag fObjectAlias )
				( objectStatus "page240_p5v_stby" )
			)
			( signal "@baseboard_fab2_lib.baseboard_fab2(sch_1):page241_p5v_stby"
				( attribute "VOLTAGE" "+5"
					( Units "uVoltage" "V" 1.000000)
					( Origin gFrontEnd )
				)
				( objectFlag fObjectAlias )
				( objectStatus "page241_p5v_stby" )
			)
			( signal "@baseboard_fab2_lib.baseboard_fab2(sch_1):page168_p5v_stby"
				( attribute "VOLTAGE" "5.0V"
					( Units "uVoltage" "V" 1.000000)
					( Origin gFrontEnd )
				)
				( objectFlag fObjectAlias )
				( objectStatus "page168_p5v_stby" )
			)
			( signal "@baseboard_fab2_lib.baseboard_fab2(sch_1):p5v_stby_dbg"
				( alias ( signalRef "@baseboard_fab2_lib.baseboard_fab2(sch_1):page155_p5v_stby_dbg") )
				( attribute "VOLTAGE" "5"
					( Units "uVoltage" "V" 1.000000)
					( Status sAliasFlattened )
					( Origin gFrontEnd )
				)
				( attribute "CDS_PHYS_NET_NAME" "P5V_STBY_DBG"
					( Origin gPackager )
				)
				( objectStatus "P5V_STBY_DBG" )
			)
			( signal "@baseboard_fab2_lib.baseboard_fab2(sch_1):page155_p5v_stby_dbg"
				( attribute "VOLTAGE" "5"
					( Units "uVoltage" "V" 1.000000)
					( Origin gFrontEnd )
				)
				( objectFlag fObjectAlias )
				( objectStatus "page155_p5v_stby_dbg" )
			)
			( signal "@baseboard_fab2_lib.baseboard_fab2(sch_1):p5v_stby_dgb_fs"
				( alias ( signalRef "@baseboard_fab2_lib.baseboard_fab2(sch_1):page155_p5v_stby_dgb_fs") )
				( attribute "VOLTAGE" "5"
					( Units "uVoltage" "V" 1.000000)
					( Status sAliasFlattened )
					( Origin gFrontEnd )
				)
				( attribute "CDS_PHYS_NET_NAME" "P5V_STBY_DGB_FS"
					( Origin gPackager )
				)
				( objectStatus "P5V_STBY_DGB_FS" )
			)
			( signal "@baseboard_fab2_lib.baseboard_fab2(sch_1):page155_p5v_stby_dgb_fs"
				( attribute "VOLTAGE" "5"
					( Units "uVoltage" "V" 1.000000)
					( Origin gFrontEnd )
				)
				( objectFlag fObjectAlias )
				( objectStatus "page155_p5v_stby_dgb_fs" )
			)
			( signal "@baseboard_fab2_lib.baseboard_fab2(sch_1):spa_5v_sin_sw"
				( attribute "CDS_PHYS_NET_NAME" "SPA_5V_SIN_SW"
					( Origin gPackager )
				)
				( objectStatus "SPA_5V_SIN_SW" )
			)
			( signal "@baseboard_fab2_lib.baseboard_fab2(sch_1):spa_mid_dbg_rx"
				( attribute "CDS_PHYS_NET_NAME" "SPA_MID_DBG_RX"
					( Origin gPackager )
				)
				( objectStatus "SPA_MID_DBG_RX" )
			)
			( signal "@baseboard_fab2_lib.baseboard_fab2(sch_1):spa_mid_dbg_tx"
				( attribute "CDS_PHYS_NET_NAME" "SPA_MID_DBG_TX"
					( Origin gPackager )
				)
				( objectStatus "SPA_MID_DBG_TX" )
			)
			( signal "@baseboard_fab2_lib.baseboard_fab2(sch_1):spa_sin_sw_r"
				( attribute "CDS_PHYS_NET_NAME" "SPA_SIN_SW_R"
					( Origin gPackager )
				)
				( objectStatus "SPA_SIN_SW_R" )
			)
			( signal "@baseboard_fab2_lib.baseboard_fab2(sch_1):fm_pch_pwrbtn_r_n"
				( attribute "CDS_PHYS_NET_NAME" "FM_PCH_PWRBTN_R_N"
					( Origin gPackager )
				)
				( objectStatus "FM_PCH_PWRBTN_R_N" )
			)
			( signal "@baseboard_fab2_lib.baseboard_fab2(sch_1):rst_bmc_sysrst_btn_out_b_r_n"
				( attribute "CDS_PHYS_NET_NAME" "RST_BMC_SYSRST_BTN_OUT_B_R_N"
					( Origin gPackager )
				)
				( objectStatus "RST_BMC_SYSRST_BTN_OUT_B_R_N" )
			)
			( signal "@baseboard_fab2_lib.baseboard_fab2(sch_1):fp_nmi_btn"
				( attribute "CDS_PHYS_NET_NAME" "FP_NMI_BTN"
					( Origin gPackager )
				)
				( objectStatus "FP_NMI_BTN" )
			)
			( signal "@baseboard_fab2_lib.baseboard_fab2(sch_1):fp_nmi_btn_out_n"
				( attribute "CDS_PHYS_NET_NAME" "FP_NMI_BTN_OUT_N"
					( Origin gPackager )
				)
				( objectStatus "FP_NMI_BTN_OUT_N" )
			)
			( signal "@baseboard_fab2_lib.baseboard_fab2(sch_1):fp_nmi_btn_out_r_n"
				( attribute "CDS_PHYS_NET_NAME" "FP_NMI_BTN_OUT_R_N"
					( Origin gPackager )
				)
				( objectStatus "FP_NMI_BTN_OUT_R_N" )
			)
			( signal "@baseboard_fab2_lib.baseboard_fab2(sch_1):fp_nmi_btn_r_n"
				( attribute "CDS_PHYS_NET_NAME" "FP_NMI_BTN_R_N"
					( Origin gPackager )
				)
				( objectStatus "FP_NMI_BTN_R_N" )
			)
			( signal "@baseboard_fab2_lib.baseboard_fab2(sch_1):h_cpu0_fast_wake"
				( attribute "CDS_PHYS_NET_NAME" "H_CPU0_FAST_WAKE"
					( Origin gPackager )
				)
				( objectStatus "H_CPU0_FAST_WAKE" )
			)
			( signal "@baseboard_fab2_lib.baseboard_fab2(sch_1):h_cpu0_fast_wake_b_n"
				( attribute "CDS_PHYS_NET_NAME" "H_CPU0_FAST_WAKE_B_N"
					( Origin gPackager )
				)
				( objectStatus "H_CPU0_FAST_WAKE_B_N" )
			)
			( signal "@baseboard_fab2_lib.baseboard_fab2(sch_1):rst_bmc_srst_r2_n"
				( attribute "CDS_PHYS_NET_NAME" "RST_BMC_SRST_R2_N"
					( Origin gPackager )
				)
				( objectStatus "RST_BMC_SRST_R2_N" )
			)
			( signal "@baseboard_fab2_lib.baseboard_fab2(sch_1):fm_uartsw_lsb_r_n"
				( attribute "CDS_PHYS_NET_NAME" "FM_UARTSW_LSB_R_N"
					( Origin gPackager )
				)
				( objectStatus "FM_UARTSW_LSB_R_N" )
			)
			( signal "@baseboard_fab2_lib.baseboard_fab2(sch_1):fm_uartsw_msb_r_n"
				( attribute "CDS_PHYS_NET_NAME" "FM_UARTSW_MSB_R_N"
					( Origin gPackager )
				)
				( objectStatus "FM_UARTSW_MSB_R_N" )
			)
			( signal "@baseboard_fab2_lib.baseboard_fab2(sch_1):sp2_bmc_cm_uart_rx_r"
				( attribute "CDS_PHYS_NET_NAME" "SP2_BMC_CM_UART_RX_R"
					( Origin gPackager )
				)
				( objectStatus "SP2_BMC_CM_UART_RX_R" )
			)
			( signal "@baseboard_fab2_lib.baseboard_fab2(sch_1):sp2_bmc_cm_uart_rx_r1"
				( attribute "CDS_PHYS_NET_NAME" "SP2_BMC_CM_UART_RX_R1"
					( Origin gPackager )
				)
				( objectStatus "SP2_BMC_CM_UART_RX_R1" )
			)
			( signal "@baseboard_fab2_lib.baseboard_fab2(sch_1):sp2_bmc_cm_uart_tx_r"
				( attribute "CDS_PHYS_NET_NAME" "SP2_BMC_CM_UART_TX_R"
					( Origin gPackager )
				)
				( objectStatus "SP2_BMC_CM_UART_TX_R" )
			)
			( signal "@baseboard_fab2_lib.baseboard_fab2(sch_1):sp2_bmc_cm_uart_tx_r1"
				( attribute "CDS_PHYS_NET_NAME" "SP2_BMC_CM_UART_TX_R1"
					( Origin gPackager )
				)
				( objectStatus "SP2_BMC_CM_UART_TX_R1" )
			)
			( signal "@baseboard_fab2_lib.baseboard_fab2(sch_1):uart_mux_in_r"
				( attribute "CDS_PHYS_NET_NAME" "UART_MUX_IN_R"
					( Origin gPackager )
				)
				( objectStatus "UART_MUX_IN_R" )
			)
			( signal "@baseboard_fab2_lib.baseboard_fab2(sch_1):uart_mux_out_r"
				( attribute "CDS_PHYS_NET_NAME" "UART_MUX_OUT_R"
					( Origin gPackager )
				)
				( objectStatus "UART_MUX_OUT_R" )
			)
			( signal "@baseboard_fab2_lib.baseboard_fab2(sch_1):smb_ocp_lan_stby_lvc3_scl"
				( attribute "CDS_PHYS_NET_NAME" "SMB_OCP_LAN_STBY_LVC3_SCL"
					( Origin gPackager )
				)
				( objectStatus "SMB_OCP_LAN_STBY_LVC3_SCL" )
			)
			( signal "@baseboard_fab2_lib.baseboard_fab2(sch_1):smb_ocp_lan_stby_lvc3_sda"
				( attribute "CDS_PHYS_NET_NAME" "SMB_OCP_LAN_STBY_LVC3_SDA"
					( Origin gPackager )
				)
				( objectStatus "SMB_OCP_LAN_STBY_LVC3_SDA" )
			)
			( signal "@baseboard_fab2_lib.baseboard_fab2(sch_1):fan_pwm_out_sys0_buf"
				( attribute "CDS_PHYS_NET_NAME" "FAN_PWM_OUT_SYS0_BUF"
					( Origin gPackager )
				)
				( objectStatus "FAN_PWM_OUT_SYS0_BUF" )
			)
			( signal "@baseboard_fab2_lib.baseboard_fab2(sch_1):fan_pwm_out_sys0_r"
				( attribute "CDS_PHYS_NET_NAME" "FAN_PWM_OUT_SYS0_R"
					( Origin gPackager )
				)
				( objectStatus "FAN_PWM_OUT_SYS0_R" )
			)
			( signal "@baseboard_fab2_lib.baseboard_fab2(sch_1):fan_pwm_out_sys1_buf"
				( attribute "CDS_PHYS_NET_NAME" "FAN_PWM_OUT_SYS1_BUF"
					( Origin gPackager )
				)
				( objectStatus "FAN_PWM_OUT_SYS1_BUF" )
			)
			( signal "@baseboard_fab2_lib.baseboard_fab2(sch_1):fan_pwm_out_sys1_r"
				( attribute "CDS_PHYS_NET_NAME" "FAN_PWM_OUT_SYS1_R"
					( Origin gPackager )
				)
				( objectStatus "FAN_PWM_OUT_SYS1_R" )
			)
			( signal "@baseboard_fab2_lib.baseboard_fab2(sch_1):fan_tach0_cpu0_d1"
				( attribute "CDS_PHYS_NET_NAME" "FAN_TACH0_CPU0_D1"
					( Origin gPackager )
				)
				( objectStatus "FAN_TACH0_CPU0_D1" )
			)
			( signal "@baseboard_fab2_lib.baseboard_fab2(sch_1):fan_tach0_cpu0_d2"
				( attribute "CDS_PHYS_NET_NAME" "FAN_TACH0_CPU0_D2"
					( Origin gPackager )
				)
				( objectStatus "FAN_TACH0_CPU0_D2" )
			)
			( signal "@baseboard_fab2_lib.baseboard_fab2(sch_1):fan_tach1_cpu1_d1"
				( attribute "CDS_PHYS_NET_NAME" "FAN_TACH1_CPU1_D1"
					( Origin gPackager )
				)
				( objectStatus "FAN_TACH1_CPU1_D1" )
			)
			( signal "@baseboard_fab2_lib.baseboard_fab2(sch_1):fan_tach1_cpu1_d2"
				( attribute "CDS_PHYS_NET_NAME" "FAN_TACH1_CPU1_D2"
					( Origin gPackager )
				)
				( objectStatus "FAN_TACH1_CPU1_D2" )
			)
			( signal "@baseboard_fab2_lib.baseboard_fab2(sch_1):fan_tach2_cpu1_d1"
				( attribute "CDS_PHYS_NET_NAME" "FAN_TACH2_CPU1_D1"
					( Origin gPackager )
				)
				( objectStatus "FAN_TACH2_CPU1_D1" )
			)
			( signal "@baseboard_fab2_lib.baseboard_fab2(sch_1):fan_tach2_cpu1_d2"
				( attribute "CDS_PHYS_NET_NAME" "FAN_TACH2_CPU1_D2"
					( Origin gPackager )
				)
				( objectStatus "FAN_TACH2_CPU1_D2" )
			)
			( signal "@baseboard_fab2_lib.baseboard_fab2(sch_1):fan_tach3_cpu1_d1"
				( attribute "CDS_PHYS_NET_NAME" "FAN_TACH3_CPU1_D1"
					( Origin gPackager )
				)
				( objectStatus "FAN_TACH3_CPU1_D1" )
			)
			( signal "@baseboard_fab2_lib.baseboard_fab2(sch_1):fan_tach3_cpu1_d2"
				( attribute "CDS_PHYS_NET_NAME" "FAN_TACH3_CPU1_D2"
					( Origin gPackager )
				)
				( objectStatus "FAN_TACH3_CPU1_D2" )
			)
			( signal "@baseboard_fab2_lib.baseboard_fab2(sch_1):fm_ctnr_ps_on"
				( attribute "CDS_PHYS_NET_NAME" "FM_CTNR_PS_ON"
					( Origin gPackager )
				)
				( objectStatus "FM_CTNR_PS_ON" )
			)
			( signal "@baseboard_fab2_lib.baseboard_fab2(sch_1):fm_disable_fan_n"
				( attribute "CDS_PHYS_NET_NAME" "FM_DISABLE_FAN_N"
					( Origin gPackager )
				)
				( objectStatus "FM_DISABLE_FAN_N" )
			)
			( signal "@baseboard_fab2_lib.baseboard_fab2(sch_1):fm_enable_fan_power"
				( attribute "CDS_PHYS_NET_NAME" "FM_ENABLE_FAN_POWER"
					( Origin gPackager )
				)
				( objectStatus "FM_ENABLE_FAN_POWER" )
			)
			( signal "@baseboard_fab2_lib.baseboard_fab2(sch_1):p12v_fan"
				( alias ( signalRef "@baseboard_fab2_lib.baseboard_fab2(sch_1):page161_p12v_fan") )
				( alias ( signalRef "@baseboard_fab2_lib.baseboard_fab2(sch_1):page198_p12v_fan") )
				( attribute "VOLTAGE" "12.0V"
					( Units "uVoltage" "V" 1.000000)
					( Status sAliasFlattened )
					( Origin gFrontEnd )
				)
				( attribute "CDS_PHYS_NET_NAME" "P12V_FAN"
					( Origin gPackager )
				)
				( objectStatus "P12V_FAN" )
			)
			( signal "@baseboard_fab2_lib.baseboard_fab2(sch_1):page161_p12v_fan"
				( attribute "VOLTAGE" "12.0V"
					( Units "uVoltage" "V" 1.000000)
					( Origin gFrontEnd )
				)
				( objectFlag fObjectAlias )
				( objectStatus "page161_p12v_fan" )
			)
			( signal "@baseboard_fab2_lib.baseboard_fab2(sch_1):page198_p12v_fan"
				( attribute "VOLTAGE" "12.0V"
					( Units "uVoltage" "V" 1.000000)
					( Origin gFrontEnd )
				)
				( objectFlag fObjectAlias )
				( objectStatus "page198_p12v_fan" )
			)
			( signal "@baseboard_fab2_lib.baseboard_fab2(sch_1):tp_fan_0"
				( attribute "CDS_PHYS_NET_NAME" "TP_FAN_0"
					( Origin gPackager )
				)
				( objectStatus "TP_FAN_0" )
			)
			( signal "@baseboard_fab2_lib.baseboard_fab2(sch_1):tp_fan_1"
				( attribute "CDS_PHYS_NET_NAME" "TP_FAN_1"
					( Origin gPackager )
				)
				( objectStatus "TP_FAN_1" )
			)
			( signal "@baseboard_fab2_lib.baseboard_fab2(sch_1):pu_spi_bmc_bt_hold_n"
				( attribute "CDS_PHYS_NET_NAME" "PU_SPI_BMC_BT_HOLD_N"
					( Origin gPackager )
				)
				( objectStatus "PU_SPI_BMC_BT_HOLD_N" )
			)
			( signal "@baseboard_fab2_lib.baseboard_fab2(sch_1):pu_spi_bmc_bt_wp_n"
				( attribute "CDS_PHYS_NET_NAME" "PU_SPI_BMC_BT_WP_N"
					( Origin gPackager )
				)
				( objectStatus "PU_SPI_BMC_BT_WP_N" )
			)
			( signal "@baseboard_fab2_lib.baseboard_fab2(sch_1):pu_spi_flash_reset_2_n"
				( attribute "CDS_PHYS_NET_NAME" "PU_SPI_FLASH_RESET_2_N"
					( Origin gPackager )
				)
				( objectStatus "PU_SPI_FLASH_RESET_2_N" )
			)
			( signal "@baseboard_fab2_lib.baseboard_fab2(sch_1):spi_bmc_bt_di_r"
				( attribute "CDS_PHYS_NET_NAME" "SPI_BMC_BT_DI_R"
					( Origin gPackager )
				)
				( objectStatus "SPI_BMC_BT_DI_R" )
			)
			( signal "@baseboard_fab2_lib.baseboard_fab2(sch_1):tp_spi_2_0"
				( attribute "CDS_PHYS_NET_NAME" "TP_SPI_2_0"
					( Origin gPackager )
				)
				( objectStatus "TP_SPI_2_0" )
			)
			( signal "@baseboard_fab2_lib.baseboard_fab2(sch_1):tp_spi_2_1"
				( attribute "CDS_PHYS_NET_NAME" "TP_SPI_2_1"
					( Origin gPackager )
				)
				( objectStatus "TP_SPI_2_1" )
			)
			( signal "@baseboard_fab2_lib.baseboard_fab2(sch_1):tp_spi_2_2"
				( attribute "CDS_PHYS_NET_NAME" "TP_SPI_2_2"
					( Origin gPackager )
				)
				( objectStatus "TP_SPI_2_2" )
			)
			( signal "@baseboard_fab2_lib.baseboard_fab2(sch_1):tp_spi_2_3"
				( attribute "CDS_PHYS_NET_NAME" "TP_SPI_2_3"
					( Origin gPackager )
				)
				( objectStatus "TP_SPI_2_3" )
			)
			( signal "@baseboard_fab2_lib.baseboard_fab2(sch_1):tp_spi_2_4"
				( attribute "CDS_PHYS_NET_NAME" "TP_SPI_2_4"
					( Origin gPackager )
				)
				( objectStatus "TP_SPI_2_4" )
			)
			( signal "@baseboard_fab2_lib.baseboard_fab2(sch_1):tp_spi_2_5"
				( attribute "CDS_PHYS_NET_NAME" "TP_SPI_2_5"
					( Origin gPackager )
				)
				( objectStatus "TP_SPI_2_5" )
			)
			( signal "@baseboard_fab2_lib.baseboard_fab2(sch_1):tp_spi_2_6"
				( attribute "CDS_PHYS_NET_NAME" "TP_SPI_2_6"
					( Origin gPackager )
				)
				( objectStatus "TP_SPI_2_6" )
			)
			( signal "@baseboard_fab2_lib.baseboard_fab2(sch_1):smb_cpu1_pe_hp_gtl_r_scl"
				( attribute "CDS_PHYS_NET_NAME" "SMB_CPU1_PE_HP_GTL_R_SCL"
					( Origin gPackager )
				)
				( objectStatus "SMB_CPU1_PE_HP_GTL_R_SCL" )
			)
			( signal "@baseboard_fab2_lib.baseboard_fab2(sch_1):smb_cpu1_pe_hp_gtl_r_sda"
				( attribute "CDS_PHYS_NET_NAME" "SMB_CPU1_PE_HP_GTL_R_SDA"
					( Origin gPackager )
				)
				( objectStatus "SMB_CPU1_PE_HP_GTL_R_SDA" )
			)
			( signal "@baseboard_fab2_lib.baseboard_fab2(sch_1):smb_pehpcpu1_stby_lvc3_r_scl"
				( attribute "CDS_PHYS_NET_NAME" "SMB_PEHPCPU1_STBY_LVC3_R_SCL"
					( Origin gPackager )
				)
				( objectStatus "SMB_PEHPCPU1_STBY_LVC3_R_SCL" )
			)
			( signal "@baseboard_fab2_lib.baseboard_fab2(sch_1):smb_pehpcpu1_stby_lvc3_r_sda"
				( attribute "CDS_PHYS_NET_NAME" "SMB_PEHPCPU1_STBY_LVC3_R_SDA"
					( Origin gPackager )
				)
				( objectStatus "SMB_PEHPCPU1_STBY_LVC3_R_SDA" )
			)
			( signal "@baseboard_fab2_lib.baseboard_fab2(sch_1):smb_pehpcpu1_stby_lvc3_scl"
				( attribute "CDS_PHYS_NET_NAME" "SMB_PEHPCPU1_STBY_LVC3_SCL"
					( Origin gPackager )
				)
				( objectStatus "SMB_PEHPCPU1_STBY_LVC3_SCL" )
			)
			( signal "@baseboard_fab2_lib.baseboard_fab2(sch_1):smb_pehpcpu1_stby_lvc3_sda"
				( attribute "CDS_PHYS_NET_NAME" "SMB_PEHPCPU1_STBY_LVC3_SDA"
					( Origin gPackager )
				)
				( objectStatus "SMB_PEHPCPU1_STBY_LVC3_SDA" )
			)
			( signal "@baseboard_fab2_lib.baseboard_fab2(sch_1):tp_smb_pehpcpu1_en"
				( attribute "CDS_PHYS_NET_NAME" "TP_SMB_PEHPCPU1_EN"
					( Origin gPackager )
				)
				( objectStatus "TP_SMB_PEHPCPU1_EN" )
			)
			( signal "@baseboard_fab2_lib.baseboard_fab2(sch_1):fm_adc128_a0"
				( attribute "CDS_PHYS_NET_NAME" "FM_ADC128_A0"
					( Origin gPackager )
				)
				( objectStatus "FM_ADC128_A0" )
			)
			( signal "@baseboard_fab2_lib.baseboard_fab2(sch_1):fm_adc128_a1"
				( attribute "CDS_PHYS_NET_NAME" "FM_ADC128_A1"
					( Origin gPackager )
				)
				( objectStatus "FM_ADC128_A1" )
			)
			( signal "@baseboard_fab2_lib.baseboard_fab2(sch_1):irq_vm_int_r_n"
				( attribute "CDS_PHYS_NET_NAME" "IRQ_VM_INT_R_N"
					( Origin gPackager )
				)
				( objectStatus "IRQ_VM_INT_R_N" )
			)
			( signal "@baseboard_fab2_lib.baseboard_fab2(sch_1):p3v3_fb_adc128_vcc"
				( alias ( signalRef "@baseboard_fab2_lib.baseboard_fab2(sch_1):page165_p3v3_fb_adc128_vcc") )
				( attribute "VOLTAGE" "+3.3V"
					( Units "uVoltage" "V" 1.000000)
					( Status sAliasFlattened )
					( Origin gFrontEnd )
				)
				( attribute "CDS_PHYS_NET_NAME" "P3V3_FB_ADC128_VCC"
					( Origin gPackager )
				)
				( objectStatus "P3V3_FB_ADC128_VCC" )
			)
			( signal "@baseboard_fab2_lib.baseboard_fab2(sch_1):page165_p3v3_fb_adc128_vcc"
				( attribute "VOLTAGE" "+3.3V"
					( Units "uVoltage" "V" 1.000000)
					( Origin gFrontEnd )
				)
				( objectFlag fObjectAlias )
				( objectStatus "page165_p3v3_fb_adc128_vcc" )
			)
			( signal "@baseboard_fab2_lib.baseboard_fab2(sch_1):tp_adc128_vref"
				( attribute "CDS_PHYS_NET_NAME" "TP_ADC128_VREF"
					( Origin gPackager )
				)
				( objectStatus "TP_ADC128_VREF" )
			)
			( signal "@baseboard_fab2_lib.baseboard_fab2(sch_1):isense_tmp421_1_bc"
				( attribute "CDS_PHYS_NET_NAME" "ISENSE_TMP421_1_BC"
					( Origin gPackager )
				)
				( objectStatus "ISENSE_TMP421_1_BC" )
			)
			( signal "@baseboard_fab2_lib.baseboard_fab2(sch_1):isense_tmp421_1_dxn"
				( attribute "CDS_PHYS_NET_NAME" "ISENSE_TMP421_1_DXN"
					( Origin gPackager )
				)
				( objectStatus "ISENSE_TMP421_1_DXN" )
			)
			( signal "@baseboard_fab2_lib.baseboard_fab2(sch_1):isense_tmp421_1_dxp"
				( attribute "CDS_PHYS_NET_NAME" "ISENSE_TMP421_1_DXP"
					( Origin gPackager )
				)
				( objectStatus "ISENSE_TMP421_1_DXP" )
			)
			( signal "@baseboard_fab2_lib.baseboard_fab2(sch_1):isense_tmp421_1_e"
				( attribute "CDS_PHYS_NET_NAME" "ISENSE_TMP421_1_E"
					( Origin gPackager )
				)
				( objectStatus "ISENSE_TMP421_1_E" )
			)
			( signal "@baseboard_fab2_lib.baseboard_fab2(sch_1):isense_tmp421_2_bc"
				( attribute "CDS_PHYS_NET_NAME" "ISENSE_TMP421_2_BC"
					( Origin gPackager )
				)
				( objectStatus "ISENSE_TMP421_2_BC" )
			)
			( signal "@baseboard_fab2_lib.baseboard_fab2(sch_1):isense_tmp421_2_dxn"
				( attribute "CDS_PHYS_NET_NAME" "ISENSE_TMP421_2_DXN"
					( Origin gPackager )
				)
				( objectStatus "ISENSE_TMP421_2_DXN" )
			)
			( signal "@baseboard_fab2_lib.baseboard_fab2(sch_1):isense_tmp421_2_dxp"
				( attribute "CDS_PHYS_NET_NAME" "ISENSE_TMP421_2_DXP"
					( Origin gPackager )
				)
				( objectStatus "ISENSE_TMP421_2_DXP" )
			)
			( signal "@baseboard_fab2_lib.baseboard_fab2(sch_1):isense_tmp421_2_e"
				( attribute "CDS_PHYS_NET_NAME" "ISENSE_TMP421_2_E"
					( Origin gPackager )
				)
				( objectStatus "ISENSE_TMP421_2_E" )
			)
			( signal "@baseboard_fab2_lib.baseboard_fab2(sch_1):pd_fru_wp"
				( attribute "CDS_PHYS_NET_NAME" "PD_FRU_WP"
					( Origin gPackager )
				)
				( objectStatus "PD_FRU_WP" )
			)
			( signal "@baseboard_fab2_lib.baseboard_fab2(sch_1):pd_tmp421_1_a0"
				( attribute "CDS_PHYS_NET_NAME" "PD_TMP421_1_A0"
					( Origin gPackager )
				)
				( objectStatus "PD_TMP421_1_A0" )
			)
			( signal "@baseboard_fab2_lib.baseboard_fab2(sch_1):pd_tmp421_2_a1"
				( attribute "CDS_PHYS_NET_NAME" "PD_TMP421_2_A1"
					( Origin gPackager )
				)
				( objectStatus "PD_TMP421_2_A1" )
			)
			( signal "@baseboard_fab2_lib.baseboard_fab2(sch_1):pu_at24c64_a2"
				( attribute "CDS_PHYS_NET_NAME" "PU_AT24C64_A2"
					( Origin gPackager )
				)
				( objectStatus "PU_AT24C64_A2" )
			)
			( signal "@baseboard_fab2_lib.baseboard_fab2(sch_1):pu_tmp421_1_a1"
				( attribute "CDS_PHYS_NET_NAME" "PU_TMP421_1_A1"
					( Origin gPackager )
				)
				( objectStatus "PU_TMP421_1_A1" )
			)
			( signal "@baseboard_fab2_lib.baseboard_fab2(sch_1):pu_tmp421_2_a0"
				( attribute "CDS_PHYS_NET_NAME" "PU_TMP421_2_A0"
					( Origin gPackager )
				)
				( objectStatus "PU_TMP421_2_A0" )
			)
			( signal "@baseboard_fab2_lib.baseboard_fab2(sch_1):smb_sensor_stby_lvc3_scl"
				( attribute "CDS_PHYS_NET_NAME" "SMB_SENSOR_STBY_LVC3_SCL"
					( Origin gPackager )
				)
				( objectStatus "SMB_SENSOR_STBY_LVC3_SCL" )
			)
			( signal "@baseboard_fab2_lib.baseboard_fab2(sch_1):smb_sensor_stby_lvc3_scl_r2"
				( attribute "CDS_PHYS_NET_NAME" "SMB_SENSOR_STBY_LVC3_SCL_R2"
					( Origin gPackager )
				)
				( objectStatus "SMB_SENSOR_STBY_LVC3_SCL_R2" )
			)
			( signal "@baseboard_fab2_lib.baseboard_fab2(sch_1):smb_sensor_stby_lvc3_sda"
				( attribute "CDS_PHYS_NET_NAME" "SMB_SENSOR_STBY_LVC3_SDA"
					( Origin gPackager )
				)
				( objectStatus "SMB_SENSOR_STBY_LVC3_SDA" )
			)
			( signal "@baseboard_fab2_lib.baseboard_fab2(sch_1):smb_sensor_stby_lvc3_sda_r2"
				( attribute "CDS_PHYS_NET_NAME" "SMB_SENSOR_STBY_LVC3_SDA_R2"
					( Origin gPackager )
				)
				( objectStatus "SMB_SENSOR_STBY_LVC3_SDA_R2" )
			)
			( signal "@baseboard_fab2_lib.baseboard_fab2(sch_1):smb_sensor_tmp421_1_scl"
				( attribute "CDS_PHYS_NET_NAME" "SMB_SENSOR_TMP421_1_SCL"
					( Origin gPackager )
				)
				( objectStatus "SMB_SENSOR_TMP421_1_SCL" )
			)
			( signal "@baseboard_fab2_lib.baseboard_fab2(sch_1):smb_sensor_tmp421_1_sda"
				( attribute "CDS_PHYS_NET_NAME" "SMB_SENSOR_TMP421_1_SDA"
					( Origin gPackager )
				)
				( objectStatus "SMB_SENSOR_TMP421_1_SDA" )
			)
			( signal "@baseboard_fab2_lib.baseboard_fab2(sch_1):smb_sensor_tmp421_2_scl"
				( attribute "CDS_PHYS_NET_NAME" "SMB_SENSOR_TMP421_2_SCL"
					( Origin gPackager )
				)
				( objectStatus "SMB_SENSOR_TMP421_2_SCL" )
			)
			( signal "@baseboard_fab2_lib.baseboard_fab2(sch_1):smb_sensor_tmp421_2_sda"
				( attribute "CDS_PHYS_NET_NAME" "SMB_SENSOR_TMP421_2_SDA"
					( Origin gPackager )
				)
				( objectStatus "SMB_SENSOR_TMP421_2_SDA" )
			)
			( signal "@baseboard_fab2_lib.baseboard_fab2(sch_1):fm_db_present"
				( attribute "CDS_PHYS_NET_NAME" "FM_DB_PRESENT"
					( Origin gPackager )
				)
				( objectStatus "FM_DB_PRESENT" )
			)
			( signal "@baseboard_fab2_lib.baseboard_fab2(sch_1):fm_db_uart_sel0_n"
				( attribute "CDS_PHYS_NET_NAME" "FM_DB_UART_SEL0_N"
					( Origin gPackager )
				)
				( objectStatus "FM_DB_UART_SEL0_N" )
			)
			( signal "@baseboard_fab2_lib.baseboard_fab2(sch_1):fm_db_uart_sel1_n"
				( attribute "CDS_PHYS_NET_NAME" "FM_DB_UART_SEL1_N"
					( Origin gPackager )
				)
				( objectStatus "FM_DB_UART_SEL1_N" )
			)
			( signal "@baseboard_fab2_lib.baseboard_fab2(sch_1):fm_db_uart_sel2_n"
				( attribute "CDS_PHYS_NET_NAME" "FM_DB_UART_SEL2_N"
					( Origin gPackager )
				)
				( objectStatus "FM_DB_UART_SEL2_N" )
			)
			( signal "@baseboard_fab2_lib.baseboard_fab2(sch_1):fm_db_uart_sel3_n"
				( attribute "CDS_PHYS_NET_NAME" "FM_DB_UART_SEL3_N"
					( Origin gPackager )
				)
				( objectStatus "FM_DB_UART_SEL3_N" )
			)
			( signal "@baseboard_fab2_lib.baseboard_fab2(sch_1):fm_db_uart_sel4_n"
				( attribute "CDS_PHYS_NET_NAME" "FM_DB_UART_SEL4_N"
					( Origin gPackager )
				)
				( objectStatus "FM_DB_UART_SEL4_N" )
			)
			( signal "@baseboard_fab2_lib.baseboard_fab2(sch_1):fm_uart_sel_n"
				( attribute "CDS_PHYS_NET_NAME" "FM_UART_SEL_N"
					( Origin gPackager )
				)
				( objectStatus "FM_UART_SEL_N" )
			)
			( signal "@baseboard_fab2_lib.baseboard_fab2(sch_1):tp_fet_q56_3"
				( attribute "CDS_PHYS_NET_NAME" "TP_FET_Q56_3"
					( Origin gPackager )
				)
				( objectStatus "TP_FET_Q56_3" )
			)
			( signal "@baseboard_fab2_lib.baseboard_fab2(sch_1):tp_fet_q56_4"
				( attribute "CDS_PHYS_NET_NAME" "TP_FET_Q56_4"
					( Origin gPackager )
				)
				( objectStatus "TP_FET_Q56_4" )
			)
			( signal "@baseboard_fab2_lib.baseboard_fab2(sch_1):a_p3v_bat_r"
				( alias ( signalRef "@baseboard_fab2_lib.baseboard_fab2(sch_1):page196_a_p3v_bat_r") )
				( attribute "VOLTAGE" "+3 V"
					( Units "uVoltage" "V" 1.000000)
					( Status sAliasFlattened )
					( Origin gFrontEnd )
				)
				( attribute "CDS_PHYS_NET_NAME" "A_P3V_BAT_R"
					( Origin gPackager )
				)
				( objectStatus "A_P3V_BAT_R" )
			)
			( signal "@baseboard_fab2_lib.baseboard_fab2(sch_1):page196_a_p3v_bat_r"
				( attribute "VOLTAGE" "+3 V"
					( Units "uVoltage" "V" 1.000000)
					( Origin gFrontEnd )
				)
				( attribute "CDS_PHYS_NET_NAME" "P3V_BAT_R"
					( Origin gPackager )
				)
				( objectFlag fObjectAlias )
				( objectStatus "page196_a_p3v_bat_r" )
			)
			( signal "@baseboard_fab2_lib.baseboard_fab2(sch_1):fm_battery_sense_en"
				( attribute "CDS_PHYS_NET_NAME" "FM_BATTERY_SENSE_EN"
					( Origin gPackager )
				)
				( objectStatus "FM_BATTERY_SENSE_EN" )
			)
			( signal "@baseboard_fab2_lib.baseboard_fab2(sch_1):p3v_bat_source_r"
				( alias ( signalRef "@baseboard_fab2_lib.baseboard_fab2(sch_1):page169_p3v_bat_source_r") )
				( attribute "VOLTAGE" "+3V"
					( Units "uVoltage" "V" 1.000000)
					( Status sAliasFlattened )
					( Origin gFrontEnd )
				)
				( attribute "CDS_PHYS_NET_NAME" "P3V_BAT_SOURCE_R"
					( Origin gPackager )
				)
				( objectStatus "P3V_BAT_SOURCE_R" )
			)
			( signal "@baseboard_fab2_lib.baseboard_fab2(sch_1):page169_p3v_bat_source_r"
				( attribute "VOLTAGE" "+3V"
					( Units "uVoltage" "V" 1.000000)
					( Origin gFrontEnd )
				)
				( objectFlag fObjectAlias )
				( objectStatus "page169_p3v_bat_source_r" )
			)
			( signal "@baseboard_fab2_lib.baseboard_fab2(sch_1):p5v"
				( alias ( signalRef "@baseboard_fab2_lib.baseboard_fab2(sch_1):page169_p5v") )
				( alias ( signalRef "@baseboard_fab2_lib.baseboard_fab2(sch_1):page172_p5v") )
				( alias ( signalRef "@baseboard_fab2_lib.baseboard_fab2(sch_1):page176_p5v") )
				( alias ( signalRef "@baseboard_fab2_lib.baseboard_fab2(sch_1):page196_p5v") )
				( alias ( signalRef "@baseboard_fab2_lib.baseboard_fab2(sch_1):page198_p5v") )
				( alias ( signalRef "@baseboard_fab2_lib.baseboard_fab2(sch_1):page155_p5v") )
				( attribute "CDS_PHYS_NET_NAME" "P5V"
					( Origin gPackager )
				)
				( attribute "VOLTAGE" "5.0V"
					( Units "uVoltage" "V" 1.000000)
					( Status sAliasFlattened )
					( Status sAliasConflict )
					( Origin gFrontEnd )
				)
				( objectStatus "P5V" )
			)
			( signal "@baseboard_fab2_lib.baseboard_fab2(sch_1):page169_p5v"
				( attribute "VOLTAGE" "5.0V"
					( Units "uVoltage" "V" 1.000000)
					( Origin gFrontEnd )
				)
				( objectFlag fObjectAlias )
				( objectStatus "page169_p5v" )
			)
			( signal "@baseboard_fab2_lib.baseboard_fab2(sch_1):page172_p5v"
				( attribute "VOLTAGE" "+5.0V"
					( Units "uVoltage" "V" 1.000000)
					( Origin gFrontEnd )
				)
				( objectFlag fObjectAlias )
				( objectStatus "page172_p5v" )
			)
			( signal "@baseboard_fab2_lib.baseboard_fab2(sch_1):page176_p5v"
				( attribute "VOLTAGE" "5.0V"
					( Units "uVoltage" "V" 1.000000)
					( Origin gFrontEnd )
				)
				( objectFlag fObjectAlias )
				( objectStatus "page176_p5v" )
			)
			( signal "@baseboard_fab2_lib.baseboard_fab2(sch_1):page196_p5v"
				( attribute "VOLTAGE" "5.0V"
					( Units "uVoltage" "V" 1.000000)
					( Origin gFrontEnd )
				)
				( objectFlag fObjectAlias )
				( objectStatus "page196_p5v" )
			)
			( signal "@baseboard_fab2_lib.baseboard_fab2(sch_1):page198_p5v"
				( attribute "VOLTAGE" "+5.0V"
					( Units "uVoltage" "V" 1.000000)
					( Origin gFrontEnd )
				)
				( objectFlag fObjectAlias )
				( objectStatus "page198_p5v" )
			)
			( signal "@baseboard_fab2_lib.baseboard_fab2(sch_1):fm_fast_prochot_and_out_0_n"
				( attribute "CDS_PHYS_NET_NAME" "FM_FAST_PROCHOT_AND_OUT_0_N"
					( Origin gPackager )
				)
				( objectStatus "FM_FAST_PROCHOT_AND_OUT_0_N" )
			)
			( signal "@baseboard_fab2_lib.baseboard_fab2(sch_1):fm_fast_prochot_and_out_1_n"
				( attribute "CDS_PHYS_NET_NAME" "FM_FAST_PROCHOT_AND_OUT_1_N"
					( Origin gPackager )
				)
				( objectStatus "FM_FAST_PROCHOT_AND_OUT_1_N" )
			)
			( signal "@baseboard_fab2_lib.baseboard_fab2(sch_1):fm_fast_prochot_en"
				( attribute "CDS_PHYS_NET_NAME" "FM_FAST_PROCHOT_EN"
					( Origin gPackager )
				)
				( objectStatus "FM_FAST_PROCHOT_EN" )
			)
			( signal "@baseboard_fab2_lib.baseboard_fab2(sch_1):fm_fast_prochot_throttle_dly_buf_n"
				( attribute "CDS_PHYS_NET_NAME" "FM_FAST_PROCHOT_THROTTLE_DLY_BU"
					( Origin gPackager )
				)
				( attribute "PNN" "FM_FAST_PROCHOT_THROTTLE_DLY_BU"
					( Origin gPackager )
				)
				( objectStatus "FM_FAST_PROCHOT_THROTTLE_DLY_BU" )
			)
			( signal "@baseboard_fab2_lib.baseboard_fab2(sch_1):fm_fast_prochot_throttle_dly_n"
				( attribute "CDS_PHYS_NET_NAME" "FM_FAST_PROCHOT_THROTTLE_DLY_N"
					( Origin gPackager )
				)
				( objectStatus "FM_FAST_PROCHOT_THROTTLE_DLY_N" )
			)
			( signal "@baseboard_fab2_lib.baseboard_fab2(sch_1):fm_fast_prochot_throttle_in_n"
				( attribute "CDS_PHYS_NET_NAME" "FM_FAST_PROCHOT_THROTTLE_IN_N"
					( Origin gPackager )
				)
				( objectStatus "FM_FAST_PROCHOT_THROTTLE_IN_N" )
			)
			( signal "@baseboard_fab2_lib.baseboard_fab2(sch_1):fm_oc_detect_n"
				( attribute "CDS_PHYS_NET_NAME" "FM_OC_DETECT_N"
					( Origin gPackager )
				)
				( objectStatus "FM_OC_DETECT_N" )
			)
			( signal "@baseboard_fab2_lib.baseboard_fab2(sch_1):fm_pmbus_alert_buf_en"
				( attribute "CDS_PHYS_NET_NAME" "FM_PMBUS_ALERT_BUF_EN"
					( Origin gPackager )
				)
				( objectStatus "FM_PMBUS_ALERT_BUF_EN" )
			)
			( signal "@baseboard_fab2_lib.baseboard_fab2(sch_1):fm_throttle_r1_n"
				( attribute "CDS_PHYS_NET_NAME" "FM_THROTTLE_R1_N"
					( Origin gPackager )
				)
				( objectStatus "FM_THROTTLE_R1_N" )
			)
			( signal "@baseboard_fab2_lib.baseboard_fab2(sch_1):irq_force_nm_throttle_r_n"
				( attribute "CDS_PHYS_NET_NAME" "IRQ_FORCE_NM_THROTTLE_R_N"
					( Origin gPackager )
				)
				( objectStatus "IRQ_FORCE_NM_THROTTLE_R_N" )
			)
			( signal "@baseboard_fab2_lib.baseboard_fab2(sch_1):irq_sml1_pmbus_alert_buf_n"
				( attribute "CDS_PHYS_NET_NAME" "IRQ_SML1_PMBUS_ALERT_BUF_N"
					( Origin gPackager )
				)
				( objectStatus "IRQ_SML1_PMBUS_ALERT_BUF_N" )
			)
			( signal "@baseboard_fab2_lib.baseboard_fab2(sch_1):p12v_hdd_sata"
				( alias ( signalRef "@baseboard_fab2_lib.baseboard_fab2(sch_1):page172_p12v_hdd_sata") )
				( attribute "VOLTAGE" "12"
					( Units "uVoltage" "V" 1.000000)
					( Status sAliasFlattened )
					( Origin gFrontEnd )
				)
				( attribute "CDS_PHYS_NET_NAME" "P12V_HDD_SATA"
					( Origin gPackager )
				)
				( objectStatus "P12V_HDD_SATA" )
			)
			( signal "@baseboard_fab2_lib.baseboard_fab2(sch_1):page172_p12v_hdd_sata"
				( attribute "VOLTAGE" "12"
					( Units "uVoltage" "V" 1.000000)
					( Origin gFrontEnd )
				)
				( objectFlag fObjectAlias )
				( objectStatus "page172_p12v_hdd_sata" )
			)
			( signal "@baseboard_fab2_lib.baseboard_fab2(sch_1):p5v_hdd_sata"
				( alias ( signalRef "@baseboard_fab2_lib.baseboard_fab2(sch_1):page172_p5v_hdd_sata") )
				( attribute "VOLTAGE" "5"
					( Units "uVoltage" "V" 1.000000)
					( Status sAliasFlattened )
					( Origin gFrontEnd )
				)
				( attribute "CDS_PHYS_NET_NAME" "P5V_HDD_SATA"
					( Origin gPackager )
				)
				( objectStatus "P5V_HDD_SATA" )
			)
			( signal "@baseboard_fab2_lib.baseboard_fab2(sch_1):page172_p5v_hdd_sata"
				( attribute "VOLTAGE" "5"
					( Units "uVoltage" "V" 1.000000)
					( Origin gFrontEnd )
				)
				( objectFlag fObjectAlias )
				( objectStatus "page172_p5v_hdd_sata" )
			)
			( signal "@baseboard_fab2_lib.baseboard_fab2(sch_1):sata6g_s1_rx_c_dn"
				( attribute "CDS_PHYS_NET_NAME" "SATA6G_S1_RX_C_DN"
					( Origin gPackager )
				)
				( objectStatus "SATA6G_S1_RX_C_DN" )
			)
			( signal "@baseboard_fab2_lib.baseboard_fab2(sch_1):sata6g_s1_rx_c_dp"
				( attribute "CDS_PHYS_NET_NAME" "SATA6G_S1_RX_C_DP"
					( Origin gPackager )
				)
				( objectStatus "SATA6G_S1_RX_C_DP" )
			)
			( signal "@baseboard_fab2_lib.baseboard_fab2(sch_1):sata6g_s1_tx_c_dn"
				( attribute "CDS_PHYS_NET_NAME" "SATA6G_S1_TX_C_DN"
					( Origin gPackager )
				)
				( objectStatus "SATA6G_S1_TX_C_DN" )
			)
			( signal "@baseboard_fab2_lib.baseboard_fab2(sch_1):sata6g_s1_tx_c_dp"
				( attribute "CDS_PHYS_NET_NAME" "SATA6G_S1_TX_C_DP"
					( Origin gPackager )
				)
				( objectStatus "SATA6G_S1_TX_C_DP" )
			)
			( signal "@baseboard_fab2_lib.baseboard_fab2(sch_1):pd_sata0_controller_type_r"
				( attribute "CDS_PHYS_NET_NAME" "PD_SATA0_CONTROLLER_TYPE_R"
					( Origin gPackager )
				)
				( objectStatus "PD_SATA0_CONTROLLER_TYPE_R" )
			)
			( signal "@baseboard_fab2_lib.baseboard_fab2(sch_1):pd_sata1_controller_type_r"
				( attribute "CDS_PHYS_NET_NAME" "PD_SATA1_CONTROLLER_TYPE_R"
					( Origin gPackager )
				)
				( objectStatus "PD_SATA1_CONTROLLER_TYPE_R" )
			)
			( signal "@baseboard_fab2_lib.baseboard_fab2(sch_1):pu_datain1_sata_0_r"
				( attribute "CDS_PHYS_NET_NAME" "PU_DATAIN1_SATA_0_R"
					( Origin gPackager )
				)
				( objectStatus "PU_DATAIN1_SATA_0_R" )
			)
			( signal "@baseboard_fab2_lib.baseboard_fab2(sch_1):pu_datain1_sata_1_r"
				( attribute "CDS_PHYS_NET_NAME" "PU_DATAIN1_SATA_1_R"
					( Origin gPackager )
				)
				( objectStatus "PU_DATAIN1_SATA_1_R" )
			)
			( signal "@baseboard_fab2_lib.baseboard_fab2(sch_1):sata6g_p0_rx_c_dn"
				( attribute "CDS_PHYS_NET_NAME" "SATA6G_P0_RX_C_DN"
					( Origin gPackager )
				)
				( objectStatus "SATA6G_P0_RX_C_DN" )
			)
			( signal "@baseboard_fab2_lib.baseboard_fab2(sch_1):sata6g_p0_rx_c_dp"
				( attribute "CDS_PHYS_NET_NAME" "SATA6G_P0_RX_C_DP"
					( Origin gPackager )
				)
				( objectStatus "SATA6G_P0_RX_C_DP" )
			)
			( signal "@baseboard_fab2_lib.baseboard_fab2(sch_1):sata6g_p0_tx_c_dn"
				( attribute "CDS_PHYS_NET_NAME" "SATA6G_P0_TX_C_DN"
					( Origin gPackager )
				)
				( objectStatus "SATA6G_P0_TX_C_DN" )
			)
			( signal "@baseboard_fab2_lib.baseboard_fab2(sch_1):sata6g_p0_tx_c_dp"
				( attribute "CDS_PHYS_NET_NAME" "SATA6G_P0_TX_C_DP"
					( Origin gPackager )
				)
				( objectStatus "SATA6G_P0_TX_C_DP" )
			)
			( signal "@baseboard_fab2_lib.baseboard_fab2(sch_1):sata6g_p1_rx_c_dn"
				( attribute "CDS_PHYS_NET_NAME" "SATA6G_P1_RX_C_DN"
					( Origin gPackager )
				)
				( objectStatus "SATA6G_P1_RX_C_DN" )
			)
			( signal "@baseboard_fab2_lib.baseboard_fab2(sch_1):sata6g_p1_rx_c_dp"
				( attribute "CDS_PHYS_NET_NAME" "SATA6G_P1_RX_C_DP"
					( Origin gPackager )
				)
				( objectStatus "SATA6G_P1_RX_C_DP" )
			)
			( signal "@baseboard_fab2_lib.baseboard_fab2(sch_1):sata6g_p1_tx_c_dn"
				( attribute "CDS_PHYS_NET_NAME" "SATA6G_P1_TX_C_DN"
					( Origin gPackager )
				)
				( objectStatus "SATA6G_P1_TX_C_DN" )
			)
			( signal "@baseboard_fab2_lib.baseboard_fab2(sch_1):sata6g_p1_tx_c_dp"
				( attribute "CDS_PHYS_NET_NAME" "SATA6G_P1_TX_C_DP"
					( Origin gPackager )
				)
				( objectStatus "SATA6G_P1_TX_C_DP" )
			)
			( signal "@baseboard_fab2_lib.baseboard_fab2(sch_1):sata6g_p2_rx_c_dn"
				( attribute "CDS_PHYS_NET_NAME" "SATA6G_P2_RX_C_DN"
					( Origin gPackager )
				)
				( objectStatus "SATA6G_P2_RX_C_DN" )
			)
			( signal "@baseboard_fab2_lib.baseboard_fab2(sch_1):sata6g_p2_rx_c_dp"
				( attribute "CDS_PHYS_NET_NAME" "SATA6G_P2_RX_C_DP"
					( Origin gPackager )
				)
				( objectStatus "SATA6G_P2_RX_C_DP" )
			)
			( signal "@baseboard_fab2_lib.baseboard_fab2(sch_1):sata6g_p2_tx_c_dn"
				( attribute "CDS_PHYS_NET_NAME" "SATA6G_P2_TX_C_DN"
					( Origin gPackager )
				)
				( objectStatus "SATA6G_P2_TX_C_DN" )
			)
			( signal "@baseboard_fab2_lib.baseboard_fab2(sch_1):sata6g_p2_tx_c_dp"
				( attribute "CDS_PHYS_NET_NAME" "SATA6G_P2_TX_C_DP"
					( Origin gPackager )
				)
				( objectStatus "SATA6G_P2_TX_C_DP" )
			)
			( signal "@baseboard_fab2_lib.baseboard_fab2(sch_1):sata6g_p3_rx_c_dn"
				( attribute "CDS_PHYS_NET_NAME" "SATA6G_P3_RX_C_DN"
					( Origin gPackager )
				)
				( objectStatus "SATA6G_P3_RX_C_DN" )
			)
			( signal "@baseboard_fab2_lib.baseboard_fab2(sch_1):sata6g_p3_rx_c_dp"
				( attribute "CDS_PHYS_NET_NAME" "SATA6G_P3_RX_C_DP"
					( Origin gPackager )
				)
				( objectStatus "SATA6G_P3_RX_C_DP" )
			)
			( signal "@baseboard_fab2_lib.baseboard_fab2(sch_1):sata6g_p3_tx_c_dn"
				( attribute "CDS_PHYS_NET_NAME" "SATA6G_P3_TX_C_DN"
					( Origin gPackager )
				)
				( objectStatus "SATA6G_P3_TX_C_DN" )
			)
			( signal "@baseboard_fab2_lib.baseboard_fab2(sch_1):sata6g_p3_tx_c_dp"
				( attribute "CDS_PHYS_NET_NAME" "SATA6G_P3_TX_C_DP"
					( Origin gPackager )
				)
				( objectStatus "SATA6G_P3_TX_C_DP" )
			)
			( signal "@baseboard_fab2_lib.baseboard_fab2(sch_1):sata6g_p4_rx_c_dn"
				( attribute "CDS_PHYS_NET_NAME" "SATA6G_P4_RX_C_DN"
					( Origin gPackager )
				)
				( objectStatus "SATA6G_P4_RX_C_DN" )
			)
			( signal "@baseboard_fab2_lib.baseboard_fab2(sch_1):sata6g_p4_rx_c_dp"
				( attribute "CDS_PHYS_NET_NAME" "SATA6G_P4_RX_C_DP"
					( Origin gPackager )
				)
				( objectStatus "SATA6G_P4_RX_C_DP" )
			)
			( signal "@baseboard_fab2_lib.baseboard_fab2(sch_1):sata6g_p4_tx_c_dn"
				( attribute "CDS_PHYS_NET_NAME" "SATA6G_P4_TX_C_DN"
					( Origin gPackager )
				)
				( objectStatus "SATA6G_P4_TX_C_DN" )
			)
			( signal "@baseboard_fab2_lib.baseboard_fab2(sch_1):sata6g_p4_tx_c_dp"
				( attribute "CDS_PHYS_NET_NAME" "SATA6G_P4_TX_C_DP"
					( Origin gPackager )
				)
				( objectStatus "SATA6G_P4_TX_C_DP" )
			)
			( signal "@baseboard_fab2_lib.baseboard_fab2(sch_1):sata6g_p5_rx_c_dn"
				( attribute "CDS_PHYS_NET_NAME" "SATA6G_P5_RX_C_DN"
					( Origin gPackager )
				)
				( objectStatus "SATA6G_P5_RX_C_DN" )
			)
			( signal "@baseboard_fab2_lib.baseboard_fab2(sch_1):sata6g_p5_rx_c_dp"
				( attribute "CDS_PHYS_NET_NAME" "SATA6G_P5_RX_C_DP"
					( Origin gPackager )
				)
				( objectStatus "SATA6G_P5_RX_C_DP" )
			)
			( signal "@baseboard_fab2_lib.baseboard_fab2(sch_1):sata6g_p5_tx_c_dn"
				( attribute "CDS_PHYS_NET_NAME" "SATA6G_P5_TX_C_DN"
					( Origin gPackager )
				)
				( objectStatus "SATA6G_P5_TX_C_DN" )
			)
			( signal "@baseboard_fab2_lib.baseboard_fab2(sch_1):sata6g_p5_tx_c_dp"
				( attribute "CDS_PHYS_NET_NAME" "SATA6G_P5_TX_C_DP"
					( Origin gPackager )
				)
				( objectStatus "SATA6G_P5_TX_C_DP" )
			)
			( signal "@baseboard_fab2_lib.baseboard_fab2(sch_1):sata6g_p6_rx_c_dn"
				( attribute "CDS_PHYS_NET_NAME" "SATA6G_P6_RX_C_DN"
					( Origin gPackager )
				)
				( objectStatus "SATA6G_P6_RX_C_DN" )
			)
			( signal "@baseboard_fab2_lib.baseboard_fab2(sch_1):sata6g_p6_rx_c_dp"
				( attribute "CDS_PHYS_NET_NAME" "SATA6G_P6_RX_C_DP"
					( Origin gPackager )
				)
				( objectStatus "SATA6G_P6_RX_C_DP" )
			)
			( signal "@baseboard_fab2_lib.baseboard_fab2(sch_1):sata6g_p6_tx_c_dn"
				( attribute "CDS_PHYS_NET_NAME" "SATA6G_P6_TX_C_DN"
					( Origin gPackager )
				)
				( objectStatus "SATA6G_P6_TX_C_DN" )
			)
			( signal "@baseboard_fab2_lib.baseboard_fab2(sch_1):sata6g_p6_tx_c_dp"
				( attribute "CDS_PHYS_NET_NAME" "SATA6G_P6_TX_C_DP"
					( Origin gPackager )
				)
				( objectStatus "SATA6G_P6_TX_C_DP" )
			)
			( signal "@baseboard_fab2_lib.baseboard_fab2(sch_1):sata6g_p7_rx_c_dn"
				( attribute "CDS_PHYS_NET_NAME" "SATA6G_P7_RX_C_DN"
					( Origin gPackager )
				)
				( objectStatus "SATA6G_P7_RX_C_DN" )
			)
			( signal "@baseboard_fab2_lib.baseboard_fab2(sch_1):sata6g_p7_rx_c_dp"
				( attribute "CDS_PHYS_NET_NAME" "SATA6G_P7_RX_C_DP"
					( Origin gPackager )
				)
				( objectStatus "SATA6G_P7_RX_C_DP" )
			)
			( signal "@baseboard_fab2_lib.baseboard_fab2(sch_1):sata6g_p7_tx_c_dn"
				( attribute "CDS_PHYS_NET_NAME" "SATA6G_P7_TX_C_DN"
					( Origin gPackager )
				)
				( objectStatus "SATA6G_P7_TX_C_DN" )
			)
			( signal "@baseboard_fab2_lib.baseboard_fab2(sch_1):sata6g_p7_tx_c_dp"
				( attribute "CDS_PHYS_NET_NAME" "SATA6G_P7_TX_C_DP"
					( Origin gPackager )
				)
				( objectStatus "SATA6G_P7_TX_C_DP" )
			)
			( signal "@baseboard_fab2_lib.baseboard_fab2(sch_1):sgpio_pch_sata_clock_r"
				( attribute "CDS_PHYS_NET_NAME" "SGPIO_PCH_SATA_CLOCK_R"
					( Origin gPackager )
				)
				( objectStatus "SGPIO_PCH_SATA_CLOCK_R" )
			)
			( signal "@baseboard_fab2_lib.baseboard_fab2(sch_1):sgpio_pch_sata_dout0_r"
				( attribute "CDS_PHYS_NET_NAME" "SGPIO_PCH_SATA_DOUT0_R"
					( Origin gPackager )
				)
				( objectStatus "SGPIO_PCH_SATA_DOUT0_R" )
			)
			( signal "@baseboard_fab2_lib.baseboard_fab2(sch_1):sgpio_pch_sata_load_r"
				( attribute "CDS_PHYS_NET_NAME" "SGPIO_PCH_SATA_LOAD_R"
					( Origin gPackager )
				)
				( objectStatus "SGPIO_PCH_SATA_LOAD_R" )
			)
			( signal "@baseboard_fab2_lib.baseboard_fab2(sch_1):tp_fm_qat_cbl_prsnt0_r_n"
				( attribute "CDS_PHYS_NET_NAME" "TP_FM_QAT_CBL_PRSNT0_R_N"
					( Origin gPackager )
				)
				( objectStatus "TP_FM_QAT_CBL_PRSNT0_R_N" )
			)
			( signal "@baseboard_fab2_lib.baseboard_fab2(sch_1):tp_fm_qat_cbl_prsnt1_n_r"
				( attribute "CDS_PHYS_NET_NAME" "TP_FM_QAT_CBL_PRSNT1_N_R"
					( Origin gPackager )
				)
				( objectStatus "TP_FM_QAT_CBL_PRSNT1_N_R" )
			)
			( signal "@baseboard_fab2_lib.baseboard_fab2(sch_1):tp_sgpio_sata_clock1_r"
				( attribute "CDS_PHYS_NET_NAME" "TP_SGPIO_SATA_CLOCK1_R"
					( Origin gPackager )
				)
				( objectStatus "TP_SGPIO_SATA_CLOCK1_R" )
			)
			( signal "@baseboard_fab2_lib.baseboard_fab2(sch_1):tp_sgpio_sata_data1_r"
				( attribute "CDS_PHYS_NET_NAME" "TP_SGPIO_SATA_DATA1_R"
					( Origin gPackager )
				)
				( objectStatus "TP_SGPIO_SATA_DATA1_R" )
			)
			( signal "@baseboard_fab2_lib.baseboard_fab2(sch_1):tp_sgpio_sata_load1_r"
				( attribute "CDS_PHYS_NET_NAME" "TP_SGPIO_SATA_LOAD1_R"
					( Origin gPackager )
				)
				( objectStatus "TP_SGPIO_SATA_LOAD1_R" )
			)
			( signal "@baseboard_fab2_lib.baseboard_fab2(sch_1):pd_sata2_controller_type"
				( attribute "CDS_PHYS_NET_NAME" "PD_SATA2_CONTROLLER_TYPE"
					( Origin gPackager )
				)
				( objectStatus "PD_SATA2_CONTROLLER_TYPE" )
			)
			( signal "@baseboard_fab2_lib.baseboard_fab2(sch_1):pu_datain1_sata_2"
				( attribute "CDS_PHYS_NET_NAME" "PU_DATAIN1_SATA_2"
					( Origin gPackager )
				)
				( objectStatus "PU_DATAIN1_SATA_2" )
			)
			( signal "@baseboard_fab2_lib.baseboard_fab2(sch_1):sata6g_p10_rx_c_dn"
				( attribute "CDS_PHYS_NET_NAME" "SATA6G_P10_RX_C_DN"
					( Origin gPackager )
				)
				( objectStatus "SATA6G_P10_RX_C_DN" )
			)
			( signal "@baseboard_fab2_lib.baseboard_fab2(sch_1):sata6g_p10_rx_c_dp"
				( attribute "CDS_PHYS_NET_NAME" "SATA6G_P10_RX_C_DP"
					( Origin gPackager )
				)
				( objectStatus "SATA6G_P10_RX_C_DP" )
			)
			( signal "@baseboard_fab2_lib.baseboard_fab2(sch_1):sata6g_p10_tx_c_dn"
				( attribute "CDS_PHYS_NET_NAME" "SATA6G_P10_TX_C_DN"
					( Origin gPackager )
				)
				( objectStatus "SATA6G_P10_TX_C_DN" )
			)
			( signal "@baseboard_fab2_lib.baseboard_fab2(sch_1):sata6g_p10_tx_c_dp"
				( attribute "CDS_PHYS_NET_NAME" "SATA6G_P10_TX_C_DP"
					( Origin gPackager )
				)
				( objectStatus "SATA6G_P10_TX_C_DP" )
			)
			( signal "@baseboard_fab2_lib.baseboard_fab2(sch_1):sata6g_p11_rx_c_dn"
				( attribute "CDS_PHYS_NET_NAME" "SATA6G_P11_RX_C_DN"
					( Origin gPackager )
				)
				( objectStatus "SATA6G_P11_RX_C_DN" )
			)
			( signal "@baseboard_fab2_lib.baseboard_fab2(sch_1):sata6g_p11_rx_c_dp"
				( attribute "CDS_PHYS_NET_NAME" "SATA6G_P11_RX_C_DP"
					( Origin gPackager )
				)
				( objectStatus "SATA6G_P11_RX_C_DP" )
			)
			( signal "@baseboard_fab2_lib.baseboard_fab2(sch_1):sata6g_p11_tx_c_dn"
				( attribute "CDS_PHYS_NET_NAME" "SATA6G_P11_TX_C_DN"
					( Origin gPackager )
				)
				( objectStatus "SATA6G_P11_TX_C_DN" )
			)
			( signal "@baseboard_fab2_lib.baseboard_fab2(sch_1):sata6g_p11_tx_c_dp"
				( attribute "CDS_PHYS_NET_NAME" "SATA6G_P11_TX_C_DP"
					( Origin gPackager )
				)
				( objectStatus "SATA6G_P11_TX_C_DP" )
			)
			( signal "@baseboard_fab2_lib.baseboard_fab2(sch_1):sata6g_p8_rx_c_dn"
				( attribute "CDS_PHYS_NET_NAME" "SATA6G_P8_RX_C_DN"
					( Origin gPackager )
				)
				( objectStatus "SATA6G_P8_RX_C_DN" )
			)
			( signal "@baseboard_fab2_lib.baseboard_fab2(sch_1):sata6g_p8_rx_c_dp"
				( attribute "CDS_PHYS_NET_NAME" "SATA6G_P8_RX_C_DP"
					( Origin gPackager )
				)
				( objectStatus "SATA6G_P8_RX_C_DP" )
			)
			( signal "@baseboard_fab2_lib.baseboard_fab2(sch_1):sata6g_p8_tx_c_dn"
				( attribute "CDS_PHYS_NET_NAME" "SATA6G_P8_TX_C_DN"
					( Origin gPackager )
				)
				( objectStatus "SATA6G_P8_TX_C_DN" )
			)
			( signal "@baseboard_fab2_lib.baseboard_fab2(sch_1):sata6g_p8_tx_c_dp"
				( attribute "CDS_PHYS_NET_NAME" "SATA6G_P8_TX_C_DP"
					( Origin gPackager )
				)
				( objectStatus "SATA6G_P8_TX_C_DP" )
			)
			( signal "@baseboard_fab2_lib.baseboard_fab2(sch_1):sata6g_p9_rx_c_dn"
				( attribute "CDS_PHYS_NET_NAME" "SATA6G_P9_RX_C_DN"
					( Origin gPackager )
				)
				( objectStatus "SATA6G_P9_RX_C_DN" )
			)
			( signal "@baseboard_fab2_lib.baseboard_fab2(sch_1):sata6g_p9_rx_c_dp"
				( attribute "CDS_PHYS_NET_NAME" "SATA6G_P9_RX_C_DP"
					( Origin gPackager )
				)
				( objectStatus "SATA6G_P9_RX_C_DP" )
			)
			( signal "@baseboard_fab2_lib.baseboard_fab2(sch_1):sata6g_p9_tx_c_dn"
				( attribute "CDS_PHYS_NET_NAME" "SATA6G_P9_TX_C_DN"
					( Origin gPackager )
				)
				( objectStatus "SATA6G_P9_TX_C_DN" )
			)
			( signal "@baseboard_fab2_lib.baseboard_fab2(sch_1):sata6g_p9_tx_c_dp"
				( attribute "CDS_PHYS_NET_NAME" "SATA6G_P9_TX_C_DP"
					( Origin gPackager )
				)
				( objectStatus "SATA6G_P9_TX_C_DP" )
			)
			( signal "@baseboard_fab2_lib.baseboard_fab2(sch_1):sgpio_pch_ssata_clock_r"
				( attribute "CDS_PHYS_NET_NAME" "SGPIO_PCH_SSATA_CLOCK_R"
					( Origin gPackager )
				)
				( objectStatus "SGPIO_PCH_SSATA_CLOCK_R" )
			)
			( signal "@baseboard_fab2_lib.baseboard_fab2(sch_1):sgpio_pch_ssata_dout0_r"
				( attribute "CDS_PHYS_NET_NAME" "SGPIO_PCH_SSATA_DOUT0_R"
					( Origin gPackager )
				)
				( objectStatus "SGPIO_PCH_SSATA_DOUT0_R" )
			)
			( signal "@baseboard_fab2_lib.baseboard_fab2(sch_1):sgpio_pch_ssata_load_r"
				( attribute "CDS_PHYS_NET_NAME" "SGPIO_PCH_SSATA_LOAD_R"
					( Origin gPackager )
				)
				( objectStatus "SGPIO_PCH_SSATA_LOAD_R" )
			)
			( signal "@baseboard_fab2_lib.baseboard_fab2(sch_1):tp_fm_qat_cbl_prsnt2_n"
				( attribute "CDS_PHYS_NET_NAME" "TP_FM_QAT_CBL_PRSNT2_N"
					( Origin gPackager )
				)
				( objectStatus "TP_FM_QAT_CBL_PRSNT2_N" )
			)
			( signal "@baseboard_fab2_lib.baseboard_fab2(sch_1):fm_beep_led_p"
				( attribute "CDS_PHYS_NET_NAME" "FM_BEEP_LED_P"
					( Origin gPackager )
				)
				( objectStatus "FM_BEEP_LED_P" )
			)
			( signal "@baseboard_fab2_lib.baseboard_fab2(sch_1):fm_pwr_btn_r_n"
				( attribute "CDS_PHYS_NET_NAME" "FM_PWR_BTN_R_N"
					( Origin gPackager )
				)
				( objectStatus "FM_PWR_BTN_R_N" )
			)
			( signal "@baseboard_fab2_lib.baseboard_fab2(sch_1):fm_speaker_pch_n"
				( attribute "CDS_PHYS_NET_NAME" "FM_SPEAKER_PCH_N"
					( Origin gPackager )
				)
				( objectStatus "FM_SPEAKER_PCH_N" )
			)
			( signal "@baseboard_fab2_lib.baseboard_fab2(sch_1):fp_id_led_p5v_stby_n"
				( attribute "CDS_PHYS_NET_NAME" "FP_ID_LED_P5V_STBY_N"
					( Origin gPackager )
				)
				( objectStatus "FP_ID_LED_P5V_STBY_N" )
			)
			( signal "@baseboard_fab2_lib.baseboard_fab2(sch_1):fp_id_led_xor_r"
				( attribute "CDS_PHYS_NET_NAME" "FP_ID_LED_XOR_R"
					( Origin gPackager )
				)
				( objectStatus "FP_ID_LED_XOR_R" )
			)
			( signal "@baseboard_fab2_lib.baseboard_fab2(sch_1):fp_pwr_btn_buf1_n"
				( attribute "CDS_PHYS_NET_NAME" "FP_PWR_BTN_BUF1_N"
					( Origin gPackager )
				)
				( objectStatus "FP_PWR_BTN_BUF1_N" )
			)
			( signal "@baseboard_fab2_lib.baseboard_fab2(sch_1):fp_pwr_btn_r1_n"
				( attribute "CDS_PHYS_NET_NAME" "FP_PWR_BTN_R1_N"
					( Origin gPackager )
				)
				( objectStatus "FP_PWR_BTN_R1_N" )
			)
			( signal "@baseboard_fab2_lib.baseboard_fab2(sch_1):fp_pwr_btn_r_n"
				( attribute "CDS_PHYS_NET_NAME" "FP_PWR_BTN_R_N"
					( Origin gPackager )
				)
				( objectStatus "FP_PWR_BTN_R_N" )
			)
			( signal "@baseboard_fab2_lib.baseboard_fab2(sch_1):fp_rst_btn_buf1_n"
				( attribute "CDS_PHYS_NET_NAME" "FP_RST_BTN_BUF1_N"
					( Origin gPackager )
				)
				( objectStatus "FP_RST_BTN_BUF1_N" )
			)
			( signal "@baseboard_fab2_lib.baseboard_fab2(sch_1):fp_rst_btn_r_n"
				( attribute "CDS_PHYS_NET_NAME" "FP_RST_BTN_R_N"
					( Origin gPackager )
				)
				( objectStatus "FP_RST_BTN_R_N" )
			)
			( signal "@baseboard_fab2_lib.baseboard_fab2(sch_1):pwrgd_p3v3"
				( attribute "CDS_PHYS_NET_NAME" "PWRGD_P3V3"
					( Origin gPackager )
				)
				( objectStatus "PWRGD_P3V3" )
			)
			( signal "@baseboard_fab2_lib.baseboard_fab2(sch_1):pwrgd_p3v3_r"
				( attribute "CDS_PHYS_NET_NAME" "PWRGD_P3V3_R"
					( Origin gPackager )
				)
				( objectStatus "PWRGD_P3V3_R" )
			)
			( signal "@baseboard_fab2_lib.baseboard_fab2(sch_1):rst_system_btn_buf_n"
				( attribute "CDS_PHYS_NET_NAME" "RST_SYSTEM_BTN_BUF_N"
					( Origin gPackager )
				)
				( objectStatus "RST_SYSTEM_BTN_BUF_N" )
			)
			( signal "@baseboard_fab2_lib.baseboard_fab2(sch_1):p5v_usb"
				( alias ( signalRef "@baseboard_fab2_lib.baseboard_fab2(sch_1):page176_p5v_usb") )
				( attribute "CDS_PHYS_NET_NAME" "P5V_USB"
					( Origin gPackager )
				)
				( attribute "VOLTAGE" "5V"
					( Units "uVoltage" "V" 1.000000)
					( Status sAliasFlattened )
					( Origin gFrontEnd )
				)
				( objectStatus "P5V_USB" )
			)
			( signal "@baseboard_fab2_lib.baseboard_fab2(sch_1):page176_p5v_usb"
				( attribute "VOLTAGE" "5V"
					( Units "uVoltage" "V" 1.000000)
					( Origin gFrontEnd )
				)
				( objectFlag fObjectAlias )
				( objectStatus "page176_p5v_usb" )
			)
			( signal "@baseboard_fab2_lib.baseboard_fab2(sch_1):tp_usb_esd_ac2"
				( attribute "CDS_PHYS_NET_NAME" "TP_USB_ESD_AC2"
					( Origin gPackager )
				)
				( objectStatus "TP_USB_ESD_AC2" )
			)
			( signal "@baseboard_fab2_lib.baseboard_fab2(sch_1):tp_usb_esd_ac3"
				( attribute "CDS_PHYS_NET_NAME" "TP_USB_ESD_AC3"
					( Origin gPackager )
				)
				( objectStatus "TP_USB_ESD_AC3" )
			)
			( signal "@baseboard_fab2_lib.baseboard_fab2(sch_1):tp_usb_esd_out2"
				( attribute "CDS_PHYS_NET_NAME" "TP_USB_ESD_OUT2"
					( Origin gPackager )
				)
				( objectStatus "TP_USB_ESD_OUT2" )
			)
			( signal "@baseboard_fab2_lib.baseboard_fab2(sch_1):tp_usb_esd_out3"
				( attribute "CDS_PHYS_NET_NAME" "TP_USB_ESD_OUT3"
					( Origin gPackager )
				)
				( objectStatus "TP_USB_ESD_OUT3" )
			)
			( signal "@baseboard_fab2_lib.baseboard_fab2(sch_1):usb2_p01_esd_dn"
				( attribute "CDS_PHYS_NET_NAME" "USB2_P01_ESD_DN"
					( Origin gPackager )
				)
				( objectStatus "USB2_P01_ESD_DN" )
			)
			( signal "@baseboard_fab2_lib.baseboard_fab2(sch_1):usb2_p01_esd_dp"
				( attribute "CDS_PHYS_NET_NAME" "USB2_P01_ESD_DP"
					( Origin gPackager )
				)
				( objectStatus "USB2_P01_ESD_DP" )
			)
			( signal "@baseboard_fab2_lib.baseboard_fab2(sch_1):fm_bmc_fault_led"
				( attribute "CDS_PHYS_NET_NAME" "FM_BMC_FAULT_LED"
					( Origin gPackager )
				)
				( objectStatus "FM_BMC_FAULT_LED" )
			)
			( signal "@baseboard_fab2_lib.baseboard_fab2(sch_1):fm_red_led_anode"
				( attribute "CDS_PHYS_NET_NAME" "FM_RED_LED_ANODE"
					( Origin gPackager )
				)
				( objectStatus "FM_RED_LED_ANODE" )
			)
			( signal "@baseboard_fab2_lib.baseboard_fab2(sch_1):fm_red_led_cathode"
				( attribute "CDS_PHYS_NET_NAME" "FM_RED_LED_CATHODE"
					( Origin gPackager )
				)
				( objectStatus "FM_RED_LED_CATHODE" )
			)
			( signal "@baseboard_fab2_lib.baseboard_fab2(sch_1):fp_led_hdd_activity_and_n"
				( attribute "CDS_PHYS_NET_NAME" "FP_LED_HDD_ACTIVITY_AND_N"
					( Origin gPackager )
				)
				( objectStatus "FP_LED_HDD_ACTIVITY_AND_N" )
			)
			( signal "@baseboard_fab2_lib.baseboard_fab2(sch_1):fp_led_hdd_activity_and_r_n"
				( attribute "CDS_PHYS_NET_NAME" "FP_LED_HDD_ACTIVITY_AND_R_N"
					( Origin gPackager )
				)
				( objectStatus "FP_LED_HDD_ACTIVITY_AND_R_N" )
			)
			( signal "@baseboard_fab2_lib.baseboard_fab2(sch_1):led_p5v_stby"
				( attribute "CDS_PHYS_NET_NAME" "LED_P5V_STBY"
					( Origin gPackager )
				)
				( objectStatus "LED_P5V_STBY" )
			)
			( signal "@baseboard_fab2_lib.baseboard_fab2(sch_1):led_sas_act_r_n"
				( attribute "CDS_PHYS_NET_NAME" "LED_SAS_ACT_R_N"
					( Origin gPackager )
				)
				( objectStatus "LED_SAS_ACT_R_N" )
			)
			( signal "@baseboard_fab2_lib.baseboard_fab2(sch_1):led_sata_act_r_n"
				( attribute "CDS_PHYS_NET_NAME" "LED_SATA_ACT_R_N"
					( Origin gPackager )
				)
				( objectStatus "LED_SATA_ACT_R_N" )
			)
			( signal "@baseboard_fab2_lib.baseboard_fab2(sch_1):fan_pwm_out_sys0_r1"
				( attribute "CDS_PHYS_NET_NAME" "FAN_PWM_OUT_SYS0_R1"
					( Origin gPackager )
				)
				( objectStatus "FAN_PWM_OUT_SYS0_R1" )
			)
			( signal "@baseboard_fab2_lib.baseboard_fab2(sch_1):fan_tach0_r"
				( attribute "CDS_PHYS_NET_NAME" "FAN_TACH0_R"
					( Origin gPackager )
				)
				( objectStatus "FAN_TACH0_R" )
			)
			( signal "@baseboard_fab2_lib.baseboard_fab2(sch_1):fan_tach1_r"
				( attribute "CDS_PHYS_NET_NAME" "FAN_TACH1_R"
					( Origin gPackager )
				)
				( objectStatus "FAN_TACH1_R" )
			)
			( signal "@baseboard_fab2_lib.baseboard_fab2(sch_1):fan_tach2_r"
				( attribute "CDS_PHYS_NET_NAME" "FAN_TACH2_R"
					( Origin gPackager )
				)
				( objectStatus "FAN_TACH2_R" )
			)
			( signal "@baseboard_fab2_lib.baseboard_fab2(sch_1):fan_tach3_r"
				( attribute "CDS_PHYS_NET_NAME" "FAN_TACH3_R"
					( Origin gPackager )
				)
				( objectStatus "FAN_TACH3_R" )
			)
			( signal "@baseboard_fab2_lib.baseboard_fab2(sch_1):fm_ctnr_ps_on_r"
				( attribute "CDS_PHYS_NET_NAME" "FM_CTNR_PS_ON_R"
					( Origin gPackager )
				)
				( objectStatus "FM_CTNR_PS_ON_R" )
			)
			( signal "@baseboard_fab2_lib.baseboard_fab2(sch_1):fm_mated_in_d1_n"
				( attribute "CDS_PHYS_NET_NAME" "FM_MATED_IN_D1_N"
					( Origin gPackager )
				)
				( objectStatus "FM_MATED_IN_D1_N" )
			)
			( signal "@baseboard_fab2_lib.baseboard_fab2(sch_1):fm_mated_in_d2_n"
				( attribute "CDS_PHYS_NET_NAME" "FM_MATED_IN_D2_N"
					( Origin gPackager )
				)
				( objectStatus "FM_MATED_IN_D2_N" )
			)
			( signal "@baseboard_fab2_lib.baseboard_fab2(sch_1):fm_mated_in_n"
				( attribute "CDS_PHYS_NET_NAME" "FM_MATED_IN_N"
					( Origin gPackager )
				)
				( objectStatus "FM_MATED_IN_N" )
			)
			( signal "@baseboard_fab2_lib.baseboard_fab2(sch_1):fm_p12v_hotswap0_en"
				( attribute "CDS_PHYS_NET_NAME" "FM_P12V_HOTSWAP0_EN"
					( Origin gPackager )
				)
				( objectStatus "FM_P12V_HOTSWAP0_EN" )
			)
			( signal "@baseboard_fab2_lib.baseboard_fab2(sch_1):fm_ps_en"
				( attribute "CDS_PHYS_NET_NAME" "FM_PS_EN"
					( Origin gPackager )
				)
				( objectStatus "FM_PS_EN" )
			)
			( signal "@baseboard_fab2_lib.baseboard_fab2(sch_1):irq_sml1_pmbus_alert_r_n"
				( attribute "CDS_PHYS_NET_NAME" "IRQ_SML1_PMBUS_ALERT_R_N"
					( Origin gPackager )
				)
				( objectStatus "IRQ_SML1_PMBUS_ALERT_R_N" )
			)
			( signal "@baseboard_fab2_lib.baseboard_fab2(sch_1):p12v_psu"
				( alias ( signalRef "@baseboard_fab2_lib.baseboard_fab2(sch_1):page181_p12v_psu") )
				( alias ( signalRef "@baseboard_fab2_lib.baseboard_fab2(sch_1):page195_p12v_psu") )
				( alias ( signalRef "@baseboard_fab2_lib.baseboard_fab2(sch_1):page199_p12v_psu") )
				( alias ( signalRef "@baseboard_fab2_lib.baseboard_fab2(sch_1):page200_p12v_psu") )
				( attribute "VOLTAGE" "12.0"
					( Units "uVoltage" "V" 1.000000)
					( Status sAliasFlattened )
					( Origin gFrontEnd )
				)
				( attribute "CDS_PHYS_NET_NAME" "P12V_PSU"
					( Origin gPackager )
				)
				( objectStatus "P12V_PSU" )
			)
			( signal "@baseboard_fab2_lib.baseboard_fab2(sch_1):page181_p12v_psu"
				( attribute "VOLTAGE" "12.0"
					( Units "uVoltage" "V" 1.000000)
					( Origin gFrontEnd )
				)
				( objectFlag fObjectAlias )
				( objectStatus "page181_p12v_psu" )
			)
			( signal "@baseboard_fab2_lib.baseboard_fab2(sch_1):page195_p12v_psu"
				( attribute "VOLTAGE" "12.0"
					( Units "uVoltage" "V" 1.000000)
					( Origin gFrontEnd )
				)
				( objectFlag fObjectAlias )
				( objectStatus "page195_p12v_psu" )
			)
			( signal "@baseboard_fab2_lib.baseboard_fab2(sch_1):page199_p12v_psu"
				( attribute "VOLTAGE" "12.0"
					( Units "uVoltage" "V" 1.000000)
					( Origin gFrontEnd )
				)
				( objectFlag fObjectAlias )
				( objectStatus "page199_p12v_psu" )
			)
			( signal "@baseboard_fab2_lib.baseboard_fab2(sch_1):page200_p12v_psu"
				( attribute "VOLTAGE" "12.0"
					( Units "uVoltage" "V" 1.000000)
					( Origin gFrontEnd )
				)
				( objectFlag fObjectAlias )
				( objectStatus "page200_p12v_psu" )
			)
			( signal "@baseboard_fab2_lib.baseboard_fab2(sch_1):p3e_cpu1_pe3_mp_c_txn(0)"
				( attribute "CDS_PHYS_NET_NAME" "P3E_CPU1_PE3_MP_C_TXN<0>"
					( Origin gPackager )
				)
				( attribute "PNN" "P3E_CPU1_PE3_MP_C_TXN<0>"
					( Origin gPackager )
				)
				( objectStatus "P3E_CPU1_PE3_MP_C_TXN<0>" )
			)
			( signal "@baseboard_fab2_lib.baseboard_fab2(sch_1):p3e_cpu1_pe3_mp_c_txn(1)"
				( attribute "CDS_PHYS_NET_NAME" "P3E_CPU1_PE3_MP_C_TXN<1>"
					( Origin gPackager )
				)
				( attribute "PNN" "P3E_CPU1_PE3_MP_C_TXN<1>"
					( Origin gPackager )
				)
				( objectStatus "P3E_CPU1_PE3_MP_C_TXN<1>" )
			)
			( signal "@baseboard_fab2_lib.baseboard_fab2(sch_1):p3e_cpu1_pe3_mp_c_txn(2)"
				( attribute "CDS_PHYS_NET_NAME" "P3E_CPU1_PE3_MP_C_TXN<2>"
					( Origin gPackager )
				)
				( attribute "PNN" "P3E_CPU1_PE3_MP_C_TXN<2>"
					( Origin gPackager )
				)
				( objectStatus "P3E_CPU1_PE3_MP_C_TXN<2>" )
			)
			( signal "@baseboard_fab2_lib.baseboard_fab2(sch_1):p3e_cpu1_pe3_mp_c_txn(3)"
				( attribute "CDS_PHYS_NET_NAME" "P3E_CPU1_PE3_MP_C_TXN<3>"
					( Origin gPackager )
				)
				( attribute "PNN" "P3E_CPU1_PE3_MP_C_TXN<3>"
					( Origin gPackager )
				)
				( objectStatus "P3E_CPU1_PE3_MP_C_TXN<3>" )
			)
			( signal "@baseboard_fab2_lib.baseboard_fab2(sch_1):p3e_cpu1_pe3_mp_c_txn(4)"
				( attribute "CDS_PHYS_NET_NAME" "P3E_CPU1_PE3_MP_C_TXN<4>"
					( Origin gPackager )
				)
				( attribute "PNN" "P3E_CPU1_PE3_MP_C_TXN<4>"
					( Origin gPackager )
				)
				( objectStatus "P3E_CPU1_PE3_MP_C_TXN<4>" )
			)
			( signal "@baseboard_fab2_lib.baseboard_fab2(sch_1):p3e_cpu1_pe3_mp_c_txn(5)"
				( attribute "CDS_PHYS_NET_NAME" "P3E_CPU1_PE3_MP_C_TXN<5>"
					( Origin gPackager )
				)
				( attribute "PNN" "P3E_CPU1_PE3_MP_C_TXN<5>"
					( Origin gPackager )
				)
				( objectStatus "P3E_CPU1_PE3_MP_C_TXN<5>" )
			)
			( signal "@baseboard_fab2_lib.baseboard_fab2(sch_1):p3e_cpu1_pe3_mp_c_txn(6)"
				( attribute "CDS_PHYS_NET_NAME" "P3E_CPU1_PE3_MP_C_TXN<6>"
					( Origin gPackager )
				)
				( attribute "PNN" "P3E_CPU1_PE3_MP_C_TXN<6>"
					( Origin gPackager )
				)
				( objectStatus "P3E_CPU1_PE3_MP_C_TXN<6>" )
			)
			( signal "@baseboard_fab2_lib.baseboard_fab2(sch_1):p3e_cpu1_pe3_mp_c_txn(7)"
				( attribute "CDS_PHYS_NET_NAME" "P3E_CPU1_PE3_MP_C_TXN<7>"
					( Origin gPackager )
				)
				( attribute "PNN" "P3E_CPU1_PE3_MP_C_TXN<7>"
					( Origin gPackager )
				)
				( objectStatus "P3E_CPU1_PE3_MP_C_TXN<7>" )
			)
			( signal "@baseboard_fab2_lib.baseboard_fab2(sch_1):p3e_cpu1_pe3_mp_c_txp(0)"
				( attribute "CDS_PHYS_NET_NAME" "P3E_CPU1_PE3_MP_C_TXP<0>"
					( Origin gPackager )
				)
				( attribute "PNN" "P3E_CPU1_PE3_MP_C_TXP<0>"
					( Origin gPackager )
				)
				( objectStatus "P3E_CPU1_PE3_MP_C_TXP<0>" )
			)
			( signal "@baseboard_fab2_lib.baseboard_fab2(sch_1):p3e_cpu1_pe3_mp_c_txp(1)"
				( attribute "CDS_PHYS_NET_NAME" "P3E_CPU1_PE3_MP_C_TXP<1>"
					( Origin gPackager )
				)
				( attribute "PNN" "P3E_CPU1_PE3_MP_C_TXP<1>"
					( Origin gPackager )
				)
				( objectStatus "P3E_CPU1_PE3_MP_C_TXP<1>" )
			)
			( signal "@baseboard_fab2_lib.baseboard_fab2(sch_1):p3e_cpu1_pe3_mp_c_txp(2)"
				( attribute "CDS_PHYS_NET_NAME" "P3E_CPU1_PE3_MP_C_TXP<2>"
					( Origin gPackager )
				)
				( attribute "PNN" "P3E_CPU1_PE3_MP_C_TXP<2>"
					( Origin gPackager )
				)
				( objectStatus "P3E_CPU1_PE3_MP_C_TXP<2>" )
			)
			( signal "@baseboard_fab2_lib.baseboard_fab2(sch_1):p3e_cpu1_pe3_mp_c_txp(3)"
				( attribute "CDS_PHYS_NET_NAME" "P3E_CPU1_PE3_MP_C_TXP<3>"
					( Origin gPackager )
				)
				( attribute "PNN" "P3E_CPU1_PE3_MP_C_TXP<3>"
					( Origin gPackager )
				)
				( objectStatus "P3E_CPU1_PE3_MP_C_TXP<3>" )
			)
			( signal "@baseboard_fab2_lib.baseboard_fab2(sch_1):p3e_cpu1_pe3_mp_c_txp(4)"
				( attribute "CDS_PHYS_NET_NAME" "P3E_CPU1_PE3_MP_C_TXP<4>"
					( Origin gPackager )
				)
				( attribute "PNN" "P3E_CPU1_PE3_MP_C_TXP<4>"
					( Origin gPackager )
				)
				( objectStatus "P3E_CPU1_PE3_MP_C_TXP<4>" )
			)
			( signal "@baseboard_fab2_lib.baseboard_fab2(sch_1):p3e_cpu1_pe3_mp_c_txp(5)"
				( attribute "CDS_PHYS_NET_NAME" "P3E_CPU1_PE3_MP_C_TXP<5>"
					( Origin gPackager )
				)
				( attribute "PNN" "P3E_CPU1_PE3_MP_C_TXP<5>"
					( Origin gPackager )
				)
				( objectStatus "P3E_CPU1_PE3_MP_C_TXP<5>" )
			)
			( signal "@baseboard_fab2_lib.baseboard_fab2(sch_1):p3e_cpu1_pe3_mp_c_txp(6)"
				( attribute "CDS_PHYS_NET_NAME" "P3E_CPU1_PE3_MP_C_TXP<6>"
					( Origin gPackager )
				)
				( attribute "PNN" "P3E_CPU1_PE3_MP_C_TXP<6>"
					( Origin gPackager )
				)
				( objectStatus "P3E_CPU1_PE3_MP_C_TXP<6>" )
			)
			( signal "@baseboard_fab2_lib.baseboard_fab2(sch_1):p3e_cpu1_pe3_mp_c_txp(7)"
				( attribute "CDS_PHYS_NET_NAME" "P3E_CPU1_PE3_MP_C_TXP<7>"
					( Origin gPackager )
				)
				( attribute "PNN" "P3E_CPU1_PE3_MP_C_TXP<7>"
					( Origin gPackager )
				)
				( objectStatus "P3E_CPU1_PE3_MP_C_TXP<7>" )
			)
			( signal "@baseboard_fab2_lib.baseboard_fab2(sch_1):pwrgd_p12v_hsc_dly"
				( attribute "CDS_PHYS_NET_NAME" "PWRGD_P12V_HSC_DLY"
					( Origin gPackager )
				)
				( objectStatus "PWRGD_P12V_HSC_DLY" )
			)
			( signal "@baseboard_fab2_lib.baseboard_fab2(sch_1):rst_pcie_midplane_n"
				( attribute "CDS_PHYS_NET_NAME" "RST_PCIE_MIDPLANE_N"
					( Origin gPackager )
				)
				( objectStatus "RST_PCIE_MIDPLANE_N" )
			)
			( signal "@baseboard_fab2_lib.baseboard_fab2(sch_1):spa_mid_dbg_rx_r"
				( attribute "CDS_PHYS_NET_NAME" "SPA_MID_DBG_RX_R"
					( Origin gPackager )
				)
				( objectStatus "SPA_MID_DBG_RX_R" )
			)
			( signal "@baseboard_fab2_lib.baseboard_fab2(sch_1):spa_mid_dbg_tx_r"
				( attribute "CDS_PHYS_NET_NAME" "SPA_MID_DBG_TX_R"
					( Origin gPackager )
				)
				( objectStatus "SPA_MID_DBG_TX_R" )
			)
			( signal "@baseboard_fab2_lib.baseboard_fab2(sch_1):p3e_cpu1_pe3_mp_c_txn(8)"
				( attribute "CDS_PHYS_NET_NAME" "P3E_CPU1_PE3_MP_C_TXN<8>"
					( Origin gPackager )
				)
				( attribute "PNN" "P3E_CPU1_PE3_MP_C_TXN<8>"
					( Origin gPackager )
				)
				( objectStatus "P3E_CPU1_PE3_MP_C_TXN<8>" )
			)
			( signal "@baseboard_fab2_lib.baseboard_fab2(sch_1):p3e_cpu1_pe3_mp_c_txn(9)"
				( attribute "CDS_PHYS_NET_NAME" "P3E_CPU1_PE3_MP_C_TXN<9>"
					( Origin gPackager )
				)
				( attribute "PNN" "P3E_CPU1_PE3_MP_C_TXN<9>"
					( Origin gPackager )
				)
				( objectStatus "P3E_CPU1_PE3_MP_C_TXN<9>" )
			)
			( signal "@baseboard_fab2_lib.baseboard_fab2(sch_1):p3e_cpu1_pe3_mp_c_txn(10)"
				( attribute "CDS_PHYS_NET_NAME" "P3E_CPU1_PE3_MP_C_TXN<10>"
					( Origin gPackager )
				)
				( attribute "PNN" "P3E_CPU1_PE3_MP_C_TXN<10>"
					( Origin gPackager )
				)
				( objectStatus "P3E_CPU1_PE3_MP_C_TXN<10>" )
			)
			( signal "@baseboard_fab2_lib.baseboard_fab2(sch_1):p3e_cpu1_pe3_mp_c_txn(11)"
				( attribute "CDS_PHYS_NET_NAME" "P3E_CPU1_PE3_MP_C_TXN<11>"
					( Origin gPackager )
				)
				( attribute "PNN" "P3E_CPU1_PE3_MP_C_TXN<11>"
					( Origin gPackager )
				)
				( objectStatus "P3E_CPU1_PE3_MP_C_TXN<11>" )
			)
			( signal "@baseboard_fab2_lib.baseboard_fab2(sch_1):p3e_cpu1_pe3_mp_c_txn(12)"
				( attribute "CDS_PHYS_NET_NAME" "P3E_CPU1_PE3_MP_C_TXN<12>"
					( Origin gPackager )
				)
				( attribute "PNN" "P3E_CPU1_PE3_MP_C_TXN<12>"
					( Origin gPackager )
				)
				( objectStatus "P3E_CPU1_PE3_MP_C_TXN<12>" )
			)
			( signal "@baseboard_fab2_lib.baseboard_fab2(sch_1):p3e_cpu1_pe3_mp_c_txn(13)"
				( attribute "CDS_PHYS_NET_NAME" "P3E_CPU1_PE3_MP_C_TXN<13>"
					( Origin gPackager )
				)
				( attribute "PNN" "P3E_CPU1_PE3_MP_C_TXN<13>"
					( Origin gPackager )
				)
				( objectStatus "P3E_CPU1_PE3_MP_C_TXN<13>" )
			)
			( signal "@baseboard_fab2_lib.baseboard_fab2(sch_1):p3e_cpu1_pe3_mp_c_txn(14)"
				( attribute "CDS_PHYS_NET_NAME" "P3E_CPU1_PE3_MP_C_TXN<14>"
					( Origin gPackager )
				)
				( attribute "PNN" "P3E_CPU1_PE3_MP_C_TXN<14>"
					( Origin gPackager )
				)
				( objectStatus "P3E_CPU1_PE3_MP_C_TXN<14>" )
			)
			( signal "@baseboard_fab2_lib.baseboard_fab2(sch_1):p3e_cpu1_pe3_mp_c_txn(15)"
				( attribute "CDS_PHYS_NET_NAME" "P3E_CPU1_PE3_MP_C_TXN<15>"
					( Origin gPackager )
				)
				( attribute "PNN" "P3E_CPU1_PE3_MP_C_TXN<15>"
					( Origin gPackager )
				)
				( objectStatus "P3E_CPU1_PE3_MP_C_TXN<15>" )
			)
			( signal "@baseboard_fab2_lib.baseboard_fab2(sch_1):p3e_cpu1_pe3_mp_c_txp(8)"
				( attribute "CDS_PHYS_NET_NAME" "P3E_CPU1_PE3_MP_C_TXP<8>"
					( Origin gPackager )
				)
				( attribute "PNN" "P3E_CPU1_PE3_MP_C_TXP<8>"
					( Origin gPackager )
				)
				( objectStatus "P3E_CPU1_PE3_MP_C_TXP<8>" )
			)
			( signal "@baseboard_fab2_lib.baseboard_fab2(sch_1):p3e_cpu1_pe3_mp_c_txp(9)"
				( attribute "CDS_PHYS_NET_NAME" "P3E_CPU1_PE3_MP_C_TXP<9>"
					( Origin gPackager )
				)
				( attribute "PNN" "P3E_CPU1_PE3_MP_C_TXP<9>"
					( Origin gPackager )
				)
				( objectStatus "P3E_CPU1_PE3_MP_C_TXP<9>" )
			)
			( signal "@baseboard_fab2_lib.baseboard_fab2(sch_1):p3e_cpu1_pe3_mp_c_txp(10)"
				( attribute "CDS_PHYS_NET_NAME" "P3E_CPU1_PE3_MP_C_TXP<10>"
					( Origin gPackager )
				)
				( attribute "PNN" "P3E_CPU1_PE3_MP_C_TXP<10>"
					( Origin gPackager )
				)
				( objectStatus "P3E_CPU1_PE3_MP_C_TXP<10>" )
			)
			( signal "@baseboard_fab2_lib.baseboard_fab2(sch_1):p3e_cpu1_pe3_mp_c_txp(11)"
				( attribute "CDS_PHYS_NET_NAME" "P3E_CPU1_PE3_MP_C_TXP<11>"
					( Origin gPackager )
				)
				( attribute "PNN" "P3E_CPU1_PE3_MP_C_TXP<11>"
					( Origin gPackager )
				)
				( objectStatus "P3E_CPU1_PE3_MP_C_TXP<11>" )
			)
			( signal "@baseboard_fab2_lib.baseboard_fab2(sch_1):p3e_cpu1_pe3_mp_c_txp(12)"
				( attribute "CDS_PHYS_NET_NAME" "P3E_CPU1_PE3_MP_C_TXP<12>"
					( Origin gPackager )
				)
				( attribute "PNN" "P3E_CPU1_PE3_MP_C_TXP<12>"
					( Origin gPackager )
				)
				( objectStatus "P3E_CPU1_PE3_MP_C_TXP<12>" )
			)
			( signal "@baseboard_fab2_lib.baseboard_fab2(sch_1):p3e_cpu1_pe3_mp_c_txp(13)"
				( attribute "CDS_PHYS_NET_NAME" "P3E_CPU1_PE3_MP_C_TXP<13>"
					( Origin gPackager )
				)
				( attribute "PNN" "P3E_CPU1_PE3_MP_C_TXP<13>"
					( Origin gPackager )
				)
				( objectStatus "P3E_CPU1_PE3_MP_C_TXP<13>" )
			)
			( signal "@baseboard_fab2_lib.baseboard_fab2(sch_1):p3e_cpu1_pe3_mp_c_txp(14)"
				( attribute "CDS_PHYS_NET_NAME" "P3E_CPU1_PE3_MP_C_TXP<14>"
					( Origin gPackager )
				)
				( attribute "PNN" "P3E_CPU1_PE3_MP_C_TXP<14>"
					( Origin gPackager )
				)
				( objectStatus "P3E_CPU1_PE3_MP_C_TXP<14>" )
			)
			( signal "@baseboard_fab2_lib.baseboard_fab2(sch_1):p3e_cpu1_pe3_mp_c_txp(15)"
				( attribute "CDS_PHYS_NET_NAME" "P3E_CPU1_PE3_MP_C_TXP<15>"
					( Origin gPackager )
				)
				( attribute "PNN" "P3E_CPU1_PE3_MP_C_TXP<15>"
					( Origin gPackager )
				)
				( objectStatus "P3E_CPU1_PE3_MP_C_TXP<15>" )
			)
			( signal "@baseboard_fab2_lib.baseboard_fab2(sch_1):tp_fm_wake_n"
				( attribute "CDS_PHYS_NET_NAME" "TP_FM_WAKE_N"
					( Origin gPackager )
				)
				( objectStatus "TP_FM_WAKE_N" )
			)
			( signal "@baseboard_fab2_lib.baseboard_fab2(sch_1):tp_ioa5"
				( attribute "CDS_PHYS_NET_NAME" "TP_IOA5"
					( Origin gPackager )
				)
				( objectStatus "TP_IOA5" )
			)
			( signal "@baseboard_fab2_lib.baseboard_fab2(sch_1):tp_ioe4"
				( attribute "CDS_PHYS_NET_NAME" "TP_IOE4"
					( Origin gPackager )
				)
				( objectStatus "TP_IOE4" )
			)
			( signal "@baseboard_fab2_lib.baseboard_fab2(sch_1):tp_iof4"
				( attribute "CDS_PHYS_NET_NAME" "TP_IOF4"
					( Origin gPackager )
				)
				( objectStatus "TP_IOF4" )
			)
			( signal "@baseboard_fab2_lib.baseboard_fab2(sch_1):tp_iog3"
				( attribute "CDS_PHYS_NET_NAME" "TP_IOG3"
					( Origin gPackager )
				)
				( objectStatus "TP_IOG3" )
			)
			( signal "@baseboard_fab2_lib.baseboard_fab2(sch_1):tp_ioh3"
				( attribute "CDS_PHYS_NET_NAME" "TP_IOH3"
					( Origin gPackager )
				)
				( objectStatus "TP_IOH3" )
			)
			( signal "@baseboard_fab2_lib.baseboard_fab2(sch_1):tp_ioh4"
				( attribute "CDS_PHYS_NET_NAME" "TP_IOH4"
					( Origin gPackager )
				)
				( objectStatus "TP_IOH4" )
			)
			( signal "@baseboard_fab2_lib.baseboard_fab2(sch_1):tp_ioi4"
				( attribute "CDS_PHYS_NET_NAME" "TP_IOI4"
					( Origin gPackager )
				)
				( objectStatus "TP_IOI4" )
			)
			( signal "@baseboard_fab2_lib.baseboard_fab2(sch_1):fm_pi7c9x1172_a0"
				( attribute "CDS_PHYS_NET_NAME" "FM_PI7C9X1172_A0"
					( Origin gPackager )
				)
				( objectStatus "FM_PI7C9X1172_A0" )
			)
			( signal "@baseboard_fab2_lib.baseboard_fab2(sch_1):fm_pi7c9x1172_a1"
				( attribute "CDS_PHYS_NET_NAME" "FM_PI7C9X1172_A1"
					( Origin gPackager )
				)
				( objectStatus "FM_PI7C9X1172_A1" )
			)
			( signal "@baseboard_fab2_lib.baseboard_fab2(sch_1):nc_pi7c9x1172_1"
				( attribute "CDS_PHYS_NET_NAME" "NC_PI7C9X1172_1"
					( Origin gPackager )
				)
				( objectStatus "NC_PI7C9X1172_1" )
			)
			( signal "@baseboard_fab2_lib.baseboard_fab2(sch_1):nc_pi7c9x1172_8"
				( attribute "CDS_PHYS_NET_NAME" "NC_PI7C9X1172_8"
					( Origin gPackager )
				)
				( objectStatus "NC_PI7C9X1172_8" )
			)
			( signal "@baseboard_fab2_lib.baseboard_fab2(sch_1):pu_pi7c9x1172_i2c_spi_n"
				( attribute "CDS_PHYS_NET_NAME" "PU_PI7C9X1172_I2C_SPI_N"
					( Origin gPackager )
				)
				( objectStatus "PU_PI7C9X1172_I2C_SPI_N" )
			)
			( signal "@baseboard_fab2_lib.baseboard_fab2(sch_1):sp1_host_bridge_uart_rx"
				( attribute "CDS_PHYS_NET_NAME" "SP1_HOST_BRIDGE_UART_RX"
					( Origin gPackager )
				)
				( objectStatus "SP1_HOST_BRIDGE_UART_RX" )
			)
			( signal "@baseboard_fab2_lib.baseboard_fab2(sch_1):sp1_host_bridge_uart_tx"
				( attribute "CDS_PHYS_NET_NAME" "SP1_HOST_BRIDGE_UART_TX"
					( Origin gPackager )
				)
				( objectStatus "SP1_HOST_BRIDGE_UART_TX" )
			)
			( signal "@baseboard_fab2_lib.baseboard_fab2(sch_1):tp_gpio0_dsrb_n"
				( attribute "CDS_PHYS_NET_NAME" "TP_GPIO0_DSRB_N"
					( Origin gPackager )
				)
				( objectStatus "TP_GPIO0_DSRB_N" )
			)
			( signal "@baseboard_fab2_lib.baseboard_fab2(sch_1):tp_gpio1_dtrb_n"
				( attribute "CDS_PHYS_NET_NAME" "TP_GPIO1_DTRB_N"
					( Origin gPackager )
				)
				( objectStatus "TP_GPIO1_DTRB_N" )
			)
			( signal "@baseboard_fab2_lib.baseboard_fab2(sch_1):tp_gpio2_cdb_n"
				( attribute "CDS_PHYS_NET_NAME" "TP_GPIO2_CDB_N"
					( Origin gPackager )
				)
				( objectStatus "TP_GPIO2_CDB_N" )
			)
			( signal "@baseboard_fab2_lib.baseboard_fab2(sch_1):tp_gpio3_rib_n"
				( attribute "CDS_PHYS_NET_NAME" "TP_GPIO3_RIB_N"
					( Origin gPackager )
				)
				( objectStatus "TP_GPIO3_RIB_N" )
			)
			( signal "@baseboard_fab2_lib.baseboard_fab2(sch_1):tp_gpio4_dsra_n"
				( attribute "CDS_PHYS_NET_NAME" "TP_GPIO4_DSRA_N"
					( Origin gPackager )
				)
				( objectStatus "TP_GPIO4_DSRA_N" )
			)
			( signal "@baseboard_fab2_lib.baseboard_fab2(sch_1):tp_gpio5_dtra_n"
				( attribute "CDS_PHYS_NET_NAME" "TP_GPIO5_DTRA_N"
					( Origin gPackager )
				)
				( objectStatus "TP_GPIO5_DTRA_N" )
			)
			( signal "@baseboard_fab2_lib.baseboard_fab2(sch_1):tp_gpio6_cda_n"
				( attribute "CDS_PHYS_NET_NAME" "TP_GPIO6_CDA_N"
					( Origin gPackager )
				)
				( objectStatus "TP_GPIO6_CDA_N" )
			)
			( signal "@baseboard_fab2_lib.baseboard_fab2(sch_1):tp_gpio7_ria_n"
				( attribute "CDS_PHYS_NET_NAME" "TP_GPIO7_RIA_N"
					( Origin gPackager )
				)
				( objectStatus "TP_GPIO7_RIA_N" )
			)
			( signal "@baseboard_fab2_lib.baseboard_fab2(sch_1):tp_pi7c9x1172_en485_n"
				( attribute "CDS_PHYS_NET_NAME" "TP_PI7C9X1172_EN485_N"
					( Origin gPackager )
				)
				( objectStatus "TP_PI7C9X1172_EN485_N" )
			)
			( signal "@baseboard_fab2_lib.baseboard_fab2(sch_1):tp_pi7c9x1172_enir_n"
				( attribute "CDS_PHYS_NET_NAME" "TP_PI7C9X1172_ENIR_N"
					( Origin gPackager )
				)
				( objectStatus "TP_PI7C9X1172_ENIR_N" )
			)
			( signal "@baseboard_fab2_lib.baseboard_fab2(sch_1):tp_pi7c9x1172_rtsa_n"
				( attribute "CDS_PHYS_NET_NAME" "TP_PI7C9X1172_RTSA_N"
					( Origin gPackager )
				)
				( objectStatus "TP_PI7C9X1172_RTSA_N" )
			)
			( signal "@baseboard_fab2_lib.baseboard_fab2(sch_1):tp_pi7c9x1172_rtsb_n"
				( attribute "CDS_PHYS_NET_NAME" "TP_PI7C9X1172_RTSB_N"
					( Origin gPackager )
				)
				( objectStatus "TP_PI7C9X1172_RTSB_N" )
			)
			( signal "@baseboard_fab2_lib.baseboard_fab2(sch_1):tp_pi7c9x1172_so"
				( attribute "CDS_PHYS_NET_NAME" "TP_PI7C9X1172_SO"
					( Origin gPackager )
				)
				( objectStatus "TP_PI7C9X1172_SO" )
			)
			( signal "@baseboard_fab2_lib.baseboard_fab2(sch_1):uart_bridge_rxd5"
				( attribute "CDS_PHYS_NET_NAME" "UART_BRIDGE_RXD5"
					( Origin gPackager )
				)
				( objectStatus "UART_BRIDGE_RXD5" )
			)
			( signal "@baseboard_fab2_lib.baseboard_fab2(sch_1):uart_bridge_txd5"
				( attribute "CDS_PHYS_NET_NAME" "UART_BRIDGE_TXD5"
					( Origin gPackager )
				)
				( objectStatus "UART_BRIDGE_TXD5" )
			)
			( signal "@baseboard_fab2_lib.baseboard_fab2(sch_1):xtal_24mhz_in_r"
				( attribute "CDS_PHYS_NET_NAME" "XTAL_24MHZ_IN_R"
					( Origin gPackager )
				)
				( objectStatus "XTAL_24MHZ_IN_R" )
			)
			( signal "@baseboard_fab2_lib.baseboard_fab2(sch_1):xtal_24mhz_out_r"
				( attribute "CDS_PHYS_NET_NAME" "XTAL_24MHZ_OUT_R"
					( Origin gPackager )
				)
				( objectStatus "XTAL_24MHZ_OUT_R" )
			)
			( signal "@baseboard_fab2_lib.baseboard_fab2(sch_1):xtal_24mhz_pi7c9x1172_in"
				( attribute "CDS_PHYS_NET_NAME" "XTAL_24MHZ_PI7C9X1172_IN"
					( Origin gPackager )
				)
				( objectStatus "XTAL_24MHZ_PI7C9X1172_IN" )
			)
			( signal "@baseboard_fab2_lib.baseboard_fab2(sch_1):xtal_24mhz_pi7c9x1172_out"
				( attribute "CDS_PHYS_NET_NAME" "XTAL_24MHZ_PI7C9X1172_OUT"
					( Origin gPackager )
				)
				( objectStatus "XTAL_24MHZ_PI7C9X1172_OUT" )
			)
			( signal "@baseboard_fab2_lib.baseboard_fab2(sch_1):irq_spi_tpm_n_r"
				( attribute "CDS_PHYS_NET_NAME" "IRQ_SPI_TPM_N_R"
					( Origin gPackager )
				)
				( objectStatus "IRQ_SPI_TPM_N_R" )
			)
			( signal "@baseboard_fab2_lib.baseboard_fab2(sch_1):spi_pch_tpm_clk_r"
				( attribute "CDS_PHYS_NET_NAME" "SPI_PCH_TPM_CLK_R"
					( Origin gPackager )
				)
				( objectStatus "SPI_PCH_TPM_CLK_R" )
			)
			( signal "@baseboard_fab2_lib.baseboard_fab2(sch_1):spi_pch_tpm_cs_r_n"
				( attribute "CDS_PHYS_NET_NAME" "SPI_PCH_TPM_CS_R_N"
					( Origin gPackager )
				)
				( objectStatus "SPI_PCH_TPM_CS_R_N" )
			)
			( signal "@baseboard_fab2_lib.baseboard_fab2(sch_1):spi_pch_tpm_miso_r"
				( attribute "CDS_PHYS_NET_NAME" "SPI_PCH_TPM_MISO_R"
					( Origin gPackager )
				)
				( objectStatus "SPI_PCH_TPM_MISO_R" )
			)
			( signal "@baseboard_fab2_lib.baseboard_fab2(sch_1):spi_pch_tpm_mosi_r"
				( attribute "CDS_PHYS_NET_NAME" "SPI_PCH_TPM_MOSI_R"
					( Origin gPackager )
				)
				( objectStatus "SPI_PCH_TPM_MOSI_R" )
			)
			( signal "@baseboard_fab2_lib.baseboard_fab2(sch_1):fm_m2_det_lvc3"
				( attribute "CDS_PHYS_NET_NAME" "FM_M2_DET_LVC3"
					( Origin gPackager )
				)
				( objectStatus "FM_M2_DET_LVC3" )
			)
			( signal "@baseboard_fab2_lib.baseboard_fab2(sch_1):fm_m2_ssd_pedet"
				( attribute "CDS_PHYS_NET_NAME" "FM_M2_SSD_PEDET"
					( Origin gPackager )
				)
				( objectStatus "FM_M2_SSD_PEDET" )
			)
			( signal "@baseboard_fab2_lib.baseboard_fab2(sch_1):nc_m2(0)"
				( attribute "CDS_PHYS_NET_NAME" "NC_M2<0>"
					( Origin gPackager )
				)
				( attribute "PNN" "NC_M2<0>"
					( Origin gPackager )
				)
				( objectStatus "NC_M2<0>" )
			)
			( signal "@baseboard_fab2_lib.baseboard_fab2(sch_1):nc_m2(1)"
				( attribute "CDS_PHYS_NET_NAME" "NC_M2<1>"
					( Origin gPackager )
				)
				( attribute "PNN" "NC_M2<1>"
					( Origin gPackager )
				)
				( objectStatus "NC_M2<1>" )
			)
			( signal "@baseboard_fab2_lib.baseboard_fab2(sch_1):nc_m2(2)"
				( attribute "CDS_PHYS_NET_NAME" "NC_M2<2>"
					( Origin gPackager )
				)
				( attribute "PNN" "NC_M2<2>"
					( Origin gPackager )
				)
				( objectStatus "NC_M2<2>" )
			)
			( signal "@baseboard_fab2_lib.baseboard_fab2(sch_1):nc_m2(3)"
				( attribute "CDS_PHYS_NET_NAME" "NC_M2<3>"
					( Origin gPackager )
				)
				( attribute "PNN" "NC_M2<3>"
					( Origin gPackager )
				)
				( objectStatus "NC_M2<3>" )
			)
			( signal "@baseboard_fab2_lib.baseboard_fab2(sch_1):nc_m2(4)"
				( attribute "CDS_PHYS_NET_NAME" "NC_M2<4>"
					( Origin gPackager )
				)
				( attribute "PNN" "NC_M2<4>"
					( Origin gPackager )
				)
				( objectStatus "NC_M2<4>" )
			)
			( signal "@baseboard_fab2_lib.baseboard_fab2(sch_1):nc_m2(5)"
				( attribute "CDS_PHYS_NET_NAME" "NC_M2<5>"
					( Origin gPackager )
				)
				( attribute "PNN" "NC_M2<5>"
					( Origin gPackager )
				)
				( objectStatus "NC_M2<5>" )
			)
			( signal "@baseboard_fab2_lib.baseboard_fab2(sch_1):nc_m2(6)"
				( attribute "CDS_PHYS_NET_NAME" "NC_M2<6>"
					( Origin gPackager )
				)
				( attribute "PNN" "NC_M2<6>"
					( Origin gPackager )
				)
				( objectStatus "NC_M2<6>" )
			)
			( signal "@baseboard_fab2_lib.baseboard_fab2(sch_1):nc_m2(7)"
				( attribute "CDS_PHYS_NET_NAME" "NC_M2<7>"
					( Origin gPackager )
				)
				( attribute "PNN" "NC_M2<7>"
					( Origin gPackager )
				)
				( objectStatus "NC_M2<7>" )
			)
			( signal "@baseboard_fab2_lib.baseboard_fab2(sch_1):nc_m2(8)"
				( attribute "CDS_PHYS_NET_NAME" "NC_M2<8>"
					( Origin gPackager )
				)
				( attribute "PNN" "NC_M2<8>"
					( Origin gPackager )
				)
				( objectStatus "NC_M2<8>" )
			)
			( signal "@baseboard_fab2_lib.baseboard_fab2(sch_1):nc_m2(9)"
				( attribute "CDS_PHYS_NET_NAME" "NC_M2<9>"
					( Origin gPackager )
				)
				( attribute "PNN" "NC_M2<9>"
					( Origin gPackager )
				)
				( objectStatus "NC_M2<9>" )
			)
			( signal "@baseboard_fab2_lib.baseboard_fab2(sch_1):nc_m2(10)"
				( attribute "CDS_PHYS_NET_NAME" "NC_M2<10>"
					( Origin gPackager )
				)
				( attribute "PNN" "NC_M2<10>"
					( Origin gPackager )
				)
				( objectStatus "NC_M2<10>" )
			)
			( signal "@baseboard_fab2_lib.baseboard_fab2(sch_1):nc_m2(11)"
				( attribute "CDS_PHYS_NET_NAME" "NC_M2<11>"
					( Origin gPackager )
				)
				( attribute "PNN" "NC_M2<11>"
					( Origin gPackager )
				)
				( objectStatus "NC_M2<11>" )
			)
			( signal "@baseboard_fab2_lib.baseboard_fab2(sch_1):nc_m2(12)"
				( attribute "CDS_PHYS_NET_NAME" "NC_M2<12>"
					( Origin gPackager )
				)
				( attribute "PNN" "NC_M2<12>"
					( Origin gPackager )
				)
				( objectStatus "NC_M2<12>" )
			)
			( signal "@baseboard_fab2_lib.baseboard_fab2(sch_1):nc_m2(13)"
				( attribute "CDS_PHYS_NET_NAME" "NC_M2<13>"
					( Origin gPackager )
				)
				( attribute "PNN" "NC_M2<13>"
					( Origin gPackager )
				)
				( objectStatus "NC_M2<13>" )
			)
			( signal "@baseboard_fab2_lib.baseboard_fab2(sch_1):nc_m2(14)"
				( attribute "CDS_PHYS_NET_NAME" "NC_M2<14>"
					( Origin gPackager )
				)
				( attribute "PNN" "NC_M2<14>"
					( Origin gPackager )
				)
				( objectStatus "NC_M2<14>" )
			)
			( signal "@baseboard_fab2_lib.baseboard_fab2(sch_1):nc_m2(15)"
				( attribute "CDS_PHYS_NET_NAME" "NC_M2<15>"
					( Origin gPackager )
				)
				( attribute "PNN" "NC_M2<15>"
					( Origin gPackager )
				)
				( objectStatus "NC_M2<15>" )
			)
			( signal "@baseboard_fab2_lib.baseboard_fab2(sch_1):nc_m2(16)"
				( attribute "CDS_PHYS_NET_NAME" "NC_M2<16>"
					( Origin gPackager )
				)
				( attribute "PNN" "NC_M2<16>"
					( Origin gPackager )
				)
				( objectStatus "NC_M2<16>" )
			)
			( signal "@baseboard_fab2_lib.baseboard_fab2(sch_1):nc_m2(17)"
				( attribute "CDS_PHYS_NET_NAME" "NC_M2<17>"
					( Origin gPackager )
				)
				( attribute "PNN" "NC_M2<17>"
					( Origin gPackager )
				)
				( objectStatus "NC_M2<17>" )
			)
			( signal "@baseboard_fab2_lib.baseboard_fab2(sch_1):nc_m2(18)"
				( attribute "CDS_PHYS_NET_NAME" "NC_M2<18>"
					( Origin gPackager )
				)
				( attribute "PNN" "NC_M2<18>"
					( Origin gPackager )
				)
				( objectStatus "NC_M2<18>" )
			)
			( signal "@baseboard_fab2_lib.baseboard_fab2(sch_1):p3e_pch_m2_sata6g_rx_r_dn"
				( attribute "CDS_PHYS_NET_NAME" "P3E_PCH_M2_SATA6G_RX_R_DN"
					( Origin gPackager )
				)
				( objectStatus "P3E_PCH_M2_SATA6G_RX_R_DN" )
			)
			( signal "@baseboard_fab2_lib.baseboard_fab2(sch_1):p3e_pch_m2_sata6g_rx_r_dp"
				( attribute "CDS_PHYS_NET_NAME" "P3E_PCH_M2_SATA6G_RX_R_DP"
					( Origin gPackager )
				)
				( objectStatus "P3E_PCH_M2_SATA6G_RX_R_DP" )
			)
			( signal "@baseboard_fab2_lib.baseboard_fab2(sch_1):p3e_pch_m2_sata6g_tx_r_dn"
				( attribute "CDS_PHYS_NET_NAME" "P3E_PCH_M2_SATA6G_TX_R_DN"
					( Origin gPackager )
				)
				( objectStatus "P3E_PCH_M2_SATA6G_TX_R_DN" )
			)
			( signal "@baseboard_fab2_lib.baseboard_fab2(sch_1):p3e_pch_m2_sata6g_tx_r_dp"
				( attribute "CDS_PHYS_NET_NAME" "P3E_PCH_M2_SATA6G_TX_R_DP"
					( Origin gPackager )
				)
				( objectStatus "P3E_PCH_M2_SATA6G_TX_R_DP" )
			)
			( signal "@baseboard_fab2_lib.baseboard_fab2(sch_1):p3e_pch_m2_tx_c_dn(1)"
				( attribute "CDS_PHYS_NET_NAME" "P3E_PCH_M2_TX_C_DN<1>"
					( Origin gPackager )
				)
				( attribute "PNN" "P3E_PCH_M2_TX_C_DN<1>"
					( Origin gPackager )
				)
				( objectStatus "P3E_PCH_M2_TX_C_DN<1>" )
			)
			( signal "@baseboard_fab2_lib.baseboard_fab2(sch_1):p3e_pch_m2_tx_c_dn(2)"
				( attribute "CDS_PHYS_NET_NAME" "P3E_PCH_M2_TX_C_DN<2>"
					( Origin gPackager )
				)
				( attribute "PNN" "P3E_PCH_M2_TX_C_DN<2>"
					( Origin gPackager )
				)
				( objectStatus "P3E_PCH_M2_TX_C_DN<2>" )
			)
			( signal "@baseboard_fab2_lib.baseboard_fab2(sch_1):p3e_pch_m2_tx_c_dn(3)"
				( attribute "CDS_PHYS_NET_NAME" "P3E_PCH_M2_TX_C_DN<3>"
					( Origin gPackager )
				)
				( attribute "PNN" "P3E_PCH_M2_TX_C_DN<3>"
					( Origin gPackager )
				)
				( objectStatus "P3E_PCH_M2_TX_C_DN<3>" )
			)
			( signal "@baseboard_fab2_lib.baseboard_fab2(sch_1):p3e_pch_m2_tx_c_dp(1)"
				( attribute "CDS_PHYS_NET_NAME" "P3E_PCH_M2_TX_C_DP<1>"
					( Origin gPackager )
				)
				( attribute "PNN" "P3E_PCH_M2_TX_C_DP<1>"
					( Origin gPackager )
				)
				( objectStatus "P3E_PCH_M2_TX_C_DP<1>" )
			)
			( signal "@baseboard_fab2_lib.baseboard_fab2(sch_1):p3e_pch_m2_tx_c_dp(2)"
				( attribute "CDS_PHYS_NET_NAME" "P3E_PCH_M2_TX_C_DP<2>"
					( Origin gPackager )
				)
				( attribute "PNN" "P3E_PCH_M2_TX_C_DP<2>"
					( Origin gPackager )
				)
				( objectStatus "P3E_PCH_M2_TX_C_DP<2>" )
			)
			( signal "@baseboard_fab2_lib.baseboard_fab2(sch_1):p3e_pch_m2_tx_c_dp(3)"
				( attribute "CDS_PHYS_NET_NAME" "P3E_PCH_M2_TX_C_DP<3>"
					( Origin gPackager )
				)
				( attribute "PNN" "P3E_PCH_M2_TX_C_DP<3>"
					( Origin gPackager )
				)
				( objectStatus "P3E_PCH_M2_TX_C_DP<3>" )
			)
			( signal "@baseboard_fab2_lib.baseboard_fab2(sch_1):pu_m2_clk_req_n"
				( attribute "CDS_PHYS_NET_NAME" "PU_M2_CLK_REQ_N"
					( Origin gPackager )
				)
				( objectStatus "PU_M2_CLK_REQ_N" )
			)
			( signal "@baseboard_fab2_lib.baseboard_fab2(sch_1):rst_pcie_m2_dev_n"
				( attribute "CDS_PHYS_NET_NAME" "RST_PCIE_M2_DEV_N"
					( Origin gPackager )
				)
				( objectStatus "RST_PCIE_M2_DEV_N" )
			)
			( signal "@baseboard_fab2_lib.baseboard_fab2(sch_1):tp_led_m2_act_n"
				( attribute "CDS_PHYS_NET_NAME" "TP_LED_M2_ACT_N"
					( Origin gPackager )
				)
				( objectStatus "TP_LED_M2_ACT_N" )
			)
			( signal "@baseboard_fab2_lib.baseboard_fab2(sch_1):tp_m2_32m_susclk"
				( attribute "CDS_PHYS_NET_NAME" "TP_M2_32M_SUSCLK"
					( Origin gPackager )
				)
				( objectStatus "TP_M2_32M_SUSCLK" )
			)
			( signal "@baseboard_fab2_lib.baseboard_fab2(sch_1):tp_m2_devslp"
				( attribute "CDS_PHYS_NET_NAME" "TP_M2_DEVSLP"
					( Origin gPackager )
				)
				( objectStatus "TP_M2_DEVSLP" )
			)
			( signal "@baseboard_fab2_lib.baseboard_fab2(sch_1):fm_mezza_prsnt1_n"
				( attribute "CDS_PHYS_NET_NAME" "FM_MEZZA_PRSNT1_N"
					( Origin gPackager )
				)
				( objectStatus "FM_MEZZA_PRSNT1_N" )
			)
			( signal "@baseboard_fab2_lib.baseboard_fab2(sch_1):rmii_bmc_ocp_crsdv_r"
				( attribute "CDS_PHYS_NET_NAME" "RMII_BMC_OCP_CRSDV_R"
					( Origin gPackager )
				)
				( objectStatus "RMII_BMC_OCP_CRSDV_R" )
			)
			( signal "@baseboard_fab2_lib.baseboard_fab2(sch_1):rmii_bmc_ocp_rxd0_r"
				( attribute "CDS_PHYS_NET_NAME" "RMII_BMC_OCP_RXD0_R"
					( Origin gPackager )
				)
				( objectStatus "RMII_BMC_OCP_RXD0_R" )
			)
			( signal "@baseboard_fab2_lib.baseboard_fab2(sch_1):rmii_bmc_ocp_rxd1_r"
				( attribute "CDS_PHYS_NET_NAME" "RMII_BMC_OCP_RXD1_R"
					( Origin gPackager )
				)
				( objectStatus "RMII_BMC_OCP_RXD1_R" )
			)
			( signal "@baseboard_fab2_lib.baseboard_fab2(sch_1):rmii_bmc_ocp_rxer_r"
				( attribute "CDS_PHYS_NET_NAME" "RMII_BMC_OCP_RXER_R"
					( Origin gPackager )
				)
				( objectStatus "RMII_BMC_OCP_RXER_R" )
			)
			( signal "@baseboard_fab2_lib.baseboard_fab2(sch_1):rst_pcie_cpu_dev0_n"
				( attribute "CDS_PHYS_NET_NAME" "RST_PCIE_CPU_DEV0_N"
					( Origin gPackager )
				)
				( objectStatus "RST_PCIE_CPU_DEV0_N" )
			)
			( signal "@baseboard_fab2_lib.baseboard_fab2(sch_1):rst_pcie_cpu_dev0_r_n"
				( attribute "CDS_PHYS_NET_NAME" "RST_PCIE_CPU_DEV0_R_N"
					( Origin gPackager )
				)
				( objectStatus "RST_PCIE_CPU_DEV0_R_N" )
			)
			( signal "@baseboard_fab2_lib.baseboard_fab2(sch_1):fm_mezz_prsntb1_n"
				( attribute "CDS_PHYS_NET_NAME" "FM_MEZZ_PRSNTB1_N"
					( Origin gPackager )
				)
				( objectStatus "FM_MEZZ_PRSNTB1_N" )
			)
			( signal "@baseboard_fab2_lib.baseboard_fab2(sch_1):rst_pcie_cpu_dev1_n"
				( attribute "CDS_PHYS_NET_NAME" "RST_PCIE_CPU_DEV1_N"
					( Origin gPackager )
				)
				( objectStatus "RST_PCIE_CPU_DEV1_N" )
			)
			( signal "@baseboard_fab2_lib.baseboard_fab2(sch_1):rst_pcie_cpu_dev1_r_n"
				( attribute "CDS_PHYS_NET_NAME" "RST_PCIE_CPU_DEV1_R_N"
					( Origin gPackager )
				)
				( objectStatus "RST_PCIE_CPU_DEV1_R_N" )
			)
			( signal "@baseboard_fab2_lib.baseboard_fab2(sch_1):rst_pcie_cpu_dev2_n"
				( attribute "CDS_PHYS_NET_NAME" "RST_PCIE_CPU_DEV2_N"
					( Origin gPackager )
				)
				( objectStatus "RST_PCIE_CPU_DEV2_N" )
			)
			( signal "@baseboard_fab2_lib.baseboard_fab2(sch_1):rst_pcie_cpu_dev2_r_n"
				( attribute "CDS_PHYS_NET_NAME" "RST_PCIE_CPU_DEV2_R_N"
					( Origin gPackager )
				)
				( objectStatus "RST_PCIE_CPU_DEV2_R_N" )
			)
			( signal "@baseboard_fab2_lib.baseboard_fab2(sch_1):rst_pcie_cpu_dev3_n"
				( attribute "CDS_PHYS_NET_NAME" "RST_PCIE_CPU_DEV3_N"
					( Origin gPackager )
				)
				( objectStatus "RST_PCIE_CPU_DEV3_N" )
			)
			( signal "@baseboard_fab2_lib.baseboard_fab2(sch_1):rst_pcie_cpu_dev3_r_n"
				( attribute "CDS_PHYS_NET_NAME" "RST_PCIE_CPU_DEV3_R_N"
					( Origin gPackager )
				)
				( objectStatus "RST_PCIE_CPU_DEV3_R_N" )
			)
			( signal "@baseboard_fab2_lib.baseboard_fab2(sch_1):tp_rsvd_b1"
				( attribute "CDS_PHYS_NET_NAME" "TP_RSVD_B1"
					( Origin gPackager )
				)
				( objectStatus "TP_RSVD_B1" )
			)
			( signal "@baseboard_fab2_lib.baseboard_fab2(sch_1):kr_p0_ocp_rx_dn"
				( attribute "CDS_PHYS_NET_NAME" "KR_P0_OCP_RX_DN"
					( Origin gPackager )
				)
				( objectStatus "KR_P0_OCP_RX_DN" )
			)
			( signal "@baseboard_fab2_lib.baseboard_fab2(sch_1):kr_p0_ocp_rx_dp"
				( attribute "CDS_PHYS_NET_NAME" "KR_P0_OCP_RX_DP"
					( Origin gPackager )
				)
				( objectStatus "KR_P0_OCP_RX_DP" )
			)
			( signal "@baseboard_fab2_lib.baseboard_fab2(sch_1):kr_p1_ocp_rx_dn"
				( attribute "CDS_PHYS_NET_NAME" "KR_P1_OCP_RX_DN"
					( Origin gPackager )
				)
				( objectStatus "KR_P1_OCP_RX_DN" )
			)
			( signal "@baseboard_fab2_lib.baseboard_fab2(sch_1):kr_p1_ocp_rx_dp"
				( attribute "CDS_PHYS_NET_NAME" "KR_P1_OCP_RX_DP"
					( Origin gPackager )
				)
				( objectStatus "KR_P1_OCP_RX_DP" )
			)
			( signal "@baseboard_fab2_lib.baseboard_fab2(sch_1):kr_p2_ocp_rx_dn"
				( attribute "CDS_PHYS_NET_NAME" "KR_P2_OCP_RX_DN"
					( Origin gPackager )
				)
				( objectStatus "KR_P2_OCP_RX_DN" )
			)
			( signal "@baseboard_fab2_lib.baseboard_fab2(sch_1):kr_p2_ocp_rx_dp"
				( attribute "CDS_PHYS_NET_NAME" "KR_P2_OCP_RX_DP"
					( Origin gPackager )
				)
				( objectStatus "KR_P2_OCP_RX_DP" )
			)
			( signal "@baseboard_fab2_lib.baseboard_fab2(sch_1):kr_p3_ocp_rx_dn"
				( attribute "CDS_PHYS_NET_NAME" "KR_P3_OCP_RX_DN"
					( Origin gPackager )
				)
				( objectStatus "KR_P3_OCP_RX_DN" )
			)
			( signal "@baseboard_fab2_lib.baseboard_fab2(sch_1):kr_p3_ocp_rx_dp"
				( attribute "CDS_PHYS_NET_NAME" "KR_P3_OCP_RX_DP"
					( Origin gPackager )
				)
				( objectStatus "KR_P3_OCP_RX_DP" )
			)
			( signal "@baseboard_fab2_lib.baseboard_fab2(sch_1):tp_ext_mdio_i2c_sel"
				( attribute "CDS_PHYS_NET_NAME" "TP_EXT_MDIO_I2C_SEL"
					( Origin gPackager )
				)
				( objectStatus "TP_EXT_MDIO_I2C_SEL" )
			)
			( signal "@baseboard_fab2_lib.baseboard_fab2(sch_1):tp_rsvd(0)"
				( attribute "CDS_PHYS_NET_NAME" "TP_RSVD<0>"
					( Origin gPackager )
				)
				( attribute "PNN" "TP_RSVD<0>"
					( Origin gPackager )
				)
				( objectStatus "TP_RSVD<0>" )
			)
			( signal "@baseboard_fab2_lib.baseboard_fab2(sch_1):tp_shared_kr_mdc_0"
				( attribute "CDS_PHYS_NET_NAME" "TP_SHARED_KR_MDC_0"
					( Origin gPackager )
				)
				( objectStatus "TP_SHARED_KR_MDC_0" )
			)
			( signal "@baseboard_fab2_lib.baseboard_fab2(sch_1):tp_shared_kr_mdio_0"
				( attribute "CDS_PHYS_NET_NAME" "TP_SHARED_KR_MDIO_0"
					( Origin gPackager )
				)
				( objectStatus "TP_SHARED_KR_MDIO_0" )
			)
			( signal "@baseboard_fab2_lib.baseboard_fab2(sch_1):fm_jtag_pld_en_debug"
				( attribute "CDS_PHYS_NET_NAME" "FM_JTAG_PLD_EN_DEBUG"
					( Origin gPackager )
				)
				( objectStatus "FM_JTAG_PLD_EN_DEBUG" )
			)
			( signal "@baseboard_fab2_lib.baseboard_fab2(sch_1):jtag_pld_tck"
				( attribute "CDS_PHYS_NET_NAME" "JTAG_PLD_TCK"
					( Origin gPackager )
				)
				( objectStatus "JTAG_PLD_TCK" )
			)
			( signal "@baseboard_fab2_lib.baseboard_fab2(sch_1):jtag_pld_tdi"
				( attribute "CDS_PHYS_NET_NAME" "JTAG_PLD_TDI"
					( Origin gPackager )
				)
				( objectStatus "JTAG_PLD_TDI" )
			)
			( signal "@baseboard_fab2_lib.baseboard_fab2(sch_1):jtag_pld_tdo"
				( attribute "CDS_PHYS_NET_NAME" "JTAG_PLD_TDO"
					( Origin gPackager )
				)
				( objectStatus "JTAG_PLD_TDO" )
			)
			( signal "@baseboard_fab2_lib.baseboard_fab2(sch_1):jtag_pld_tms"
				( attribute "CDS_PHYS_NET_NAME" "JTAG_PLD_TMS"
					( Origin gPackager )
				)
				( objectStatus "JTAG_PLD_TMS" )
			)
			( signal "@baseboard_fab2_lib.baseboard_fab2(sch_1):jtag_tck"
				( attribute "CDS_PHYS_NET_NAME" "JTAG_TCK"
					( Origin gPackager )
				)
				( objectStatus "JTAG_TCK" )
			)
			( signal "@baseboard_fab2_lib.baseboard_fab2(sch_1):jtag_tck_r"
				( attribute "CDS_PHYS_NET_NAME" "JTAG_TCK_R"
					( Origin gPackager )
				)
				( objectStatus "JTAG_TCK_R" )
			)
			( signal "@baseboard_fab2_lib.baseboard_fab2(sch_1):jtag_tdi"
				( attribute "CDS_PHYS_NET_NAME" "JTAG_TDI"
					( Origin gPackager )
				)
				( objectStatus "JTAG_TDI" )
			)
			( signal "@baseboard_fab2_lib.baseboard_fab2(sch_1):jtag_tdi_r"
				( attribute "CDS_PHYS_NET_NAME" "JTAG_TDI_R"
					( Origin gPackager )
				)
				( objectStatus "JTAG_TDI_R" )
			)
			( signal "@baseboard_fab2_lib.baseboard_fab2(sch_1):jtag_tdo"
				( attribute "CDS_PHYS_NET_NAME" "JTAG_TDO"
					( Origin gPackager )
				)
				( objectStatus "JTAG_TDO" )
			)
			( signal "@baseboard_fab2_lib.baseboard_fab2(sch_1):jtag_tdo_r"
				( attribute "CDS_PHYS_NET_NAME" "JTAG_TDO_R"
					( Origin gPackager )
				)
				( objectStatus "JTAG_TDO_R" )
			)
			( signal "@baseboard_fab2_lib.baseboard_fab2(sch_1):jtag_tms"
				( attribute "CDS_PHYS_NET_NAME" "JTAG_TMS"
					( Origin gPackager )
				)
				( objectStatus "JTAG_TMS" )
			)
			( signal "@baseboard_fab2_lib.baseboard_fab2(sch_1):jtag_tms_r"
				( attribute "CDS_PHYS_NET_NAME" "JTAG_TMS_R"
					( Origin gPackager )
				)
				( objectStatus "JTAG_TMS_R" )
			)
			( signal "@baseboard_fab2_lib.baseboard_fab2(sch_1):jtag_trst_n"
				( attribute "CDS_PHYS_NET_NAME" "JTAG_TRST_N"
					( Origin gPackager )
				)
				( objectStatus "JTAG_TRST_N" )
			)
			( signal "@baseboard_fab2_lib.baseboard_fab2(sch_1):p3v3_stby_pld_d"
				( alias ( signalRef "@baseboard_fab2_lib.baseboard_fab2(sch_1):page189_p3v3_stby_pld_d") )
				( attribute "VOLTAGE" "3.3"
					( Units "uVoltage" "V" 1.000000)
					( Status sAliasFlattened )
					( Origin gFrontEnd )
				)
				( attribute "CDS_PHYS_NET_NAME" "P3V3_STBY_PLD_D"
					( Origin gPackager )
				)
				( objectStatus "P3V3_STBY_PLD_D" )
			)
			( signal "@baseboard_fab2_lib.baseboard_fab2(sch_1):page189_p3v3_stby_pld_d"
				( attribute "VOLTAGE" "3.3"
					( Units "uVoltage" "V" 1.000000)
					( Origin gFrontEnd )
				)
				( objectFlag fObjectAlias )
				( objectStatus "page189_p3v3_stby_pld_d" )
			)
			( signal "@baseboard_fab2_lib.baseboard_fab2(sch_1):fm_mem_event_func"
				( attribute "CDS_PHYS_NET_NAME" "FM_MEM_EVENT_FUNC"
					( Origin gPackager )
				)
				( objectStatus "FM_MEM_EVENT_FUNC" )
			)
			( signal "@baseboard_fab2_lib.baseboard_fab2(sch_1):fm_pvccio_cpu0_en"
				( attribute "CDS_PHYS_NET_NAME" "FM_PVCCIO_CPU0_EN"
					( Origin gPackager )
				)
				( objectStatus "FM_PVCCIO_CPU0_EN" )
			)
			( signal "@baseboard_fab2_lib.baseboard_fab2(sch_1):fm_pvccio_cpu1_en"
				( attribute "CDS_PHYS_NET_NAME" "FM_PVCCIO_CPU1_EN"
					( Origin gPackager )
				)
				( objectStatus "FM_PVCCIO_CPU1_EN" )
			)
			( signal "@baseboard_fab2_lib.baseboard_fab2(sch_1):fm_pvcciomcp_cpu0_en"
				( attribute "CDS_PHYS_NET_NAME" "FM_PVCCIOMCP_CPU0_EN"
					( Origin gPackager )
				)
				( objectStatus "FM_PVCCIOMCP_CPU0_EN" )
			)
			( signal "@baseboard_fab2_lib.baseboard_fab2(sch_1):fm_pvcciomcp_cpu1_en"
				( attribute "CDS_PHYS_NET_NAME" "FM_PVCCIOMCP_CPU1_EN"
					( Origin gPackager )
				)
				( objectStatus "FM_PVCCIOMCP_CPU1_EN" )
			)
			( signal "@baseboard_fab2_lib.baseboard_fab2(sch_1):fm_pvccmcp_cpu0_en"
				( attribute "CDS_PHYS_NET_NAME" "FM_PVCCMCP_CPU0_EN"
					( Origin gPackager )
				)
				( objectStatus "FM_PVCCMCP_CPU0_EN" )
			)
			( signal "@baseboard_fab2_lib.baseboard_fab2(sch_1):fm_pvccmcp_cpu1_en"
				( attribute "CDS_PHYS_NET_NAME" "FM_PVCCMCP_CPU1_EN"
					( Origin gPackager )
				)
				( objectStatus "FM_PVCCMCP_CPU1_EN" )
			)
			( signal "@baseboard_fab2_lib.baseboard_fab2(sch_1):pu_rst_perst_bit0"
				( attribute "CDS_PHYS_NET_NAME" "PU_RST_PERST_BIT0"
					( Origin gPackager )
				)
				( objectStatus "PU_RST_PERST_BIT0" )
			)
			( signal "@baseboard_fab2_lib.baseboard_fab2(sch_1):pwrgd_p5v"
				( attribute "CDS_PHYS_NET_NAME" "PWRGD_P5V"
					( Origin gPackager )
				)
				( objectStatus "PWRGD_P5V" )
			)
			( signal "@baseboard_fab2_lib.baseboard_fab2(sch_1):pwrgd_pvccin_cpu1"
				( attribute "CDS_PHYS_NET_NAME" "PWRGD_PVCCIN_CPU1"
					( Origin gPackager )
				)
				( objectStatus "PWRGD_PVCCIN_CPU1" )
			)
			( signal "@baseboard_fab2_lib.baseboard_fab2(sch_1):pwrgd_pvcciomcp_cpu0"
				( attribute "CDS_PHYS_NET_NAME" "PWRGD_PVCCIOMCP_CPU0"
					( Origin gPackager )
				)
				( objectStatus "PWRGD_PVCCIOMCP_CPU0" )
			)
			( signal "@baseboard_fab2_lib.baseboard_fab2(sch_1):pwrgd_pvcciomcp_cpu1"
				( attribute "CDS_PHYS_NET_NAME" "PWRGD_PVCCIOMCP_CPU1"
					( Origin gPackager )
				)
				( objectStatus "PWRGD_PVCCIOMCP_CPU1" )
			)
			( signal "@baseboard_fab2_lib.baseboard_fab2(sch_1):pwrgd_pvccmcp_cpu0"
				( attribute "CDS_PHYS_NET_NAME" "PWRGD_PVCCMCP_CPU0"
					( Origin gPackager )
				)
				( objectStatus "PWRGD_PVCCMCP_CPU0" )
			)
			( signal "@baseboard_fab2_lib.baseboard_fab2(sch_1):pwrgd_pvccmcp_cpu1"
				( attribute "CDS_PHYS_NET_NAME" "PWRGD_PVCCMCP_CPU1"
					( Origin gPackager )
				)
				( objectStatus "PWRGD_PVCCMCP_CPU1" )
			)
			( signal "@baseboard_fab2_lib.baseboard_fab2(sch_1):pwrgd_pvnn_p1v05_pch"
				( attribute "CDS_PHYS_NET_NAME" "PWRGD_PVNN_P1V05_PCH"
					( Origin gPackager )
				)
				( objectStatus "PWRGD_PVNN_P1V05_PCH" )
			)
			( signal "@baseboard_fab2_lib.baseboard_fab2(sch_1):pwrgd_pvpp_def"
				( attribute "CDS_PHYS_NET_NAME" "PWRGD_PVPP_DEF"
					( Origin gPackager )
				)
				( objectStatus "PWRGD_PVPP_DEF" )
			)
			( signal "@baseboard_fab2_lib.baseboard_fab2(sch_1):pwrgd_pvpp_ghj"
				( attribute "CDS_PHYS_NET_NAME" "PWRGD_PVPP_GHJ"
					( Origin gPackager )
				)
				( objectStatus "PWRGD_PVPP_GHJ" )
			)
			( signal "@baseboard_fab2_lib.baseboard_fab2(sch_1):pwrgd_pvpp_klm"
				( attribute "CDS_PHYS_NET_NAME" "PWRGD_PVPP_KLM"
					( Origin gPackager )
				)
				( objectStatus "PWRGD_PVPP_KLM" )
			)
			( signal "@baseboard_fab2_lib.baseboard_fab2(sch_1):pwrgd_pvsa_cpu0"
				( attribute "CDS_PHYS_NET_NAME" "PWRGD_PVSA_CPU0"
					( Origin gPackager )
				)
				( objectStatus "PWRGD_PVSA_CPU0" )
			)
			( signal "@baseboard_fab2_lib.baseboard_fab2(sch_1):pwrgd_pvsa_cpu1"
				( attribute "CDS_PHYS_NET_NAME" "PWRGD_PVSA_CPU1"
					( Origin gPackager )
				)
				( objectStatus "PWRGD_PVSA_CPU1" )
			)
			( signal "@baseboard_fab2_lib.baseboard_fab2(sch_1):pwrgd_pvtt_cpu1"
				( attribute "CDS_PHYS_NET_NAME" "PWRGD_PVTT_CPU1"
					( Origin gPackager )
				)
				( objectStatus "PWRGD_PVTT_CPU1" )
			)
			( signal "@baseboard_fab2_lib.baseboard_fab2(sch_1):rst_cpu0_lvc3_r1_n"
				( attribute "CDS_PHYS_NET_NAME" "RST_CPU0_LVC3_R1_N"
					( Origin gPackager )
				)
				( objectStatus "RST_CPU0_LVC3_R1_N" )
			)
			( signal "@baseboard_fab2_lib.baseboard_fab2(sch_1):rst_cpu1_lvc3_r1_n"
				( attribute "CDS_PHYS_NET_NAME" "RST_CPU1_LVC3_R1_N"
					( Origin gPackager )
				)
				( objectStatus "RST_CPU1_LVC3_R1_N" )
			)
			( signal "@baseboard_fab2_lib.baseboard_fab2(sch_1):rst_rsmrst_r_n"
				( attribute "CDS_PHYS_NET_NAME" "RST_RSMRST_R_N"
					( Origin gPackager )
				)
				( objectStatus "RST_RSMRST_R_N" )
			)
			( signal "@baseboard_fab2_lib.baseboard_fab2(sch_1):tp_cpld1_pb11b_pclkc2_0"
				( attribute "CDS_PHYS_NET_NAME" "TP_CPLD1_PB11B_PCLKC2_0"
					( Origin gPackager )
				)
				( objectStatus "TP_CPLD1_PB11B_PCLKC2_0" )
			)
			( signal "@baseboard_fab2_lib.baseboard_fab2(sch_1):tp_cpld1_pb16a_pclkt2_1"
				( attribute "CDS_PHYS_NET_NAME" "TP_CPLD1_PB16A_PCLKT2_1"
					( Origin gPackager )
				)
				( objectStatus "TP_CPLD1_PB16A_PCLKT2_1" )
			)
			( signal "@baseboard_fab2_lib.baseboard_fab2(sch_1):tp_cpld1_pb16b_pclkc2_1"
				( attribute "CDS_PHYS_NET_NAME" "TP_CPLD1_PB16B_PCLKC2_1"
					( Origin gPackager )
				)
				( objectStatus "TP_CPLD1_PB16B_PCLKC2_1" )
			)
			( signal "@baseboard_fab2_lib.baseboard_fab2(sch_1):tp_cpld1_pb25b_si_sispi"
				( attribute "CDS_PHYS_NET_NAME" "TP_CPLD1_PB25B_SI_SISPI"
					( Origin gPackager )
				)
				( objectStatus "TP_CPLD1_PB25B_SI_SISPI" )
			)
			( signal "@baseboard_fab2_lib.baseboard_fab2(sch_1):tp_cpld1_pb5a_csspin"
				( attribute "CDS_PHYS_NET_NAME" "TP_CPLD1_PB5A_CSSPIN"
					( Origin gPackager )
				)
				( objectStatus "TP_CPLD1_PB5A_CSSPIN" )
			)
			( signal "@baseboard_fab2_lib.baseboard_fab2(sch_1):tp_cpld1_pb8a_mclk_cclk"
				( attribute "CDS_PHYS_NET_NAME" "TP_CPLD1_PB8A_MCLK_CCLK"
					( Origin gPackager )
				)
				( objectStatus "TP_CPLD1_PB8A_MCLK_CCLK" )
			)
			( signal "@baseboard_fab2_lib.baseboard_fab2(sch_1):tp_cpld1_pb8b_so_spiso"
				( attribute "CDS_PHYS_NET_NAME" "TP_CPLD1_PB8B_SO_SPISO"
					( Origin gPackager )
				)
				( objectStatus "TP_CPLD1_PB8B_SO_SPISO" )
			)
			( signal "@baseboard_fab2_lib.baseboard_fab2(sch_1):tp_cpld1_pb8d"
				( attribute "CDS_PHYS_NET_NAME" "TP_CPLD1_PB8D"
					( Origin gPackager )
				)
				( objectStatus "TP_CPLD1_PB8D" )
			)
			( signal "@baseboard_fab2_lib.baseboard_fab2(sch_1):tp_cpld1_pl11a"
				( attribute "CDS_PHYS_NET_NAME" "TP_CPLD1_PL11A"
					( Origin gPackager )
				)
				( objectStatus "TP_CPLD1_PL11A" )
			)
			( signal "@baseboard_fab2_lib.baseboard_fab2(sch_1):tp_cpld1_pl1a_l_gpllt_fb"
				( attribute "CDS_PHYS_NET_NAME" "TP_CPLD1_PL1A_L_GPLLT_FB"
					( Origin gPackager )
				)
				( objectStatus "TP_CPLD1_PL1A_L_GPLLT_FB" )
			)
			( signal "@baseboard_fab2_lib.baseboard_fab2(sch_1):tp_cpld1_pl1b_l_gpllc_fb"
				( attribute "CDS_PHYS_NET_NAME" "TP_CPLD1_PL1B_L_GPLLC_FB"
					( Origin gPackager )
				)
				( objectStatus "TP_CPLD1_PL1B_L_GPLLC_FB" )
			)
			( signal "@baseboard_fab2_lib.baseboard_fab2(sch_1):tp_cpld1_pl2b_l_gpllc_in"
				( attribute "CDS_PHYS_NET_NAME" "TP_CPLD1_PL2B_L_GPLLC_IN"
					( Origin gPackager )
				)
				( objectStatus "TP_CPLD1_PL2B_L_GPLLC_IN" )
			)
			( signal "@baseboard_fab2_lib.baseboard_fab2(sch_1):tp_cpld1_pl7d_pclkt4_0"
				( attribute "CDS_PHYS_NET_NAME" "TP_CPLD1_PL7D_PCLKT4_0"
					( Origin gPackager )
				)
				( objectStatus "TP_CPLD1_PL7D_PCLKT4_0" )
			)
			( signal "@baseboard_fab2_lib.baseboard_fab2(sch_1):fm_adr_smi_gpio_r_n"
				( attribute "CDS_PHYS_NET_NAME" "FM_ADR_SMI_GPIO_R_N"
					( Origin gPackager )
				)
				( objectStatus "FM_ADR_SMI_GPIO_R_N" )
			)
			( signal "@baseboard_fab2_lib.baseboard_fab2(sch_1):fm_p12v_main_sw_en"
				( attribute "CDS_PHYS_NET_NAME" "FM_P12V_MAIN_SW_EN"
					( Origin gPackager )
				)
				( objectStatus "FM_P12V_MAIN_SW_EN" )
			)
			( signal "@baseboard_fab2_lib.baseboard_fab2(sch_1):fm_p1v8mcp_cpu0_en"
				( attribute "CDS_PHYS_NET_NAME" "FM_P1V8MCP_CPU0_EN"
					( Origin gPackager )
				)
				( objectStatus "FM_P1V8MCP_CPU0_EN" )
			)
			( signal "@baseboard_fab2_lib.baseboard_fab2(sch_1):fm_p1v8mcp_cpu1_en"
				( attribute "CDS_PHYS_NET_NAME" "FM_P1V8MCP_CPU1_EN"
					( Origin gPackager )
				)
				( objectStatus "FM_P1V8MCP_CPU1_EN" )
			)
			( signal "@baseboard_fab2_lib.baseboard_fab2(sch_1):fm_p3v3_cpld_en"
				( attribute "CDS_PHYS_NET_NAME" "FM_P3V3_CPLD_EN"
					( Origin gPackager )
				)
				( objectStatus "FM_P3V3_CPLD_EN" )
			)
			( signal "@baseboard_fab2_lib.baseboard_fab2(sch_1):fm_pld_debug_mode_n"
				( attribute "CDS_PHYS_NET_NAME" "FM_PLD_DEBUG_MODE_N"
					( Origin gPackager )
				)
				( objectStatus "FM_PLD_DEBUG_MODE_N" )
			)
			( signal "@baseboard_fab2_lib.baseboard_fab2(sch_1):fm_pvccin_pvccsa_cpu0_en_lvc1"
				( attribute "CDS_PHYS_NET_NAME" "FM_PVCCIN_PVCCSA_CPU0_EN_LVC1"
					( Origin gPackager )
				)
				( objectStatus "FM_PVCCIN_PVCCSA_CPU0_EN_LVC1" )
			)
			( signal "@baseboard_fab2_lib.baseboard_fab2(sch_1):fm_pvccin_pvccsa_cpu1_en_lvc1"
				( attribute "CDS_PHYS_NET_NAME" "FM_PVCCIN_PVCCSA_CPU1_EN_LVC1"
					( Origin gPackager )
				)
				( objectStatus "FM_PVCCIN_PVCCSA_CPU1_EN_LVC1" )
			)
			( signal "@baseboard_fab2_lib.baseboard_fab2(sch_1):fm_pvddq_abc_en"
				( attribute "CDS_PHYS_NET_NAME" "FM_PVDDQ_ABC_EN"
					( Origin gPackager )
				)
				( objectStatus "FM_PVDDQ_ABC_EN" )
			)
			( signal "@baseboard_fab2_lib.baseboard_fab2(sch_1):fm_pvddq_def_en"
				( attribute "CDS_PHYS_NET_NAME" "FM_PVDDQ_DEF_EN"
					( Origin gPackager )
				)
				( objectStatus "FM_PVDDQ_DEF_EN" )
			)
			( signal "@baseboard_fab2_lib.baseboard_fab2(sch_1):fm_pvddq_ghj_en"
				( attribute "CDS_PHYS_NET_NAME" "FM_PVDDQ_GHJ_EN"
					( Origin gPackager )
				)
				( objectStatus "FM_PVDDQ_GHJ_EN" )
			)
			( signal "@baseboard_fab2_lib.baseboard_fab2(sch_1):fm_pvddq_klm_en"
				( attribute "CDS_PHYS_NET_NAME" "FM_PVDDQ_KLM_EN"
					( Origin gPackager )
				)
				( objectStatus "FM_PVDDQ_KLM_EN" )
			)
			( signal "@baseboard_fab2_lib.baseboard_fab2(sch_1):fm_pvpp_cpu0_en"
				( attribute "CDS_PHYS_NET_NAME" "FM_PVPP_CPU0_EN"
					( Origin gPackager )
				)
				( objectStatus "FM_PVPP_CPU0_EN" )
			)
			( signal "@baseboard_fab2_lib.baseboard_fab2(sch_1):fm_pvpp_cpu1_en"
				( attribute "CDS_PHYS_NET_NAME" "FM_PVPP_CPU1_EN"
					( Origin gPackager )
				)
				( objectStatus "FM_PVPP_CPU1_EN" )
			)
			( signal "@baseboard_fab2_lib.baseboard_fab2(sch_1):fm_uv_adr_trigger_n"
				( attribute "CDS_PHYS_NET_NAME" "FM_UV_ADR_TRIGGER_N"
					( Origin gPackager )
				)
				( objectStatus "FM_UV_ADR_TRIGGER_N" )
			)
			( signal "@baseboard_fab2_lib.baseboard_fab2(sch_1):pu_fab2_marker_cpld"
				( attribute "CDS_PHYS_NET_NAME" "PU_FAB2_MARKER_CPLD"
					( Origin gPackager )
				)
				( objectStatus "PU_FAB2_MARKER_CPLD" )
			)
			( signal "@baseboard_fab2_lib.baseboard_fab2(sch_1):pu_rst_perst_bit1"
				( attribute "CDS_PHYS_NET_NAME" "PU_RST_PERST_BIT1"
					( Origin gPackager )
				)
				( objectStatus "PU_RST_PERST_BIT1" )
			)
			( signal "@baseboard_fab2_lib.baseboard_fab2(sch_1):pu_thermtrip_force_n"
				( attribute "CDS_PHYS_NET_NAME" "PU_THERMTRIP_FORCE_N"
					( Origin gPackager )
				)
				( objectStatus "PU_THERMTRIP_FORCE_N" )
			)
			( signal "@baseboard_fab2_lib.baseboard_fab2(sch_1):pwrgd_p12v_main"
				( attribute "CDS_PHYS_NET_NAME" "PWRGD_P12V_MAIN"
					( Origin gPackager )
				)
				( objectStatus "PWRGD_P12V_MAIN" )
			)
			( signal "@baseboard_fab2_lib.baseboard_fab2(sch_1):pwrgd_p1v26_bmc_stby"
				( attribute "CDS_PHYS_NET_NAME" "PWRGD_P1V26_BMC_STBY"
					( Origin gPackager )
				)
				( objectStatus "PWRGD_P1V26_BMC_STBY" )
			)
			( signal "@baseboard_fab2_lib.baseboard_fab2(sch_1):pwrgd_p1v8mcp_cpu0"
				( attribute "CDS_PHYS_NET_NAME" "PWRGD_P1V8MCP_CPU0"
					( Origin gPackager )
				)
				( objectStatus "PWRGD_P1V8MCP_CPU0" )
			)
			( signal "@baseboard_fab2_lib.baseboard_fab2(sch_1):pwrgd_p1v8mcp_cpu1"
				( attribute "CDS_PHYS_NET_NAME" "PWRGD_P1V8MCP_CPU1"
					( Origin gPackager )
				)
				( objectStatus "PWRGD_P1V8MCP_CPU1" )
			)
			( signal "@baseboard_fab2_lib.baseboard_fab2(sch_1):pwrgd_pvccio_cpu1"
				( attribute "CDS_PHYS_NET_NAME" "PWRGD_PVCCIO_CPU1"
					( Origin gPackager )
				)
				( objectStatus "PWRGD_PVCCIO_CPU1" )
			)
			( signal "@baseboard_fab2_lib.baseboard_fab2(sch_1):pwrgd_pvtt_cpu0"
				( attribute "CDS_PHYS_NET_NAME" "PWRGD_PVTT_CPU0"
					( Origin gPackager )
				)
				( objectStatus "PWRGD_PVTT_CPU0" )
			)
			( signal "@baseboard_fab2_lib.baseboard_fab2(sch_1):sgpio_bmc_din_r"
				( attribute "CDS_PHYS_NET_NAME" "SGPIO_BMC_DIN_R"
					( Origin gPackager )
				)
				( objectStatus "SGPIO_BMC_DIN_R" )
			)
			( signal "@baseboard_fab2_lib.baseboard_fab2(sch_1):tp_cpld1_pr10c"
				( attribute "CDS_PHYS_NET_NAME" "TP_CPLD1_PR10C"
					( Origin gPackager )
				)
				( objectStatus "TP_CPLD1_PR10C" )
			)
			( signal "@baseboard_fab2_lib.baseboard_fab2(sch_1):tp_cpld1_pr11b"
				( attribute "CDS_PHYS_NET_NAME" "TP_CPLD1_PR11B"
					( Origin gPackager )
				)
				( objectStatus "TP_CPLD1_PR11B" )
			)
			( signal "@baseboard_fab2_lib.baseboard_fab2(sch_1):tp_cpld1_pr12d"
				( attribute "CDS_PHYS_NET_NAME" "TP_CPLD1_PR12D"
					( Origin gPackager )
				)
				( objectStatus "TP_CPLD1_PR12D" )
			)
			( signal "@baseboard_fab2_lib.baseboard_fab2(sch_1):tp_cpld1_pr7a_pclkt1_0"
				( attribute "CDS_PHYS_NET_NAME" "TP_CPLD1_PR7A_PCLKT1_0"
					( Origin gPackager )
				)
				( objectStatus "TP_CPLD1_PR7A_PCLKT1_0" )
			)
			( signal "@baseboard_fab2_lib.baseboard_fab2(sch_1):tp_cpld1_pr7b_pclkc1_0"
				( attribute "CDS_PHYS_NET_NAME" "TP_CPLD1_PR7B_PCLKC1_0"
					( Origin gPackager )
				)
				( objectStatus "TP_CPLD1_PR7B_PCLKC1_0" )
			)
			( signal "@baseboard_fab2_lib.baseboard_fab2(sch_1):tp_cpld1_pr7c"
				( attribute "CDS_PHYS_NET_NAME" "TP_CPLD1_PR7C"
					( Origin gPackager )
				)
				( objectStatus "TP_CPLD1_PR7C" )
			)
			( signal "@baseboard_fab2_lib.baseboard_fab2(sch_1):tp_cpld1_pr7d"
				( attribute "CDS_PHYS_NET_NAME" "TP_CPLD1_PR7D"
					( Origin gPackager )
				)
				( objectStatus "TP_CPLD1_PR7D" )
			)
			( signal "@baseboard_fab2_lib.baseboard_fab2(sch_1):tp_cpld1_pr9a"
				( attribute "CDS_PHYS_NET_NAME" "TP_CPLD1_PR9A"
					( Origin gPackager )
				)
				( objectStatus "TP_CPLD1_PR9A" )
			)
			( signal "@baseboard_fab2_lib.baseboard_fab2(sch_1):tp_cpld1_pr9c"
				( attribute "CDS_PHYS_NET_NAME" "TP_CPLD1_PR9C"
					( Origin gPackager )
				)
				( objectStatus "TP_CPLD1_PR9C" )
			)
			( signal "@baseboard_fab2_lib.baseboard_fab2(sch_1):tp_cpld1_pr9d"
				( attribute "CDS_PHYS_NET_NAME" "TP_CPLD1_PR9D"
					( Origin gPackager )
				)
				( objectStatus "TP_CPLD1_PR9D" )
			)
			( signal "@baseboard_fab2_lib.baseboard_fab2(sch_1):tp_cpld1_pt11a"
				( attribute "CDS_PHYS_NET_NAME" "TP_CPLD1_PT11A"
					( Origin gPackager )
				)
				( objectStatus "TP_CPLD1_PT11A" )
			)
			( signal "@baseboard_fab2_lib.baseboard_fab2(sch_1):tp_cpld1_pt11b"
				( attribute "CDS_PHYS_NET_NAME" "TP_CPLD1_PT11B"
					( Origin gPackager )
				)
				( objectStatus "TP_CPLD1_PT11B" )
			)
			( signal "@baseboard_fab2_lib.baseboard_fab2(sch_1):tp_cpld1_pt13a"
				( attribute "CDS_PHYS_NET_NAME" "TP_CPLD1_PT13A"
					( Origin gPackager )
				)
				( objectStatus "TP_CPLD1_PT13A" )
			)
			( signal "@baseboard_fab2_lib.baseboard_fab2(sch_1):tp_cpld1_pt16b"
				( attribute "CDS_PHYS_NET_NAME" "TP_CPLD1_PT16B"
					( Origin gPackager )
				)
				( objectStatus "TP_CPLD1_PT16B" )
			)
			( signal "@baseboard_fab2_lib.baseboard_fab2(sch_1):tp_cpld1_pt17b_pclkc0_1"
				( attribute "CDS_PHYS_NET_NAME" "TP_CPLD1_PT17B_PCLKC0_1"
					( Origin gPackager )
				)
				( objectStatus "TP_CPLD1_PT17B_PCLKC0_1" )
			)
			( signal "@baseboard_fab2_lib.baseboard_fab2(sch_1):tp_cpld1_pt17c"
				( attribute "CDS_PHYS_NET_NAME" "TP_CPLD1_PT17C"
					( Origin gPackager )
				)
				( objectStatus "TP_CPLD1_PT17C" )
			)
			( signal "@baseboard_fab2_lib.baseboard_fab2(sch_1):tp_cpld1_pt19d"
				( attribute "CDS_PHYS_NET_NAME" "TP_CPLD1_PT19D"
					( Origin gPackager )
				)
				( objectStatus "TP_CPLD1_PT19D" )
			)
			( signal "@baseboard_fab2_lib.baseboard_fab2(sch_1):tp_cpld1_pt20a"
				( attribute "CDS_PHYS_NET_NAME" "TP_CPLD1_PT20A"
					( Origin gPackager )
				)
				( objectStatus "TP_CPLD1_PT20A" )
			)
			( signal "@baseboard_fab2_lib.baseboard_fab2(sch_1):tp_cpld1_pt20b"
				( attribute "CDS_PHYS_NET_NAME" "TP_CPLD1_PT20B"
					( Origin gPackager )
				)
				( objectStatus "TP_CPLD1_PT20B" )
			)
			( signal "@baseboard_fab2_lib.baseboard_fab2(sch_1):tp_cpld1_pt20d_programn"
				( attribute "CDS_PHYS_NET_NAME" "TP_CPLD1_PT20D_PROGRAMN"
					( Origin gPackager )
				)
				( objectStatus "TP_CPLD1_PT20D_PROGRAMN" )
			)
			( signal "@baseboard_fab2_lib.baseboard_fab2(sch_1):tp_cpld1_pt22c"
				( attribute "CDS_PHYS_NET_NAME" "TP_CPLD1_PT22C"
					( Origin gPackager )
				)
				( objectStatus "TP_CPLD1_PT22C" )
			)
			( signal "@baseboard_fab2_lib.baseboard_fab2(sch_1):tp_cpld1_pt22d"
				( attribute "CDS_PHYS_NET_NAME" "TP_CPLD1_PT22D"
					( Origin gPackager )
				)
				( objectStatus "TP_CPLD1_PT22D" )
			)
			( signal "@baseboard_fab2_lib.baseboard_fab2(sch_1):tp_cpld1_pt24b"
				( attribute "CDS_PHYS_NET_NAME" "TP_CPLD1_PT24B"
					( Origin gPackager )
				)
				( objectStatus "TP_CPLD1_PT24B" )
			)
			( signal "@baseboard_fab2_lib.baseboard_fab2(sch_1):tp_cpld1_pt24c_initn"
				( attribute "CDS_PHYS_NET_NAME" "TP_CPLD1_PT24C_INITN"
					( Origin gPackager )
				)
				( objectStatus "TP_CPLD1_PT24C_INITN" )
			)
			( signal "@baseboard_fab2_lib.baseboard_fab2(sch_1):tp_cpld1_pt24d_done"
				( attribute "CDS_PHYS_NET_NAME" "TP_CPLD1_PT24D_DONE"
					( Origin gPackager )
				)
				( objectStatus "TP_CPLD1_PT24D_DONE" )
			)
			( signal "@baseboard_fab2_lib.baseboard_fab2(sch_1):nc_cpld1"
				( attribute "CDS_PHYS_NET_NAME" "NC_CPLD1"
					( Origin gPackager )
				)
				( objectStatus "NC_CPLD1" )
			)
			( signal "@baseboard_fab2_lib.baseboard_fab2(sch_1):vr_pvcciomcp_cpu1_xaddr1"
				( attribute "CDS_PHYS_NET_NAME" "VR_PVCCIOMCP_CPU1_XADDR1"
					( Origin gPackager )
				)
				( objectStatus "VR_PVCCIOMCP_CPU1_XADDR1" )
			)
			( signal "@baseboard_fab2_lib.baseboard_fab2(sch_1):vr_pvccmcp_cpu1_xaddr2"
				( attribute "CDS_PHYS_NET_NAME" "VR_PVCCMCP_CPU1_XADDR2"
					( Origin gPackager )
				)
				( objectStatus "VR_PVCCMCP_CPU1_XADDR2" )
			)
			( signal "@baseboard_fab2_lib.baseboard_fab2(sch_1):vr_pvcciomcp_cpu0_xaddr1"
				( attribute "CDS_PHYS_NET_NAME" "VR_PVCCIOMCP_CPU0_XADDR1"
					( Origin gPackager )
				)
				( objectStatus "VR_PVCCIOMCP_CPU0_XADDR1" )
			)
			( signal "@baseboard_fab2_lib.baseboard_fab2(sch_1):vr_pvccmcp_cpu0_xaddr2"
				( attribute "CDS_PHYS_NET_NAME" "VR_PVCCMCP_CPU0_XADDR2"
					( Origin gPackager )
				)
				( objectStatus "VR_PVCCMCP_CPU0_XADDR2" )
			)
			( signal "@baseboard_fab2_lib.baseboard_fab2(sch_1):a_adm1085_cext"
				( attribute "CDS_PHYS_NET_NAME" "A_ADM1085_CEXT"
					( Origin gPackager )
				)
				( objectStatus "A_ADM1085_CEXT" )
			)
			( signal "@baseboard_fab2_lib.baseboard_fab2(sch_1):a_pg_p12v_main"
				( attribute "CDS_PHYS_NET_NAME" "A_PG_P12V_MAIN"
					( Origin gPackager )
				)
				( objectStatus "A_PG_P12V_MAIN" )
			)
			( signal "@baseboard_fab2_lib.baseboard_fab2(sch_1):a_pg_p5v"
				( attribute "CDS_PHYS_NET_NAME" "A_PG_P5V"
					( Origin gPackager )
				)
				( objectStatus "A_PG_P5V" )
			)
			( signal "@baseboard_fab2_lib.baseboard_fab2(sch_1):p3v_bat_source"
				( alias ( signalRef "@baseboard_fab2_lib.baseboard_fab2(sch_1):page196_p3v_bat_source") )
				( attribute "VOLTAGE" "+3 V"
					( Units "uVoltage" "V" 1.000000)
					( Status sAliasFlattened )
					( Origin gFrontEnd )
				)
				( attribute "CDS_PHYS_NET_NAME" "P3V_BAT_SOURCE"
					( Origin gPackager )
				)
				( objectStatus "P3V_BAT_SOURCE" )
			)
			( signal "@baseboard_fab2_lib.baseboard_fab2(sch_1):page196_p3v_bat_source"
				( attribute "CDS_PHYS_NET_NAME" "P3V_BAT_SOURCE"
					( Origin gPackager )
				)
				( attribute "VOLTAGE" "+3 V"
					( Units "uVoltage" "V" 1.000000)
					( Origin gFrontEnd )
				)
				( objectFlag fObjectAlias )
				( objectStatus "page196_p3v_bat_source" )
			)
			( signal "@baseboard_fab2_lib.baseboard_fab2(sch_1):pwrgd_p12v_hsc"
				( attribute "CDS_PHYS_NET_NAME" "PWRGD_P12V_HSC"
					( Origin gPackager )
				)
				( objectStatus "PWRGD_P12V_HSC" )
			)
			( signal "@baseboard_fab2_lib.baseboard_fab2(sch_1):pwrgd_p12v_hsc_dly_r"
				( attribute "CDS_PHYS_NET_NAME" "PWRGD_P12V_HSC_DLY_R"
					( Origin gPackager )
				)
				( objectStatus "PWRGD_P12V_HSC_DLY_R" )
			)
			( signal "@baseboard_fab2_lib.baseboard_fab2(sch_1):pwrgd_p12v_main_r"
				( attribute "CDS_PHYS_NET_NAME" "PWRGD_P12V_MAIN_R"
					( Origin gPackager )
				)
				( objectStatus "PWRGD_P12V_MAIN_R" )
			)
			( signal "@baseboard_fab2_lib.baseboard_fab2(sch_1):pwrgd_p3v3_r1"
				( attribute "CDS_PHYS_NET_NAME" "PWRGD_P3V3_R1"
					( Origin gPackager )
				)
				( objectStatus "PWRGD_P3V3_R1" )
			)
			( signal "@baseboard_fab2_lib.baseboard_fab2(sch_1):pwrgd_p5v_n"
				( attribute "CDS_PHYS_NET_NAME" "PWRGD_P5V_N"
					( Origin gPackager )
				)
				( objectStatus "PWRGD_P5V_N" )
			)
			( signal "@baseboard_fab2_lib.baseboard_fab2(sch_1):pwrgd_p5v_r"
				( attribute "CDS_PHYS_NET_NAME" "PWRGD_P5V_R"
					( Origin gPackager )
				)
				( objectStatus "PWRGD_P5V_R" )
			)
			( signal "@baseboard_fab2_lib.baseboard_fab2(sch_1):vsense_p12v_adm1085"
				( attribute "CDS_PHYS_NET_NAME" "VSENSE_P12V_ADM1085"
					( Origin gPackager )
				)
				( objectStatus "VSENSE_P12V_ADM1085" )
			)
			( signal "@baseboard_fab2_lib.baseboard_fab2(sch_1):vr_pvddq_abc_aiinsen"
				( attribute "CDS_PHYS_NET_NAME" "VR_PVDDQ_ABC_AIINSEN"
					( Origin gPackager )
				)
				( objectStatus "VR_PVDDQ_ABC_AIINSEN" )
			)
			( signal "@baseboard_fab2_lib.baseboard_fab2(sch_1):vr_pvddq_abc_aiinsen_r"
				( attribute "CDS_PHYS_NET_NAME" "VR_PVDDQ_ABC_AIINSEN_R"
					( Origin gPackager )
				)
				( objectStatus "VR_PVDDQ_ABC_AIINSEN_R" )
			)
			( signal "@baseboard_fab2_lib.baseboard_fab2(sch_1):vr_pvddq_def_aiinsen"
				( attribute "CDS_PHYS_NET_NAME" "VR_PVDDQ_DEF_AIINSEN"
					( Origin gPackager )
				)
				( objectStatus "VR_PVDDQ_DEF_AIINSEN" )
			)
			( signal "@baseboard_fab2_lib.baseboard_fab2(sch_1):vr_pvddq_def_aiinsen_r"
				( attribute "CDS_PHYS_NET_NAME" "VR_PVDDQ_DEF_AIINSEN_R"
					( Origin gPackager )
				)
				( objectStatus "VR_PVDDQ_DEF_AIINSEN_R" )
			)
			( signal "@baseboard_fab2_lib.baseboard_fab2(sch_1):vr_pvddq_ghj_aiinsen"
				( attribute "CDS_PHYS_NET_NAME" "VR_PVDDQ_GHJ_AIINSEN"
					( Origin gPackager )
				)
				( objectStatus "VR_PVDDQ_GHJ_AIINSEN" )
			)
			( signal "@baseboard_fab2_lib.baseboard_fab2(sch_1):vr_pvddq_ghj_aiinsen_r"
				( attribute "CDS_PHYS_NET_NAME" "VR_PVDDQ_GHJ_AIINSEN_R"
					( Origin gPackager )
				)
				( objectStatus "VR_PVDDQ_GHJ_AIINSEN_R" )
			)
			( signal "@baseboard_fab2_lib.baseboard_fab2(sch_1):vr_pvddq_klm_aiinsen"
				( attribute "CDS_PHYS_NET_NAME" "VR_PVDDQ_KLM_AIINSEN"
					( Origin gPackager )
				)
				( objectStatus "VR_PVDDQ_KLM_AIINSEN" )
			)
			( signal "@baseboard_fab2_lib.baseboard_fab2(sch_1):vr_pvddq_klm_aiinsen_r"
				( attribute "CDS_PHYS_NET_NAME" "VR_PVDDQ_KLM_AIINSEN_R"
					( Origin gPackager )
				)
				( objectStatus "VR_PVDDQ_KLM_AIINSEN_R" )
			)
			( signal "@baseboard_fab2_lib.baseboard_fab2(sch_1):p12v_fan_switch_g"
				( alias ( signalRef "@baseboard_fab2_lib.baseboard_fab2(sch_1):page198_p12v_fan_switch_g") )
				( attribute "VOLTAGE" "+5V"
					( Units "uVoltage" "V" 1.000000)
					( Status sAliasFlattened )
					( Origin gFrontEnd )
				)
				( attribute "CDS_PHYS_NET_NAME" "P12V_FAN_SWITCH_G"
					( Origin gPackager )
				)
				( objectStatus "P12V_FAN_SWITCH_G" )
			)
			( signal "@baseboard_fab2_lib.baseboard_fab2(sch_1):page198_p12v_fan_switch_g"
				( attribute "VOLTAGE" "+5V"
					( Units "uVoltage" "V" 1.000000)
					( Origin gFrontEnd )
				)
				( objectFlag fObjectAlias )
				( objectStatus "page198_p12v_fan_switch_g" )
			)
			( signal "@baseboard_fab2_lib.baseboard_fab2(sch_1):p12v_switch_g"
				( alias ( signalRef "@baseboard_fab2_lib.baseboard_fab2(sch_1):page198_p12v_switch_g") )
				( attribute "VOLTAGE" "+3.3V"
					( Units "uVoltage" "V" 1.000000)
					( Status sAliasFlattened )
					( Origin gFrontEnd )
				)
				( attribute "CDS_PHYS_NET_NAME" "P12V_SWITCH_G"
					( Origin gPackager )
				)
				( objectStatus "P12V_SWITCH_G" )
			)
			( signal "@baseboard_fab2_lib.baseboard_fab2(sch_1):page198_p12v_switch_g"
				( attribute "VOLTAGE" "+3.3V"
					( Units "uVoltage" "V" 1.000000)
					( Origin gFrontEnd )
				)
				( objectFlag fObjectAlias )
				( objectStatus "page198_p12v_switch_g" )
			)
			( signal "@baseboard_fab2_lib.baseboard_fab2(sch_1):p3v3_switch_g"
				( alias ( signalRef "@baseboard_fab2_lib.baseboard_fab2(sch_1):page198_p3v3_switch_g") )
				( attribute "VOLTAGE" "3.3"
					( Units "uVoltage" "V" 1.000000)
					( Status sAliasFlattened )
					( Origin gFrontEnd )
				)
				( attribute "CDS_PHYS_NET_NAME" "P3V3_SWITCH_G"
					( Origin gPackager )
				)
				( objectStatus "P3V3_SWITCH_G" )
			)
			( signal "@baseboard_fab2_lib.baseboard_fab2(sch_1):page198_p3v3_switch_g"
				( attribute "VOLTAGE" "3.3"
					( Units "uVoltage" "V" 1.000000)
					( Origin gFrontEnd )
				)
				( objectFlag fObjectAlias )
				( objectStatus "page198_p3v3_switch_g" )
			)
			( signal "@baseboard_fab2_lib.baseboard_fab2(sch_1):p5v_switch_g"
				( alias ( signalRef "@baseboard_fab2_lib.baseboard_fab2(sch_1):page198_p5v_switch_g") )
				( attribute "VOLTAGE" "+5V"
					( Units "uVoltage" "V" 1.000000)
					( Status sAliasFlattened )
					( Origin gFrontEnd )
				)
				( attribute "CDS_PHYS_NET_NAME" "P5V_SWITCH_G"
					( Origin gPackager )
				)
				( objectStatus "P5V_SWITCH_G" )
			)
			( signal "@baseboard_fab2_lib.baseboard_fab2(sch_1):page198_p5v_switch_g"
				( attribute "VOLTAGE" "+5V"
					( Units "uVoltage" "V" 1.000000)
					( Origin gFrontEnd )
				)
				( objectFlag fObjectAlias )
				( objectStatus "page198_p5v_switch_g" )
			)
			( signal "@baseboard_fab2_lib.baseboard_fab2(sch_1):tp_slg55021_p12v_fan_8"
				( attribute "CDS_PHYS_NET_NAME" "TP_SLG55021_P12V_FAN_8"
					( Origin gPackager )
				)
				( objectStatus "TP_SLG55021_P12V_FAN_8" )
			)
			( signal "@baseboard_fab2_lib.baseboard_fab2(sch_1):tp_slg55021_p12v_main_8"
				( attribute "CDS_PHYS_NET_NAME" "TP_SLG55021_P12V_MAIN_8"
					( Origin gPackager )
				)
				( objectStatus "TP_SLG55021_P12V_MAIN_8" )
			)
			( signal "@baseboard_fab2_lib.baseboard_fab2(sch_1):tp_slg55021_p3v3_8"
				( attribute "CDS_PHYS_NET_NAME" "TP_SLG55021_P3V3_8"
					( Origin gPackager )
				)
				( objectStatus "TP_SLG55021_P3V3_8" )
			)
			( signal "@baseboard_fab2_lib.baseboard_fab2(sch_1):tp_slg55021_p5v_8"
				( attribute "CDS_PHYS_NET_NAME" "TP_SLG55021_P5V_8"
					( Origin gPackager )
				)
				( objectStatus "TP_SLG55021_P5V_8" )
			)
			( signal "@baseboard_fab2_lib.baseboard_fab2(sch_1):a_hsc_csout"
				( attribute "CDS_PHYS_NET_NAME" "A_HSC_CSOUT"
					( Origin gPackager )
				)
				( objectStatus "A_HSC_CSOUT" )
			)
			( signal "@baseboard_fab2_lib.baseboard_fab2(sch_1):a_hsc_gate"
				( attribute "CDS_PHYS_NET_NAME" "A_HSC_GATE"
					( Origin gPackager )
				)
				( objectStatus "A_HSC_GATE" )
			)
			( signal "@baseboard_fab2_lib.baseboard_fab2(sch_1):a_hsc_high_en"
				( attribute "CDS_PHYS_NET_NAME" "A_HSC_HIGH_EN"
					( Origin gPackager )
				)
				( objectStatus "A_HSC_HIGH_EN" )
			)
			( signal "@baseboard_fab2_lib.baseboard_fab2(sch_1):a_hsc_hsn"
				( attribute "CDS_PHYS_NET_NAME" "A_HSC_HSN"
					( Origin gPackager )
				)
				( objectStatus "A_HSC_HSN" )
			)
			( signal "@baseboard_fab2_lib.baseboard_fab2(sch_1):a_hsc_hsp"
				( attribute "CDS_PHYS_NET_NAME" "A_HSC_HSP"
					( Origin gPackager )
				)
				( objectStatus "A_HSC_HSP" )
			)
			( signal "@baseboard_fab2_lib.baseboard_fab2(sch_1):a_hsc_iset"
				( attribute "CDS_PHYS_NET_NAME" "A_HSC_ISET"
					( Origin gPackager )
				)
				( objectStatus "A_HSC_ISET" )
			)
			( signal "@baseboard_fab2_lib.baseboard_fab2(sch_1):a_hsc_iset_s"
				( attribute "CDS_PHYS_NET_NAME" "A_HSC_ISET_S"
					( Origin gPackager )
				)
				( objectStatus "A_HSC_ISET_S" )
			)
			( signal "@baseboard_fab2_lib.baseboard_fab2(sch_1):a_hsc_iset_s2"
				( attribute "CDS_PHYS_NET_NAME" "A_HSC_ISET_S2"
					( Origin gPackager )
				)
				( objectStatus "A_HSC_ISET_S2" )
			)
			( signal "@baseboard_fab2_lib.baseboard_fab2(sch_1):a_hsc_istart"
				( attribute "CDS_PHYS_NET_NAME" "A_HSC_ISTART"
					( Origin gPackager )
				)
				( objectStatus "A_HSC_ISTART" )
			)
			( signal "@baseboard_fab2_lib.baseboard_fab2(sch_1):a_hsc_low_en"
				( attribute "CDS_PHYS_NET_NAME" "A_HSC_LOW_EN"
					( Origin gPackager )
				)
				( objectStatus "A_HSC_LOW_EN" )
			)
			( signal "@baseboard_fab2_lib.baseboard_fab2(sch_1):a_hsc_mon"
				( attribute "CDS_PHYS_NET_NAME" "A_HSC_MON"
					( Origin gPackager )
				)
				( objectStatus "A_HSC_MON" )
			)
			( signal "@baseboard_fab2_lib.baseboard_fab2(sch_1):a_hsc_mop"
				( attribute "CDS_PHYS_NET_NAME" "A_HSC_MOP"
					( Origin gPackager )
				)
				( objectStatus "A_HSC_MOP" )
			)
			( signal "@baseboard_fab2_lib.baseboard_fab2(sch_1):a_hsc_ocp_sel"
				( attribute "CDS_PHYS_NET_NAME" "A_HSC_OCP_SEL"
					( Origin gPackager )
				)
				( objectStatus "A_HSC_OCP_SEL" )
			)
			( signal "@baseboard_fab2_lib.baseboard_fab2(sch_1):a_hsc_ov"
				( attribute "CDS_PHYS_NET_NAME" "A_HSC_OV"
					( Origin gPackager )
				)
				( objectStatus "A_HSC_OV" )
			)
			( signal "@baseboard_fab2_lib.baseboard_fab2(sch_1):a_hsc_pset"
				( attribute "CDS_PHYS_NET_NAME" "A_HSC_PSET"
					( Origin gPackager )
				)
				( objectStatus "A_HSC_PSET" )
			)
			( signal "@baseboard_fab2_lib.baseboard_fab2(sch_1):a_hsc_pwgin"
				( attribute "CDS_PHYS_NET_NAME" "A_HSC_PWGIN"
					( Origin gPackager )
				)
				( objectStatus "A_HSC_PWGIN" )
			)
			( signal "@baseboard_fab2_lib.baseboard_fab2(sch_1):a_hsc_temp"
				( attribute "CDS_PHYS_NET_NAME" "A_HSC_TEMP"
					( Origin gPackager )
				)
				( objectStatus "A_HSC_TEMP" )
			)
			( signal "@baseboard_fab2_lib.baseboard_fab2(sch_1):a_hsc_timer"
				( attribute "CDS_PHYS_NET_NAME" "A_HSC_TIMER"
					( Origin gPackager )
				)
				( objectStatus "A_HSC_TIMER" )
			)
			( signal "@baseboard_fab2_lib.baseboard_fab2(sch_1):a_hsc_uv"
				( attribute "CDS_PHYS_NET_NAME" "A_HSC_UV"
					( Origin gPackager )
				)
				( objectStatus "A_HSC_UV" )
			)
			( signal "@baseboard_fab2_lib.baseboard_fab2(sch_1):a_hsc_vcap"
				( attribute "CDS_PHYS_NET_NAME" "A_HSC_VCAP"
					( Origin gPackager )
				)
				( objectStatus "A_HSC_VCAP" )
			)
			( signal "@baseboard_fab2_lib.baseboard_fab2(sch_1):a_hsc_vout"
				( attribute "CDS_PHYS_NET_NAME" "A_HSC_VOUT"
					( Origin gPackager )
				)
				( objectStatus "A_HSC_VOUT" )
			)
			( signal "@baseboard_fab2_lib.baseboard_fab2(sch_1):agnd_hsc"
				( alias ( signalRef "@baseboard_fab2_lib.baseboard_fab2(sch_1):page199_agnd_hsc") )
				( alias ( signalRef "@baseboard_fab2_lib.baseboard_fab2(sch_1):page200_agnd_hsc") )
				( attribute "VOLTAGE" "0"
					( Units "uVoltage" "V" 1.000000)
					( Status sAliasFlattened )
					( Origin gFrontEnd )
				)
				( attribute "CDS_PHYS_NET_NAME" "AGND_HSC"
					( Origin gPackager )
				)
				( objectStatus "AGND_HSC" )
			)
			( signal "@baseboard_fab2_lib.baseboard_fab2(sch_1):page199_agnd_hsc"
				( attribute "VOLTAGE" "0"
					( Units "uVoltage" "V" 1.000000)
					( Origin gFrontEnd )
				)
				( objectFlag fObjectAlias )
				( objectStatus "page199_agnd_hsc" )
			)
			( signal "@baseboard_fab2_lib.baseboard_fab2(sch_1):page200_agnd_hsc"
				( attribute "VOLTAGE" "0"
					( Units "uVoltage" "V" 1.000000)
					( Origin gFrontEnd )
				)
				( objectFlag fObjectAlias )
				( objectStatus "page200_agnd_hsc" )
			)
			( signal "@baseboard_fab2_lib.baseboard_fab2(sch_1):fm_p12v_hsc_adr1"
				( attribute "CDS_PHYS_NET_NAME" "FM_P12V_HSC_ADR1"
					( Origin gPackager )
				)
				( objectStatus "FM_P12V_HSC_ADR1" )
			)
			( signal "@baseboard_fab2_lib.baseboard_fab2(sch_1):fm_p12v_hsc_adr2"
				( attribute "CDS_PHYS_NET_NAME" "FM_P12V_HSC_ADR2"
					( Origin gPackager )
				)
				( objectStatus "FM_P12V_HSC_ADR2" )
			)
			( signal "@baseboard_fab2_lib.baseboard_fab2(sch_1):irq_hsc_fault_r_n"
				( attribute "CDS_PHYS_NET_NAME" "IRQ_HSC_FAULT_R_N"
					( Origin gPackager )
				)
				( objectStatus "IRQ_HSC_FAULT_R_N" )
			)
			( signal "@baseboard_fab2_lib.baseboard_fab2(sch_1):p12v_hsc_vcc"
				( alias ( signalRef "@baseboard_fab2_lib.baseboard_fab2(sch_1):page199_p12v_hsc_vcc") )
				( attribute "VOLTAGE" "+12V"
					( Units "uVoltage" "V" 1.000000)
					( Status sAliasFlattened )
					( Origin gFrontEnd )
				)
				( attribute "CDS_PHYS_NET_NAME" "P12V_HSC_VCC"
					( Origin gPackager )
				)
				( objectStatus "P12V_HSC_VCC" )
			)
			( signal "@baseboard_fab2_lib.baseboard_fab2(sch_1):page199_p12v_hsc_vcc"
				( attribute "VOLTAGE" "+12V"
					( Units "uVoltage" "V" 1.000000)
					( Origin gFrontEnd )
				)
				( objectFlag fObjectAlias )
				( objectStatus "page199_p12v_hsc_vcc" )
			)
			( signal "@baseboard_fab2_lib.baseboard_fab2(sch_1):pd_hsc_retry_n"
				( attribute "CDS_PHYS_NET_NAME" "PD_HSC_RETRY_N"
					( Origin gPackager )
				)
				( objectStatus "PD_HSC_RETRY_N" )
			)
			( signal "@baseboard_fab2_lib.baseboard_fab2(sch_1):pwrgd_p12v_r"
				( attribute "CDS_PHYS_NET_NAME" "PWRGD_P12V_R"
					( Origin gPackager )
				)
				( objectStatus "PWRGD_P12V_R" )
			)
			( signal "@baseboard_fab2_lib.baseboard_fab2(sch_1):smb_3v3sb_hsc_scl_r"
				( attribute "CDS_PHYS_NET_NAME" "SMB_3V3SB_HSC_SCL_R"
					( Origin gPackager )
				)
				( objectStatus "SMB_3V3SB_HSC_SCL_R" )
			)
			( signal "@baseboard_fab2_lib.baseboard_fab2(sch_1):smb_3v3sb_hsc_sda_r"
				( attribute "CDS_PHYS_NET_NAME" "SMB_3V3SB_HSC_SDA_R"
					( Origin gPackager )
				)
				( objectStatus "SMB_3V3SB_HSC_SDA_R" )
			)
			( signal "@baseboard_fab2_lib.baseboard_fab2(sch_1):tp_hsc_alert2_n"
				( attribute "CDS_PHYS_NET_NAME" "TP_HSC_ALERT2_N"
					( Origin gPackager )
				)
				( objectStatus "TP_HSC_ALERT2_N" )
			)
			( signal "@baseboard_fab2_lib.baseboard_fab2(sch_1):tp_hsc_mclk"
				( attribute "CDS_PHYS_NET_NAME" "TP_HSC_MCLK"
					( Origin gPackager )
				)
				( objectStatus "TP_HSC_MCLK" )
			)
			( signal "@baseboard_fab2_lib.baseboard_fab2(sch_1):tp_hsc_mdat"
				( attribute "CDS_PHYS_NET_NAME" "TP_HSC_MDAT"
					( Origin gPackager )
				)
				( objectStatus "TP_HSC_MDAT" )
			)
			( signal "@baseboard_fab2_lib.baseboard_fab2(sch_1):tp_hsc_spissn"
				( attribute "CDS_PHYS_NET_NAME" "TP_HSC_SPISSN"
					( Origin gPackager )
				)
				( objectStatus "TP_HSC_SPISSN" )
			)
			( signal "@baseboard_fab2_lib.baseboard_fab2(sch_1):a_hsc_c"
				( attribute "CDS_PHYS_NET_NAME" "A_HSC_C"
					( Origin gPackager )
				)
				( objectStatus "A_HSC_C" )
			)
			( signal "@baseboard_fab2_lib.baseboard_fab2(sch_1):a_hsc_gate1_r"
				( attribute "CDS_PHYS_NET_NAME" "A_HSC_GATE1_R"
					( Origin gPackager )
				)
				( objectStatus "A_HSC_GATE1_R" )
			)
			( signal "@baseboard_fab2_lib.baseboard_fab2(sch_1):a_hsc_gate2_r"
				( attribute "CDS_PHYS_NET_NAME" "A_HSC_GATE2_R"
					( Origin gPackager )
				)
				( objectStatus "A_HSC_GATE2_R" )
			)
			( signal "@baseboard_fab2_lib.baseboard_fab2(sch_1):a_hsc_gate3_r"
				( attribute "CDS_PHYS_NET_NAME" "A_HSC_GATE3_R"
					( Origin gPackager )
				)
				( objectStatus "A_HSC_GATE3_R" )
			)
			( signal "@baseboard_fab2_lib.baseboard_fab2(sch_1):a_hsc_high"
				( attribute "CDS_PHYS_NET_NAME" "A_HSC_HIGH"
					( Origin gPackager )
				)
				( objectStatus "A_HSC_HIGH" )
			)
			( signal "@baseboard_fab2_lib.baseboard_fab2(sch_1):a_hsc_inap"
				( attribute "CDS_PHYS_NET_NAME" "A_HSC_INAP"
					( Origin gPackager )
				)
				( objectStatus "A_HSC_INAP" )
			)
			( signal "@baseboard_fab2_lib.baseboard_fab2(sch_1):a_hsc_low"
				( attribute "CDS_PHYS_NET_NAME" "A_HSC_LOW"
					( Origin gPackager )
				)
				( objectStatus "A_HSC_LOW" )
			)
			( signal "@baseboard_fab2_lib.baseboard_fab2(sch_1):a_hsc_low_drain"
				( attribute "CDS_PHYS_NET_NAME" "A_HSC_LOW_DRAIN"
					( Origin gPackager )
				)
				( objectStatus "A_HSC_LOW_DRAIN" )
			)
			( signal "@baseboard_fab2_lib.baseboard_fab2(sch_1):a_hsc_low_gate"
				( attribute "CDS_PHYS_NET_NAME" "A_HSC_LOW_GATE"
					( Origin gPackager )
				)
				( objectStatus "A_HSC_LOW_GATE" )
			)
			( signal "@baseboard_fab2_lib.baseboard_fab2(sch_1):a_hsc_timer_r"
				( attribute "CDS_PHYS_NET_NAME" "A_HSC_TIMER_R"
					( Origin gPackager )
				)
				( objectStatus "A_HSC_TIMER_R" )
			)
			( signal "@baseboard_fab2_lib.baseboard_fab2(sch_1):a_p12v_stby_adr_trigger"
				( attribute "CDS_PHYS_NET_NAME" "A_P12V_STBY_ADR_TRIGGER"
					( Origin gPackager )
				)
				( objectStatus "A_P12V_STBY_ADR_TRIGGER" )
			)
			( signal "@baseboard_fab2_lib.baseboard_fab2(sch_1):a_p12v_stby_fp_trigger"
				( attribute "CDS_PHYS_NET_NAME" "A_P12V_STBY_FP_TRIGGER"
					( Origin gPackager )
				)
				( objectStatus "A_P12V_STBY_FP_TRIGGER" )
			)
			( signal "@baseboard_fab2_lib.baseboard_fab2(sch_1):a_p12v_stby_fph_gate"
				( attribute "CDS_PHYS_NET_NAME" "A_P12V_STBY_FPH_GATE"
					( Origin gPackager )
				)
				( objectStatus "A_P12V_STBY_FPH_GATE" )
			)
			( signal "@baseboard_fab2_lib.baseboard_fab2(sch_1):fm_oc_detect_en"
				( attribute "CDS_PHYS_NET_NAME" "FM_OC_DETECT_EN"
					( Origin gPackager )
				)
				( objectStatus "FM_OC_DETECT_EN" )
			)
			( signal "@baseboard_fab2_lib.baseboard_fab2(sch_1):p12v_hsc_senn0"
				( alias ( signalRef "@baseboard_fab2_lib.baseboard_fab2(sch_1):page200_p12v_hsc_senn0") )
				( attribute "VOLTAGE" "+12V"
					( Units "uVoltage" "V" 1.000000)
					( Status sAliasFlattened )
					( Origin gFrontEnd )
				)
				( attribute "CDS_PHYS_NET_NAME" "P12V_HSC_SENN0"
					( Origin gPackager )
				)
				( objectStatus "P12V_HSC_SENN0" )
			)
			( signal "@baseboard_fab2_lib.baseboard_fab2(sch_1):page200_p12v_hsc_senn0"
				( attribute "VOLTAGE" "+12V"
					( Units "uVoltage" "V" 1.000000)
					( Origin gFrontEnd )
				)
				( objectFlag fObjectAlias )
				( objectStatus "page200_p12v_hsc_senn0" )
			)
			( signal "@baseboard_fab2_lib.baseboard_fab2(sch_1):p12v_hsc_senn1"
				( alias ( signalRef "@baseboard_fab2_lib.baseboard_fab2(sch_1):page200_p12v_hsc_senn1") )
				( attribute "VOLTAGE" "+12V"
					( Units "uVoltage" "V" 1.000000)
					( Status sAliasFlattened )
					( Origin gFrontEnd )
				)
				( attribute "CDS_PHYS_NET_NAME" "P12V_HSC_SENN1"
					( Origin gPackager )
				)
				( objectStatus "P12V_HSC_SENN1" )
			)
			( signal "@baseboard_fab2_lib.baseboard_fab2(sch_1):page200_p12v_hsc_senn1"
				( attribute "VOLTAGE" "+12V"
					( Units "uVoltage" "V" 1.000000)
					( Origin gFrontEnd )
				)
				( objectFlag fObjectAlias )
				( objectStatus "page200_p12v_hsc_senn1" )
			)
			( signal "@baseboard_fab2_lib.baseboard_fab2(sch_1):p12v_hsc_senp0"
				( alias ( signalRef "@baseboard_fab2_lib.baseboard_fab2(sch_1):page200_p12v_hsc_senp0") )
				( attribute "VOLTAGE" "+12V"
					( Units "uVoltage" "V" 1.000000)
					( Status sAliasFlattened )
					( Origin gFrontEnd )
				)
				( attribute "CDS_PHYS_NET_NAME" "P12V_HSC_SENP0"
					( Origin gPackager )
				)
				( objectStatus "P12V_HSC_SENP0" )
			)
			( signal "@baseboard_fab2_lib.baseboard_fab2(sch_1):page200_p12v_hsc_senp0"
				( attribute "VOLTAGE" "+12V"
					( Units "uVoltage" "V" 1.000000)
					( Origin gFrontEnd )
				)
				( objectFlag fObjectAlias )
				( objectStatus "page200_p12v_hsc_senp0" )
			)
			( signal "@baseboard_fab2_lib.baseboard_fab2(sch_1):p12v_hsc_senp1"
				( alias ( signalRef "@baseboard_fab2_lib.baseboard_fab2(sch_1):page200_p12v_hsc_senp1") )
				( attribute "VOLTAGE" "+12V"
					( Units "uVoltage" "V" 1.000000)
					( Status sAliasFlattened )
					( Origin gFrontEnd )
				)
				( attribute "CDS_PHYS_NET_NAME" "P12V_HSC_SENP1"
					( Origin gPackager )
				)
				( objectStatus "P12V_HSC_SENP1" )
			)
			( signal "@baseboard_fab2_lib.baseboard_fab2(sch_1):page200_p12v_hsc_senp1"
				( attribute "VOLTAGE" "+12V"
					( Units "uVoltage" "V" 1.000000)
					( Origin gFrontEnd )
				)
				( objectFlag fObjectAlias )
				( objectStatus "page200_p12v_hsc_senp1" )
			)
			( signal "@baseboard_fab2_lib.baseboard_fab2(sch_1):p12v_mb0_sw"
				( alias ( signalRef "@baseboard_fab2_lib.baseboard_fab2(sch_1):page200_p12v_mb0_sw") )
				( attribute "VOLTAGE" "+12V"
					( Units "uVoltage" "V" 1.000000)
					( Status sAliasFlattened )
					( Origin gFrontEnd )
				)
				( attribute "CDS_PHYS_NET_NAME" "P12V_MB0_SW"
					( Origin gPackager )
				)
				( objectStatus "P12V_MB0_SW" )
			)
			( signal "@baseboard_fab2_lib.baseboard_fab2(sch_1):page200_p12v_mb0_sw"
				( attribute "VOLTAGE" "+12V"
					( Units "uVoltage" "V" 1.000000)
					( Origin gFrontEnd )
				)
				( objectFlag fObjectAlias )
				( objectStatus "page200_p12v_mb0_sw" )
			)
			( signal "@baseboard_fab2_lib.baseboard_fab2(sch_1):a_tsense_pvccin_cpu0"
				( attribute "CDS_PHYS_NET_NAME" "A_TSENSE_PVCCIN_CPU0"
					( Origin gPackager )
				)
				( objectStatus "A_TSENSE_PVCCIN_CPU0" )
			)
			( signal "@baseboard_fab2_lib.baseboard_fab2(sch_1):a_tsense_pvsa_cpu0"
				( attribute "CDS_PHYS_NET_NAME" "A_TSENSE_PVSA_CPU0"
					( Origin gPackager )
				)
				( objectStatus "A_TSENSE_PVSA_CPU0" )
			)
			( signal "@baseboard_fab2_lib.baseboard_fab2(sch_1):irq_pvccin_cpu0_vrhot_lvc3_r_n"
				( attribute "CDS_PHYS_NET_NAME" "IRQ_PVCCIN_CPU0_VRHOT_LVC3_R_N"
					( Origin gPackager )
				)
				( objectStatus "IRQ_PVCCIN_CPU0_VRHOT_LVC3_R_N" )
			)
			( signal "@baseboard_fab2_lib.baseboard_fab2(sch_1):isense_pvccin_cpu0_ph1_imon"
				( attribute "CDS_PHYS_NET_NAME" "ISENSE_PVCCIN_CPU0_PH1_IMON"
					( Origin gPackager )
				)
				( objectStatus "ISENSE_PVCCIN_CPU0_PH1_IMON" )
			)
			( signal "@baseboard_fab2_lib.baseboard_fab2(sch_1):isense_pvccin_cpu0_ph2_imon"
				( attribute "CDS_PHYS_NET_NAME" "ISENSE_PVCCIN_CPU0_PH2_IMON"
					( Origin gPackager )
				)
				( objectStatus "ISENSE_PVCCIN_CPU0_PH2_IMON" )
			)
			( signal "@baseboard_fab2_lib.baseboard_fab2(sch_1):isense_pvccin_cpu0_ph3_imon"
				( attribute "CDS_PHYS_NET_NAME" "ISENSE_PVCCIN_CPU0_PH3_IMON"
					( Origin gPackager )
				)
				( objectStatus "ISENSE_PVCCIN_CPU0_PH3_IMON" )
			)
			( signal "@baseboard_fab2_lib.baseboard_fab2(sch_1):isense_pvccin_cpu0_ph4_imon"
				( attribute "CDS_PHYS_NET_NAME" "ISENSE_PVCCIN_CPU0_PH4_IMON"
					( Origin gPackager )
				)
				( objectStatus "ISENSE_PVCCIN_CPU0_PH4_IMON" )
			)
			( signal "@baseboard_fab2_lib.baseboard_fab2(sch_1):isense_pvccin_cpu0_ph5_imon"
				( attribute "CDS_PHYS_NET_NAME" "ISENSE_PVCCIN_CPU0_PH5_IMON"
					( Origin gPackager )
				)
				( objectStatus "ISENSE_PVCCIN_CPU0_PH5_IMON" )
			)
			( signal "@baseboard_fab2_lib.baseboard_fab2(sch_1):isense_pvsa_cpu0_imon"
				( attribute "CDS_PHYS_NET_NAME" "ISENSE_PVSA_CPU0_IMON"
					( Origin gPackager )
				)
				( objectStatus "ISENSE_PVSA_CPU0_IMON" )
			)
			( signal "@baseboard_fab2_lib.baseboard_fab2(sch_1):pu_vr_pvccin_cpu0_flt1_smbalt_n_imon"
				( attribute "CDS_PHYS_NET_NAME" "PU_VR_PVCCIN_CPU0_FLT1_SMBALT_N"
					( Origin gPackager )
				)
				( attribute "PNN" "PU_VR_PVCCIN_CPU0_FLT1_SMBALT_N"
					( Origin gPackager )
				)
				( objectStatus "PU_VR_PVCCIN_CPU0_FLT1_SMBALT_N" )
			)
			( signal "@baseboard_fab2_lib.baseboard_fab2(sch_1):pu_vr_pvccin_cpu0_imon"
				( attribute "CDS_PHYS_NET_NAME" "PU_VR_PVCCIN_CPU0_IMON"
					( Origin gPackager )
				)
				( objectStatus "PU_VR_PVCCIN_CPU0_IMON" )
			)
			( signal "@baseboard_fab2_lib.baseboard_fab2(sch_1):pvccin_pvsa_cpu0_iinsen"
				( alias ( signalRef "@baseboard_fab2_lib.baseboard_fab2(sch_1):page201_pvccin_pvsa_cpu0_iinsen") )
				( attribute "VOLTAGE" "+3.3V"
					( Units "uVoltage" "V" 1.000000)
					( Status sAliasFlattened )
					( Origin gFrontEnd )
				)
				( attribute "CDS_PHYS_NET_NAME" "PVCCIN_PVSA_CPU0_IINSEN"
					( Origin gPackager )
				)
				( objectStatus "PVCCIN_PVSA_CPU0_IINSEN" )
			)
			( signal "@baseboard_fab2_lib.baseboard_fab2(sch_1):page201_pvccin_pvsa_cpu0_iinsen"
				( attribute "VOLTAGE" "+3.3V"
					( Units "uVoltage" "V" 1.000000)
					( Origin gFrontEnd )
				)
				( objectFlag fObjectAlias )
				( objectStatus "page201_pvccin_pvsa_cpu0_iinsen" )
			)
			( signal "@baseboard_fab2_lib.baseboard_fab2(sch_1):pwrgd_pvsa_cpu0_r"
				( attribute "CDS_PHYS_NET_NAME" "PWRGD_PVSA_CPU0_R"
					( Origin gPackager )
				)
				( objectStatus "PWRGD_PVSA_CPU0_R" )
			)
			( signal "@baseboard_fab2_lib.baseboard_fab2(sch_1):smb_vr_scl_r"
				( attribute "CDS_PHYS_NET_NAME" "SMB_VR_SCL_R"
					( Origin gPackager )
				)
				( objectStatus "SMB_VR_SCL_R" )
			)
			( signal "@baseboard_fab2_lib.baseboard_fab2(sch_1):smb_vr_sda_r"
				( attribute "CDS_PHYS_NET_NAME" "SMB_VR_SDA_R"
					( Origin gPackager )
				)
				( objectStatus "SMB_VR_SDA_R" )
			)
			( signal "@baseboard_fab2_lib.baseboard_fab2(sch_1):svid_valert_vccin_cpu0"
				( attribute "CDS_PHYS_NET_NAME" "SVID_VALERT_VCCIN_CPU0"
					( Origin gPackager )
				)
				( objectStatus "SVID_VALERT_VCCIN_CPU0" )
			)
			( signal "@baseboard_fab2_lib.baseboard_fab2(sch_1):svid_vclk_pvccin_cpu0"
				( attribute "CDS_PHYS_NET_NAME" "SVID_VCLK_PVCCIN_CPU0"
					( Origin gPackager )
				)
				( objectStatus "SVID_VCLK_PVCCIN_CPU0" )
			)
			( signal "@baseboard_fab2_lib.baseboard_fab2(sch_1):svid_vdio_pvccin_cpu0"
				( attribute "CDS_PHYS_NET_NAME" "SVID_VDIO_PVCCIN_CPU0"
					( Origin gPackager )
				)
				( objectStatus "SVID_VDIO_PVCCIN_CPU0" )
			)
			( signal "@baseboard_fab2_lib.baseboard_fab2(sch_1):tp_pvccin_cpu0_airef6"
				( attribute "CDS_PHYS_NET_NAME" "TP_PVCCIN_CPU0_AIREF6"
					( Origin gPackager )
				)
				( objectStatus "TP_PVCCIN_CPU0_AIREF6" )
			)
			( signal "@baseboard_fab2_lib.baseboard_fab2(sch_1):tp_pvccin_cpu0_aisen6"
				( attribute "CDS_PHYS_NET_NAME" "TP_PVCCIN_CPU0_AISEN6"
					( Origin gPackager )
				)
				( objectStatus "TP_PVCCIN_CPU0_AISEN6" )
			)
			( signal "@baseboard_fab2_lib.baseboard_fab2(sch_1):tp_pvccin_cpu0_apwm6"
				( attribute "CDS_PHYS_NET_NAME" "TP_PVCCIN_CPU0_APWM6"
					( Origin gPackager )
				)
				( objectStatus "TP_PVCCIN_CPU0_APWM6" )
			)
			( signal "@baseboard_fab2_lib.baseboard_fab2(sch_1):tp_pvccin_cpu0_fault1_20"
				( attribute "CDS_PHYS_NET_NAME" "TP_PVCCIN_CPU0_FAULT1_20"
					( Origin gPackager )
				)
				( objectStatus "TP_PVCCIN_CPU0_FAULT1_20" )
			)
			( signal "@baseboard_fab2_lib.baseboard_fab2(sch_1):tp_pvccin_cpu0_gp1"
				( attribute "CDS_PHYS_NET_NAME" "TP_PVCCIN_CPU0_GP1"
					( Origin gPackager )
				)
				( objectStatus "TP_PVCCIN_CPU0_GP1" )
			)
			( signal "@baseboard_fab2_lib.baseboard_fab2(sch_1):tp_pvccin_cpu0_reset"
				( attribute "CDS_PHYS_NET_NAME" "TP_PVCCIN_CPU0_RESET"
					( Origin gPackager )
				)
				( objectStatus "TP_PVCCIN_CPU0_RESET" )
			)
			( signal "@baseboard_fab2_lib.baseboard_fab2(sch_1):vr_fet_sw_p12v_stby_pvccin_cpu0"
				( alias ( signalRef "@baseboard_fab2_lib.baseboard_fab2(sch_1):page201_vr_fet_sw_p12v_stby_pvccin_cpu0") )
				( alias ( signalRef "@baseboard_fab2_lib.baseboard_fab2(sch_1):page202_vr_fet_sw_p12v_stby_pvccin_cpu0") )
				( alias ( signalRef "@baseboard_fab2_lib.baseboard_fab2(sch_1):page203_vr_fet_sw_p12v_stby_pvccin_cpu0") )
				( alias ( signalRef "@baseboard_fab2_lib.baseboard_fab2(sch_1):page204_vr_fet_sw_p12v_stby_pvccin_cpu0") )
				( alias ( signalRef "@baseboard_fab2_lib.baseboard_fab2(sch_1):page205_vr_fet_sw_p12v_stby_pvccin_cpu0") )
				( alias ( signalRef "@baseboard_fab2_lib.baseboard_fab2(sch_1):page213_vr_fet_sw_p12v_stby_pvccin_cpu0") )
				( alias ( signalRef "@baseboard_fab2_lib.baseboard_fab2(sch_1):page214_vr_fet_sw_p12v_stby_pvccin_cpu0") )
				( attribute "CDS_PHYS_NET_NAME" "VR_FET_SW_P12V_STBY_PVCCIN_CPU0"
					( Origin gPackager )
				)
				( objectStatus "VR_FET_SW_P12V_STBY_PVCCIN_CPU0" )
			)
			( signal "@baseboard_fab2_lib.baseboard_fab2(sch_1):page201_vr_fet_sw_p12v_stby_pvccin_cpu0"
				( objectFlag fObjectAlias )
				( objectStatus "page201_vr_fet_sw_p12v_stby_pvccin_cpu0" )
			)
			( signal "@baseboard_fab2_lib.baseboard_fab2(sch_1):page202_vr_fet_sw_p12v_stby_pvccin_cpu0"
				( objectFlag fObjectAlias )
				( objectStatus "page202_vr_fet_sw_p12v_stby_pvccin_cpu0" )
			)
			( signal "@baseboard_fab2_lib.baseboard_fab2(sch_1):page203_vr_fet_sw_p12v_stby_pvccin_cpu0"
				( objectFlag fObjectAlias )
				( objectStatus "page203_vr_fet_sw_p12v_stby_pvccin_cpu0" )
			)
			( signal "@baseboard_fab2_lib.baseboard_fab2(sch_1):page204_vr_fet_sw_p12v_stby_pvccin_cpu0"
				( objectFlag fObjectAlias )
				( objectStatus "page204_vr_fet_sw_p12v_stby_pvccin_cpu0" )
			)
			( signal "@baseboard_fab2_lib.baseboard_fab2(sch_1):page205_vr_fet_sw_p12v_stby_pvccin_cpu0"
				( objectFlag fObjectAlias )
				( objectStatus "page205_vr_fet_sw_p12v_stby_pvccin_cpu0" )
			)
			( signal "@baseboard_fab2_lib.baseboard_fab2(sch_1):page213_vr_fet_sw_p12v_stby_pvccin_cpu0"
				( objectFlag fObjectAlias )
				( objectStatus "page213_vr_fet_sw_p12v_stby_pvccin_cpu0" )
			)
			( signal "@baseboard_fab2_lib.baseboard_fab2(sch_1):page214_vr_fet_sw_p12v_stby_pvccin_cpu0"
				( objectFlag fObjectAlias )
				( objectStatus "page214_vr_fet_sw_p12v_stby_pvccin_cpu0" )
			)
			( signal "@baseboard_fab2_lib.baseboard_fab2(sch_1):vr_pvccin_cpu0_airef1"
				( attribute "CDS_PHYS_NET_NAME" "VR_PVCCIN_CPU0_AIREF1"
					( Origin gPackager )
				)
				( objectStatus "VR_PVCCIN_CPU0_AIREF1" )
			)
			( signal "@baseboard_fab2_lib.baseboard_fab2(sch_1):vr_pvccin_cpu0_airef2"
				( attribute "CDS_PHYS_NET_NAME" "VR_PVCCIN_CPU0_AIREF2"
					( Origin gPackager )
				)
				( objectStatus "VR_PVCCIN_CPU0_AIREF2" )
			)
			( signal "@baseboard_fab2_lib.baseboard_fab2(sch_1):vr_pvccin_cpu0_airef3"
				( attribute "CDS_PHYS_NET_NAME" "VR_PVCCIN_CPU0_AIREF3"
					( Origin gPackager )
				)
				( objectStatus "VR_PVCCIN_CPU0_AIREF3" )
			)
			( signal "@baseboard_fab2_lib.baseboard_fab2(sch_1):vr_pvccin_cpu0_airef4"
				( attribute "CDS_PHYS_NET_NAME" "VR_PVCCIN_CPU0_AIREF4"
					( Origin gPackager )
				)
				( objectStatus "VR_PVCCIN_CPU0_AIREF4" )
			)
			( signal "@baseboard_fab2_lib.baseboard_fab2(sch_1):vr_pvccin_cpu0_airef5"
				( attribute "CDS_PHYS_NET_NAME" "VR_PVCCIN_CPU0_AIREF5"
					( Origin gPackager )
				)
				( objectStatus "VR_PVCCIN_CPU0_AIREF5" )
			)
			( signal "@baseboard_fab2_lib.baseboard_fab2(sch_1):vr_pvccin_cpu0_avinsen"
				( alias ( signalRef "@baseboard_fab2_lib.baseboard_fab2(sch_1):page201_vr_pvccin_cpu0_avinsen") )
				( attribute "VOLTAGE" "0.8"
					( Units "uVoltage" "V" 1.000000)
					( Status sAliasFlattened )
					( Origin gFrontEnd )
				)
				( attribute "CDS_PHYS_NET_NAME" "VR_PVCCIN_CPU0_AVINSEN"
					( Origin gPackager )
				)
				( objectStatus "VR_PVCCIN_CPU0_AVINSEN" )
			)
			( signal "@baseboard_fab2_lib.baseboard_fab2(sch_1):page201_vr_pvccin_cpu0_avinsen"
				( attribute "VOLTAGE" "0.8"
					( Units "uVoltage" "V" 1.000000)
					( Origin gFrontEnd )
				)
				( objectFlag fObjectAlias )
				( objectStatus "page201_vr_pvccin_cpu0_avinsen" )
			)
			( signal "@baseboard_fab2_lib.baseboard_fab2(sch_1):vr_pvccin_cpu0_pwm1"
				( alias ( signalRef "@baseboard_fab2_lib.baseboard_fab2(sch_1):page201_vr_pvccin_cpu0_pwm1") )
				( attribute "VOLTAGE" "3.6"
					( Units "uVoltage" "V" 1.000000)
					( Status sAliasFlattened )
					( Origin gFrontEnd )
				)
				( attribute "CDS_PHYS_NET_NAME" "VR_PVCCIN_CPU0_PWM1"
					( Origin gPackager )
				)
				( objectStatus "VR_PVCCIN_CPU0_PWM1" )
			)
			( signal "@baseboard_fab2_lib.baseboard_fab2(sch_1):page201_vr_pvccin_cpu0_pwm1"
				( attribute "VOLTAGE" "3.6"
					( Units "uVoltage" "V" 1.000000)
					( Origin gFrontEnd )
				)
				( objectFlag fObjectAlias )
				( objectStatus "page201_vr_pvccin_cpu0_pwm1" )
			)
			( signal "@baseboard_fab2_lib.baseboard_fab2(sch_1):vr_pvccin_cpu0_pwm2"
				( alias ( signalRef "@baseboard_fab2_lib.baseboard_fab2(sch_1):page201_vr_pvccin_cpu0_pwm2") )
				( attribute "VOLTAGE" "3.6"
					( Units "uVoltage" "V" 1.000000)
					( Status sAliasFlattened )
					( Origin gFrontEnd )
				)
				( attribute "CDS_PHYS_NET_NAME" "VR_PVCCIN_CPU0_PWM2"
					( Origin gPackager )
				)
				( objectStatus "VR_PVCCIN_CPU0_PWM2" )
			)
			( signal "@baseboard_fab2_lib.baseboard_fab2(sch_1):page201_vr_pvccin_cpu0_pwm2"
				( attribute "VOLTAGE" "3.6"
					( Units "uVoltage" "V" 1.000000)
					( Origin gFrontEnd )
				)
				( objectFlag fObjectAlias )
				( objectStatus "page201_vr_pvccin_cpu0_pwm2" )
			)
			( signal "@baseboard_fab2_lib.baseboard_fab2(sch_1):vr_pvccin_cpu0_pwm3"
				( alias ( signalRef "@baseboard_fab2_lib.baseboard_fab2(sch_1):page201_vr_pvccin_cpu0_pwm3") )
				( attribute "VOLTAGE" "3.6"
					( Units "uVoltage" "V" 1.000000)
					( Status sAliasFlattened )
					( Origin gFrontEnd )
				)
				( attribute "CDS_PHYS_NET_NAME" "VR_PVCCIN_CPU0_PWM3"
					( Origin gPackager )
				)
				( objectStatus "VR_PVCCIN_CPU0_PWM3" )
			)
			( signal "@baseboard_fab2_lib.baseboard_fab2(sch_1):page201_vr_pvccin_cpu0_pwm3"
				( attribute "VOLTAGE" "3.6"
					( Units "uVoltage" "V" 1.000000)
					( Origin gFrontEnd )
				)
				( objectFlag fObjectAlias )
				( objectStatus "page201_vr_pvccin_cpu0_pwm3" )
			)
			( signal "@baseboard_fab2_lib.baseboard_fab2(sch_1):vr_pvccin_cpu0_pwm4"
				( alias ( signalRef "@baseboard_fab2_lib.baseboard_fab2(sch_1):page201_vr_pvccin_cpu0_pwm4") )
				( attribute "VOLTAGE" "3.6"
					( Units "uVoltage" "V" 1.000000)
					( Status sAliasFlattened )
					( Origin gFrontEnd )
				)
				( attribute "CDS_PHYS_NET_NAME" "VR_PVCCIN_CPU0_PWM4"
					( Origin gPackager )
				)
				( objectStatus "VR_PVCCIN_CPU0_PWM4" )
			)
			( signal "@baseboard_fab2_lib.baseboard_fab2(sch_1):page201_vr_pvccin_cpu0_pwm4"
				( attribute "VOLTAGE" "3.6"
					( Units "uVoltage" "V" 1.000000)
					( Origin gFrontEnd )
				)
				( objectFlag fObjectAlias )
				( objectStatus "page201_vr_pvccin_cpu0_pwm4" )
			)
			( signal "@baseboard_fab2_lib.baseboard_fab2(sch_1):vr_pvccin_cpu0_pwm5"
				( alias ( signalRef "@baseboard_fab2_lib.baseboard_fab2(sch_1):page201_vr_pvccin_cpu0_pwm5") )
				( attribute "VOLTAGE" "3.6"
					( Units "uVoltage" "V" 1.000000)
					( Status sAliasFlattened )
					( Origin gFrontEnd )
				)
				( attribute "CDS_PHYS_NET_NAME" "VR_PVCCIN_CPU0_PWM5"
					( Origin gPackager )
				)
				( objectStatus "VR_PVCCIN_CPU0_PWM5" )
			)
			( signal "@baseboard_fab2_lib.baseboard_fab2(sch_1):page201_vr_pvccin_cpu0_pwm5"
				( attribute "VOLTAGE" "3.6"
					( Units "uVoltage" "V" 1.000000)
					( Origin gFrontEnd )
				)
				( objectFlag fObjectAlias )
				( objectStatus "page201_vr_pvccin_cpu0_pwm5" )
			)
			( signal "@baseboard_fab2_lib.baseboard_fab2(sch_1):vr_pvccin_cpu0_vd12"
				( attribute "CDS_PHYS_NET_NAME" "VR_PVCCIN_CPU0_VD12"
					( Origin gPackager )
				)
				( objectStatus "VR_PVCCIN_CPU0_VD12" )
			)
			( signal "@baseboard_fab2_lib.baseboard_fab2(sch_1):vr_pvccin_cpu0_vdd"
				( alias ( signalRef "@baseboard_fab2_lib.baseboard_fab2(sch_1):page201_vr_pvccin_cpu0_vdd") )
				( attribute "VOLTAGE" "3.3"
					( Units "uVoltage" "V" 1.000000)
					( Status sAliasFlattened )
					( Origin gFrontEnd )
				)
				( attribute "CDS_PHYS_NET_NAME" "VR_PVCCIN_CPU0_VDD"
					( Origin gPackager )
				)
				( objectStatus "VR_PVCCIN_CPU0_VDD" )
			)
			( signal "@baseboard_fab2_lib.baseboard_fab2(sch_1):page201_vr_pvccin_cpu0_vdd"
				( attribute "VOLTAGE" "3.3"
					( Units "uVoltage" "V" 1.000000)
					( Origin gFrontEnd )
				)
				( objectFlag fObjectAlias )
				( objectStatus "page201_vr_pvccin_cpu0_vdd" )
			)
			( signal "@baseboard_fab2_lib.baseboard_fab2(sch_1):vr_pvccin_cpu0_vren"
				( alias ( signalRef "@baseboard_fab2_lib.baseboard_fab2(sch_1):page201_vr_pvccin_cpu0_vren") )
				( attribute "VOLTAGE" "3.3"
					( Units "uVoltage" "V" 1.000000)
					( Status sAliasFlattened )
					( Origin gFrontEnd )
				)
				( attribute "CDS_PHYS_NET_NAME" "VR_PVCCIN_CPU0_VREN"
					( Origin gPackager )
				)
				( objectStatus "VR_PVCCIN_CPU0_VREN" )
			)
			( signal "@baseboard_fab2_lib.baseboard_fab2(sch_1):page201_vr_pvccin_cpu0_vren"
				( attribute "VOLTAGE" "3.3"
					( Units "uVoltage" "V" 1.000000)
					( Origin gFrontEnd )
				)
				( objectFlag fObjectAlias )
				( objectStatus "page201_vr_pvccin_cpu0_vren" )
			)
			( signal "@baseboard_fab2_lib.baseboard_fab2(sch_1):vr_pvccin_cpu0_xaddr1"
				( alias ( signalRef "@baseboard_fab2_lib.baseboard_fab2(sch_1):page201_vr_pvccin_cpu0_xaddr1") )
				( attribute "VOLTAGE" "3.3"
					( Units "uVoltage" "V" 1.000000)
					( Status sAliasFlattened )
					( Origin gFrontEnd )
				)
				( attribute "CDS_PHYS_NET_NAME" "VR_PVCCIN_CPU0_XADDR1"
					( Origin gPackager )
				)
				( objectStatus "VR_PVCCIN_CPU0_XADDR1" )
			)
			( signal "@baseboard_fab2_lib.baseboard_fab2(sch_1):page201_vr_pvccin_cpu0_xaddr1"
				( attribute "VOLTAGE" "3.3"
					( Units "uVoltage" "V" 1.000000)
					( Origin gFrontEnd )
				)
				( objectFlag fObjectAlias )
				( objectStatus "page201_vr_pvccin_cpu0_xaddr1" )
			)
			( signal "@baseboard_fab2_lib.baseboard_fab2(sch_1):vr_pvccin_cpu0_xaddr2"
				( alias ( signalRef "@baseboard_fab2_lib.baseboard_fab2(sch_1):page201_vr_pvccin_cpu0_xaddr2") )
				( attribute "VOLTAGE" "3.3"
					( Units "uVoltage" "V" 1.000000)
					( Status sAliasFlattened )
					( Origin gFrontEnd )
				)
				( attribute "CDS_PHYS_NET_NAME" "VR_PVCCIN_CPU0_XADDR2"
					( Origin gPackager )
				)
				( objectStatus "VR_PVCCIN_CPU0_XADDR2" )
			)
			( signal "@baseboard_fab2_lib.baseboard_fab2(sch_1):page201_vr_pvccin_cpu0_xaddr2"
				( attribute "VOLTAGE" "3.3"
					( Units "uVoltage" "V" 1.000000)
					( Origin gFrontEnd )
				)
				( objectFlag fObjectAlias )
				( objectStatus "page201_vr_pvccin_cpu0_xaddr2" )
			)
			( signal "@baseboard_fab2_lib.baseboard_fab2(sch_1):vr_pvsa_cpu0_biref1"
				( attribute "CDS_PHYS_NET_NAME" "VR_PVSA_CPU0_BIREF1"
					( Origin gPackager )
				)
				( objectStatus "VR_PVSA_CPU0_BIREF1" )
			)
			( signal "@baseboard_fab2_lib.baseboard_fab2(sch_1):vr_pvsa_cpu0_pwm"
				( attribute "CDS_PHYS_NET_NAME" "VR_PVSA_CPU0_PWM"
					( Origin gPackager )
				)
				( objectStatus "VR_PVSA_CPU0_PWM" )
			)
			( signal "@baseboard_fab2_lib.baseboard_fab2(sch_1):vr_vrrdy_pvccin_cpu0"
				( alias ( signalRef "@baseboard_fab2_lib.baseboard_fab2(sch_1):page201_vr_vrrdy_pvccin_cpu0") )
				( attribute "VOLTAGE" "3.3"
					( Units "uVoltage" "V" 1.000000)
					( Status sAliasFlattened )
					( Origin gFrontEnd )
				)
				( attribute "CDS_PHYS_NET_NAME" "VR_VRRDY_PVCCIN_CPU0"
					( Origin gPackager )
				)
				( objectStatus "VR_VRRDY_PVCCIN_CPU0" )
			)
			( signal "@baseboard_fab2_lib.baseboard_fab2(sch_1):page201_vr_vrrdy_pvccin_cpu0"
				( attribute "VOLTAGE" "3.3"
					( Units "uVoltage" "V" 1.000000)
					( Origin gFrontEnd )
				)
				( objectFlag fObjectAlias )
				( objectStatus "page201_vr_vrrdy_pvccin_cpu0" )
			)
			( signal "@baseboard_fab2_lib.baseboard_fab2(sch_1):vsense_pvccin_cpu0_avsp"
				( attribute "CDS_PHYS_NET_NAME" "VSENSE_PVCCIN_CPU0_AVSP"
					( Origin gPackager )
				)
				( objectStatus "VSENSE_PVCCIN_CPU0_AVSP" )
			)
			( signal "@baseboard_fab2_lib.baseboard_fab2(sch_1):vsense_pvccin_cpu0_n"
				( attribute "CDS_PHYS_NET_NAME" "VSENSE_PVCCIN_CPU0_N"
					( Origin gPackager )
				)
				( objectStatus "VSENSE_PVCCIN_CPU0_N" )
			)
			( signal "@baseboard_fab2_lib.baseboard_fab2(sch_1):vsense_pvccin_cpu0_p"
				( attribute "CDS_PHYS_NET_NAME" "VSENSE_PVCCIN_CPU0_P"
					( Origin gPackager )
				)
				( objectStatus "VSENSE_PVCCIN_CPU0_P" )
			)
			( signal "@baseboard_fab2_lib.baseboard_fab2(sch_1):vsense_pvsa_cpu0_bvsp"
				( attribute "CDS_PHYS_NET_NAME" "VSENSE_PVSA_CPU0_BVSP"
					( Origin gPackager )
				)
				( objectStatus "VSENSE_PVSA_CPU0_BVSP" )
			)
			( signal "@baseboard_fab2_lib.baseboard_fab2(sch_1):vsense_pvsa_cpu0_n"
				( attribute "CDS_PHYS_NET_NAME" "VSENSE_PVSA_CPU0_N"
					( Origin gPackager )
				)
				( objectStatus "VSENSE_PVSA_CPU0_N" )
			)
			( signal "@baseboard_fab2_lib.baseboard_fab2(sch_1):vsense_pvsa_cpu0_p"
				( attribute "CDS_PHYS_NET_NAME" "VSENSE_PVSA_CPU0_P"
					( Origin gPackager )
				)
				( objectStatus "VSENSE_PVSA_CPU0_P" )
			)
			( signal "@baseboard_fab2_lib.baseboard_fab2(sch_1):nc_pvccin_cpu0_ph1_p31"
				( attribute "CDS_PHYS_NET_NAME" "NC_PVCCIN_CPU0_PH1_P31"
					( Origin gPackager )
				)
				( objectStatus "NC_PVCCIN_CPU0_PH1_P31" )
			)
			( signal "@baseboard_fab2_lib.baseboard_fab2(sch_1):nc_pvccin_cpu0_ph2_p31"
				( attribute "CDS_PHYS_NET_NAME" "NC_PVCCIN_CPU0_PH2_P31"
					( Origin gPackager )
				)
				( objectStatus "NC_PVCCIN_CPU0_PH2_P31" )
			)
			( signal "@baseboard_fab2_lib.baseboard_fab2(sch_1):tp_pvccin_cpu0_ph1_gl_0"
				( attribute "CDS_PHYS_NET_NAME" "TP_PVCCIN_CPU0_PH1_GL_0"
					( Origin gPackager )
				)
				( objectStatus "TP_PVCCIN_CPU0_PH1_GL_0" )
			)
			( signal "@baseboard_fab2_lib.baseboard_fab2(sch_1):tp_pvccin_cpu0_ph1_gl_1"
				( attribute "CDS_PHYS_NET_NAME" "TP_PVCCIN_CPU0_PH1_GL_1"
					( Origin gPackager )
				)
				( objectStatus "TP_PVCCIN_CPU0_PH1_GL_1" )
			)
			( signal "@baseboard_fab2_lib.baseboard_fab2(sch_1):tp_pvccin_cpu0_ph2_gl_0"
				( attribute "CDS_PHYS_NET_NAME" "TP_PVCCIN_CPU0_PH2_GL_0"
					( Origin gPackager )
				)
				( objectStatus "TP_PVCCIN_CPU0_PH2_GL_0" )
			)
			( signal "@baseboard_fab2_lib.baseboard_fab2(sch_1):tp_pvccin_cpu0_ph2_gl_1"
				( attribute "CDS_PHYS_NET_NAME" "TP_PVCCIN_CPU0_PH2_GL_1"
					( Origin gPackager )
				)
				( objectStatus "TP_PVCCIN_CPU0_PH2_GL_1" )
			)
			( signal "@baseboard_fab2_lib.baseboard_fab2(sch_1):vr_pvccin_cpu0_ph1_boot"
				( attribute "CDS_PHYS_NET_NAME" "VR_PVCCIN_CPU0_PH1_BOOT"
					( Origin gPackager )
				)
				( objectStatus "VR_PVCCIN_CPU0_PH1_BOOT" )
			)
			( signal "@baseboard_fab2_lib.baseboard_fab2(sch_1):\unnamed_202_3d01r5f-gp_i75_2\"
				( attribute "CDS_PHYS_NET_NAME" "UNNAMED_202_3D01R5F-GP_I75_2"
					( Origin gPackager )
				)
				( objectStatus "UNNAMED_202_3D01R5F-GP_I75_2" )
			)
			( signal "@baseboard_fab2_lib.baseboard_fab2(sch_1):vr_pvccin_cpu0_ph1_ocset"
				( attribute "CDS_PHYS_NET_NAME" "VR_PVCCIN_CPU0_PH1_OCSET"
					( Origin gPackager )
				)
				( objectStatus "VR_PVCCIN_CPU0_PH1_OCSET" )
			)
			( signal "@baseboard_fab2_lib.baseboard_fab2(sch_1):vr_pvccin_cpu0_ph1_phase"
				( alias ( signalRef "@baseboard_fab2_lib.baseboard_fab2(sch_1):page202_vr_pvccin_cpu0_ph1_phase") )
				( attribute "VOLTAGE" "5"
					( Units "uVoltage" "V" 1.000000)
					( Status sAliasFlattened )
					( Origin gFrontEnd )
				)
				( attribute "CDS_PHYS_NET_NAME" "VR_PVCCIN_CPU0_PH1_PHASE"
					( Origin gPackager )
				)
				( objectStatus "VR_PVCCIN_CPU0_PH1_PHASE" )
			)
			( signal "@baseboard_fab2_lib.baseboard_fab2(sch_1):page202_vr_pvccin_cpu0_ph1_phase"
				( attribute "VOLTAGE" "5"
					( Units "uVoltage" "V" 1.000000)
					( Origin gFrontEnd )
				)
				( objectFlag fObjectAlias )
				( objectStatus "page202_vr_pvccin_cpu0_ph1_phase" )
			)
			( signal "@baseboard_fab2_lib.baseboard_fab2(sch_1):vr_pvccin_cpu0_ph1_vcin"
				( alias ( signalRef "@baseboard_fab2_lib.baseboard_fab2(sch_1):page202_vr_pvccin_cpu0_ph1_vcin") )
				( attribute "VOLTAGE" "5"
					( Units "uVoltage" "V" 1.000000)
					( Status sAliasFlattened )
					( Origin gFrontEnd )
				)
				( attribute "CDS_PHYS_NET_NAME" "VR_PVCCIN_CPU0_PH1_VCIN"
					( Origin gPackager )
				)
				( objectStatus "VR_PVCCIN_CPU0_PH1_VCIN" )
			)
			( signal "@baseboard_fab2_lib.baseboard_fab2(sch_1):page202_vr_pvccin_cpu0_ph1_vcin"
				( attribute "VOLTAGE" "5"
					( Units "uVoltage" "V" 1.000000)
					( Origin gFrontEnd )
				)
				( objectFlag fObjectAlias )
				( objectStatus "page202_vr_pvccin_cpu0_ph1_vcin" )
			)
			( signal "@baseboard_fab2_lib.baseboard_fab2(sch_1):vr_pvccin_cpu0_ph2_boot"
				( attribute "CDS_PHYS_NET_NAME" "VR_PVCCIN_CPU0_PH2_BOOT"
					( Origin gPackager )
				)
				( attribute "VOLTAGE" "5"
					( Units "uVoltage" "V" 1.000000)
					( Origin gFrontEnd )
				)
				( objectStatus "VR_PVCCIN_CPU0_PH2_BOOT" )
			)
			( signal "@baseboard_fab2_lib.baseboard_fab2(sch_1):\unnamed_209_3d01r5f-gp_i66_2\"
				( attribute "CDS_PHYS_NET_NAME" "UNNAMED_209_3D01R5F-GP_I66_2"
					( Origin gPackager )
				)
				( objectStatus "UNNAMED_209_3D01R5F-GP_I66_2" )
			)
			( signal "@baseboard_fab2_lib.baseboard_fab2(sch_1):vr_pvccin_cpu0_ph2_ocset"
				( alias ( signalRef "@baseboard_fab2_lib.baseboard_fab2(sch_1):page202_vr_pvccin_cpu0_ph2_ocset") )
				( attribute "VOLTAGE" "3.6"
					( Units "uVoltage" "V" 1.000000)
					( Status sAliasFlattened )
					( Origin gFrontEnd )
				)
				( attribute "CDS_PHYS_NET_NAME" "VR_PVCCIN_CPU0_PH2_OCSET"
					( Origin gPackager )
				)
				( objectStatus "VR_PVCCIN_CPU0_PH2_OCSET" )
			)
			( signal "@baseboard_fab2_lib.baseboard_fab2(sch_1):page202_vr_pvccin_cpu0_ph2_ocset"
				( attribute "VOLTAGE" "3.6"
					( Units "uVoltage" "V" 1.000000)
					( Origin gFrontEnd )
				)
				( objectFlag fObjectAlias )
				( objectStatus "page202_vr_pvccin_cpu0_ph2_ocset" )
			)
			( signal "@baseboard_fab2_lib.baseboard_fab2(sch_1):vr_pvccin_cpu0_ph2_phase"
				( alias ( signalRef "@baseboard_fab2_lib.baseboard_fab2(sch_1):page202_vr_pvccin_cpu0_ph2_phase") )
				( attribute "VOLTAGE" "5"
					( Units "uVoltage" "V" 1.000000)
					( Status sAliasFlattened )
					( Origin gFrontEnd )
				)
				( attribute "CDS_PHYS_NET_NAME" "VR_PVCCIN_CPU0_PH2_PHASE"
					( Origin gPackager )
				)
				( objectStatus "VR_PVCCIN_CPU0_PH2_PHASE" )
			)
			( signal "@baseboard_fab2_lib.baseboard_fab2(sch_1):page202_vr_pvccin_cpu0_ph2_phase"
				( attribute "VOLTAGE" "5"
					( Units "uVoltage" "V" 1.000000)
					( Origin gFrontEnd )
				)
				( objectFlag fObjectAlias )
				( objectStatus "page202_vr_pvccin_cpu0_ph2_phase" )
			)
			( signal "@baseboard_fab2_lib.baseboard_fab2(sch_1):vr_pvccin_cpu0_ph2_vcin"
				( alias ( signalRef "@baseboard_fab2_lib.baseboard_fab2(sch_1):page202_vr_pvccin_cpu0_ph2_vcin") )
				( attribute "VOLTAGE" "5"
					( Units "uVoltage" "V" 1.000000)
					( Status sAliasFlattened )
					( Origin gFrontEnd )
				)
				( attribute "CDS_PHYS_NET_NAME" "VR_PVCCIN_CPU0_PH2_VCIN"
					( Origin gPackager )
				)
				( objectStatus "VR_PVCCIN_CPU0_PH2_VCIN" )
			)
			( signal "@baseboard_fab2_lib.baseboard_fab2(sch_1):page202_vr_pvccin_cpu0_ph2_vcin"
				( attribute "VOLTAGE" "5"
					( Units "uVoltage" "V" 1.000000)
					( Origin gFrontEnd )
				)
				( objectFlag fObjectAlias )
				( objectStatus "page202_vr_pvccin_cpu0_ph2_vcin" )
			)
			( signal "@baseboard_fab2_lib.baseboard_fab2(sch_1):vr_pvccin_cpu0_phase1"
				( alias ( signalRef "@baseboard_fab2_lib.baseboard_fab2(sch_1):page202_vr_pvccin_cpu0_phase1") )
				( attribute "VOLTAGE" "5"
					( Units "uVoltage" "V" 1.000000)
					( Status sAliasFlattened )
					( Origin gFrontEnd )
				)
				( attribute "CDS_PHYS_NET_NAME" "VR_PVCCIN_CPU0_PHASE1"
					( Origin gPackager )
				)
				( objectStatus "VR_PVCCIN_CPU0_PHASE1" )
			)
			( signal "@baseboard_fab2_lib.baseboard_fab2(sch_1):page202_vr_pvccin_cpu0_phase1"
				( attribute "VOLTAGE" "5"
					( Units "uVoltage" "V" 1.000000)
					( Origin gFrontEnd )
				)
				( objectFlag fObjectAlias )
				( objectStatus "page202_vr_pvccin_cpu0_phase1" )
			)
			( signal "@baseboard_fab2_lib.baseboard_fab2(sch_1):vr_pvccin_cpu0_phase2"
				( alias ( signalRef "@baseboard_fab2_lib.baseboard_fab2(sch_1):page202_vr_pvccin_cpu0_phase2") )
				( attribute "VOLTAGE" "5"
					( Units "uVoltage" "V" 1.000000)
					( Status sAliasFlattened )
					( Origin gFrontEnd )
				)
				( attribute "CDS_PHYS_NET_NAME" "VR_PVCCIN_CPU0_PHASE2"
					( Origin gPackager )
				)
				( objectStatus "VR_PVCCIN_CPU0_PHASE2" )
			)
			( signal "@baseboard_fab2_lib.baseboard_fab2(sch_1):page202_vr_pvccin_cpu0_phase2"
				( attribute "VOLTAGE" "5"
					( Units "uVoltage" "V" 1.000000)
					( Origin gFrontEnd )
				)
				( objectFlag fObjectAlias )
				( objectStatus "page202_vr_pvccin_cpu0_phase2" )
			)
			( signal "@baseboard_fab2_lib.baseboard_fab2(sch_1):nc_pvccin_cpu0_ph3_p31"
				( attribute "CDS_PHYS_NET_NAME" "NC_PVCCIN_CPU0_PH3_P31"
					( Origin gPackager )
				)
				( objectStatus "NC_PVCCIN_CPU0_PH3_P31" )
			)
			( signal "@baseboard_fab2_lib.baseboard_fab2(sch_1):nc_pvccin_cpu0_ph4_p31"
				( attribute "CDS_PHYS_NET_NAME" "NC_PVCCIN_CPU0_PH4_P31"
					( Origin gPackager )
				)
				( objectStatus "NC_PVCCIN_CPU0_PH4_P31" )
			)
			( signal "@baseboard_fab2_lib.baseboard_fab2(sch_1):tp_pvccin_cpu0_ph3_gl_0"
				( attribute "CDS_PHYS_NET_NAME" "TP_PVCCIN_CPU0_PH3_GL_0"
					( Origin gPackager )
				)
				( objectStatus "TP_PVCCIN_CPU0_PH3_GL_0" )
			)
			( signal "@baseboard_fab2_lib.baseboard_fab2(sch_1):tp_pvccin_cpu0_ph3_gl_1"
				( attribute "CDS_PHYS_NET_NAME" "TP_PVCCIN_CPU0_PH3_GL_1"
					( Origin gPackager )
				)
				( objectStatus "TP_PVCCIN_CPU0_PH3_GL_1" )
			)
			( signal "@baseboard_fab2_lib.baseboard_fab2(sch_1):tp_pvccin_cpu0_ph4_gl_0"
				( attribute "CDS_PHYS_NET_NAME" "TP_PVCCIN_CPU0_PH4_GL_0"
					( Origin gPackager )
				)
				( objectStatus "TP_PVCCIN_CPU0_PH4_GL_0" )
			)
			( signal "@baseboard_fab2_lib.baseboard_fab2(sch_1):tp_pvccin_cpu0_ph4_gl_1"
				( attribute "CDS_PHYS_NET_NAME" "TP_PVCCIN_CPU0_PH4_GL_1"
					( Origin gPackager )
				)
				( objectStatus "TP_PVCCIN_CPU0_PH4_GL_1" )
			)
			( signal "@baseboard_fab2_lib.baseboard_fab2(sch_1):vr_pvccin_cpu0_ph3_boot"
				( attribute "CDS_PHYS_NET_NAME" "VR_PVCCIN_CPU0_PH3_BOOT"
					( Origin gPackager )
				)
				( objectStatus "VR_PVCCIN_CPU0_PH3_BOOT" )
			)
			( signal "@baseboard_fab2_lib.baseboard_fab2(sch_1):\unnamed_219_3d01r5f-gp_i123_2\"
				( attribute "CDS_PHYS_NET_NAME" "UNNAMED_219_3D01R5F-GP_I123_2"
					( Origin gPackager )
				)
				( objectStatus "UNNAMED_219_3D01R5F-GP_I123_2" )
			)
			( signal "@baseboard_fab2_lib.baseboard_fab2(sch_1):vr_pvccin_cpu0_ph3_ocset"
				( alias ( signalRef "@baseboard_fab2_lib.baseboard_fab2(sch_1):page203_vr_pvccin_cpu0_ph3_ocset") )
				( attribute "VOLTAGE" "3.6"
					( Units "uVoltage" "V" 1.000000)
					( Status sAliasFlattened )
					( Origin gFrontEnd )
				)
				( attribute "CDS_PHYS_NET_NAME" "VR_PVCCIN_CPU0_PH3_OCSET"
					( Origin gPackager )
				)
				( objectStatus "VR_PVCCIN_CPU0_PH3_OCSET" )
			)
			( signal "@baseboard_fab2_lib.baseboard_fab2(sch_1):page203_vr_pvccin_cpu0_ph3_ocset"
				( attribute "VOLTAGE" "3.6"
					( Units "uVoltage" "V" 1.000000)
					( Origin gFrontEnd )
				)
				( objectFlag fObjectAlias )
				( objectStatus "page203_vr_pvccin_cpu0_ph3_ocset" )
			)
			( signal "@baseboard_fab2_lib.baseboard_fab2(sch_1):vr_pvccin_cpu0_ph3_phase"
				( alias ( signalRef "@baseboard_fab2_lib.baseboard_fab2(sch_1):page203_vr_pvccin_cpu0_ph3_phase") )
				( attribute "VOLTAGE" "5"
					( Units "uVoltage" "V" 1.000000)
					( Status sAliasFlattened )
					( Origin gFrontEnd )
				)
				( attribute "CDS_PHYS_NET_NAME" "VR_PVCCIN_CPU0_PH3_PHASE"
					( Origin gPackager )
				)
				( objectStatus "VR_PVCCIN_CPU0_PH3_PHASE" )
			)
			( signal "@baseboard_fab2_lib.baseboard_fab2(sch_1):page203_vr_pvccin_cpu0_ph3_phase"
				( attribute "VOLTAGE" "5"
					( Units "uVoltage" "V" 1.000000)
					( Origin gFrontEnd )
				)
				( objectFlag fObjectAlias )
				( objectStatus "page203_vr_pvccin_cpu0_ph3_phase" )
			)
			( signal "@baseboard_fab2_lib.baseboard_fab2(sch_1):vr_pvccin_cpu0_ph3_vcin"
				( attribute "CDS_PHYS_NET_NAME" "VR_PVCCIN_CPU0_PH3_VCIN"
					( Origin gPackager )
				)
				( objectStatus "VR_PVCCIN_CPU0_PH3_VCIN" )
			)
			( signal "@baseboard_fab2_lib.baseboard_fab2(sch_1):vr_pvccin_cpu0_ph4_boot"
				( attribute "CDS_PHYS_NET_NAME" "VR_PVCCIN_CPU0_PH4_BOOT"
					( Origin gPackager )
				)
				( objectStatus "VR_PVCCIN_CPU0_PH4_BOOT" )
			)
			( signal "@baseboard_fab2_lib.baseboard_fab2(sch_1):\unnamed_216_3d01r5f-gp_i114_2\"
				( attribute "CDS_PHYS_NET_NAME" "UNNAMED_216_3D01R5F-GP_I114_2"
					( Origin gPackager )
				)
				( objectStatus "UNNAMED_216_3D01R5F-GP_I114_2" )
			)
			( signal "@baseboard_fab2_lib.baseboard_fab2(sch_1):vr_pvccin_cpu0_ph4_ocset"
				( alias ( signalRef "@baseboard_fab2_lib.baseboard_fab2(sch_1):page203_vr_pvccin_cpu0_ph4_ocset") )
				( attribute "VOLTAGE" "3.6"
					( Units "uVoltage" "V" 1.000000)
					( Status sAliasFlattened )
					( Origin gFrontEnd )
				)
				( attribute "CDS_PHYS_NET_NAME" "VR_PVCCIN_CPU0_PH4_OCSET"
					( Origin gPackager )
				)
				( objectStatus "VR_PVCCIN_CPU0_PH4_OCSET" )
			)
			( signal "@baseboard_fab2_lib.baseboard_fab2(sch_1):page203_vr_pvccin_cpu0_ph4_ocset"
				( attribute "VOLTAGE" "3.6"
					( Units "uVoltage" "V" 1.000000)
					( Origin gFrontEnd )
				)
				( objectFlag fObjectAlias )
				( objectStatus "page203_vr_pvccin_cpu0_ph4_ocset" )
			)
			( signal "@baseboard_fab2_lib.baseboard_fab2(sch_1):vr_pvccin_cpu0_ph4_phase"
				( alias ( signalRef "@baseboard_fab2_lib.baseboard_fab2(sch_1):page203_vr_pvccin_cpu0_ph4_phase") )
				( attribute "VOLTAGE" "5"
					( Units "uVoltage" "V" 1.000000)
					( Status sAliasFlattened )
					( Origin gFrontEnd )
				)
				( attribute "CDS_PHYS_NET_NAME" "VR_PVCCIN_CPU0_PH4_PHASE"
					( Origin gPackager )
				)
				( objectStatus "VR_PVCCIN_CPU0_PH4_PHASE" )
			)
			( signal "@baseboard_fab2_lib.baseboard_fab2(sch_1):page203_vr_pvccin_cpu0_ph4_phase"
				( attribute "VOLTAGE" "5"
					( Units "uVoltage" "V" 1.000000)
					( Origin gFrontEnd )
				)
				( objectFlag fObjectAlias )
				( objectStatus "page203_vr_pvccin_cpu0_ph4_phase" )
			)
			( signal "@baseboard_fab2_lib.baseboard_fab2(sch_1):vr_pvccin_cpu0_ph4_vcin"
				( alias ( signalRef "@baseboard_fab2_lib.baseboard_fab2(sch_1):page203_vr_pvccin_cpu0_ph4_vcin") )
				( attribute "VOLTAGE" "5"
					( Units "uVoltage" "V" 1.000000)
					( Status sAliasFlattened )
					( Origin gFrontEnd )
				)
				( attribute "CDS_PHYS_NET_NAME" "VR_PVCCIN_CPU0_PH4_VCIN"
					( Origin gPackager )
				)
				( objectStatus "VR_PVCCIN_CPU0_PH4_VCIN" )
			)
			( signal "@baseboard_fab2_lib.baseboard_fab2(sch_1):page203_vr_pvccin_cpu0_ph4_vcin"
				( attribute "VOLTAGE" "5"
					( Units "uVoltage" "V" 1.000000)
					( Origin gFrontEnd )
				)
				( objectFlag fObjectAlias )
				( objectStatus "page203_vr_pvccin_cpu0_ph4_vcin" )
			)
			( signal "@baseboard_fab2_lib.baseboard_fab2(sch_1):vr_pvccin_cpu0_phase3"
				( alias ( signalRef "@baseboard_fab2_lib.baseboard_fab2(sch_1):page203_vr_pvccin_cpu0_phase3") )
				( attribute "VOLTAGE" "5"
					( Units "uVoltage" "V" 1.000000)
					( Status sAliasFlattened )
					( Origin gFrontEnd )
				)
				( attribute "CDS_PHYS_NET_NAME" "VR_PVCCIN_CPU0_PHASE3"
					( Origin gPackager )
				)
				( objectStatus "VR_PVCCIN_CPU0_PHASE3" )
			)
			( signal "@baseboard_fab2_lib.baseboard_fab2(sch_1):page203_vr_pvccin_cpu0_phase3"
				( attribute "VOLTAGE" "5"
					( Units "uVoltage" "V" 1.000000)
					( Origin gFrontEnd )
				)
				( objectFlag fObjectAlias )
				( objectStatus "page203_vr_pvccin_cpu0_phase3" )
			)
			( signal "@baseboard_fab2_lib.baseboard_fab2(sch_1):vr_pvccin_cpu0_phase4"
				( alias ( signalRef "@baseboard_fab2_lib.baseboard_fab2(sch_1):page203_vr_pvccin_cpu0_phase4") )
				( attribute "VOLTAGE" "5"
					( Units "uVoltage" "V" 1.000000)
					( Status sAliasFlattened )
					( Origin gFrontEnd )
				)
				( attribute "CDS_PHYS_NET_NAME" "VR_PVCCIN_CPU0_PHASE4"
					( Origin gPackager )
				)
				( objectStatus "VR_PVCCIN_CPU0_PHASE4" )
			)
			( signal "@baseboard_fab2_lib.baseboard_fab2(sch_1):page203_vr_pvccin_cpu0_phase4"
				( attribute "VOLTAGE" "5"
					( Units "uVoltage" "V" 1.000000)
					( Origin gFrontEnd )
				)
				( objectFlag fObjectAlias )
				( objectStatus "page203_vr_pvccin_cpu0_phase4" )
			)
			( signal "@baseboard_fab2_lib.baseboard_fab2(sch_1):nc_pvccin_cpu0_ph5_p31"
				( attribute "CDS_PHYS_NET_NAME" "NC_PVCCIN_CPU0_PH5_P31"
					( Origin gPackager )
				)
				( objectStatus "NC_PVCCIN_CPU0_PH5_P31" )
			)
			( signal "@baseboard_fab2_lib.baseboard_fab2(sch_1):tp_pvccin_cpu0_ph5_gl_0"
				( attribute "CDS_PHYS_NET_NAME" "TP_PVCCIN_CPU0_PH5_GL_0"
					( Origin gPackager )
				)
				( objectStatus "TP_PVCCIN_CPU0_PH5_GL_0" )
			)
			( signal "@baseboard_fab2_lib.baseboard_fab2(sch_1):tp_pvccin_cpu0_ph5_gl_1"
				( attribute "CDS_PHYS_NET_NAME" "TP_PVCCIN_CPU0_PH5_GL_1"
					( Origin gPackager )
				)
				( objectStatus "TP_PVCCIN_CPU0_PH5_GL_1" )
			)
			( signal "@baseboard_fab2_lib.baseboard_fab2(sch_1):vr_fet_sw_p12v_pvccin_cpu0_r"
				( attribute "CDS_PHYS_NET_NAME" "VR_FET_SW_P12V_PVCCIN_CPU0_R"
					( Origin gPackager )
				)
				( objectStatus "VR_FET_SW_P12V_PVCCIN_CPU0_R" )
			)
			( signal "@baseboard_fab2_lib.baseboard_fab2(sch_1):vr_pvccin_cpu0_ph5_boot"
				( attribute "CDS_PHYS_NET_NAME" "VR_PVCCIN_CPU0_PH5_BOOT"
					( Origin gPackager )
				)
				( objectStatus "VR_PVCCIN_CPU0_PH5_BOOT" )
			)
			( signal "@baseboard_fab2_lib.baseboard_fab2(sch_1):\unnamed_202_3d01r5f-gp_i83_2\"
				( attribute "CDS_PHYS_NET_NAME" "UNNAMED_202_3D01R5F-GP_I83_2"
					( Origin gPackager )
				)
				( objectStatus "UNNAMED_202_3D01R5F-GP_I83_2" )
			)
			( signal "@baseboard_fab2_lib.baseboard_fab2(sch_1):vr_pvccin_cpu0_ph5_ocset"
				( alias ( signalRef "@baseboard_fab2_lib.baseboard_fab2(sch_1):page204_vr_pvccin_cpu0_ph5_ocset") )
				( attribute "VOLTAGE" "3.6"
					( Units "uVoltage" "V" 1.000000)
					( Status sAliasFlattened )
					( Origin gFrontEnd )
				)
				( attribute "CDS_PHYS_NET_NAME" "VR_PVCCIN_CPU0_PH5_OCSET"
					( Origin gPackager )
				)
				( objectStatus "VR_PVCCIN_CPU0_PH5_OCSET" )
			)
			( signal "@baseboard_fab2_lib.baseboard_fab2(sch_1):page204_vr_pvccin_cpu0_ph5_ocset"
				( attribute "VOLTAGE" "3.6"
					( Units "uVoltage" "V" 1.000000)
					( Origin gFrontEnd )
				)
				( objectFlag fObjectAlias )
				( objectStatus "page204_vr_pvccin_cpu0_ph5_ocset" )
			)
			( signal "@baseboard_fab2_lib.baseboard_fab2(sch_1):vr_pvccin_cpu0_ph5_phase"
				( alias ( signalRef "@baseboard_fab2_lib.baseboard_fab2(sch_1):page204_vr_pvccin_cpu0_ph5_phase") )
				( attribute "VOLTAGE" "5"
					( Units "uVoltage" "V" 1.000000)
					( Status sAliasFlattened )
					( Origin gFrontEnd )
				)
				( attribute "CDS_PHYS_NET_NAME" "VR_PVCCIN_CPU0_PH5_PHASE"
					( Origin gPackager )
				)
				( objectStatus "VR_PVCCIN_CPU0_PH5_PHASE" )
			)
			( signal "@baseboard_fab2_lib.baseboard_fab2(sch_1):page204_vr_pvccin_cpu0_ph5_phase"
				( attribute "VOLTAGE" "5"
					( Units "uVoltage" "V" 1.000000)
					( Origin gFrontEnd )
				)
				( objectFlag fObjectAlias )
				( objectStatus "page204_vr_pvccin_cpu0_ph5_phase" )
			)
			( signal "@baseboard_fab2_lib.baseboard_fab2(sch_1):vr_pvccin_cpu0_ph5_vcin"
				( alias ( signalRef "@baseboard_fab2_lib.baseboard_fab2(sch_1):page204_vr_pvccin_cpu0_ph5_vcin") )
				( attribute "VOLTAGE" "5"
					( Units "uVoltage" "V" 1.000000)
					( Status sAliasFlattened )
					( Origin gFrontEnd )
				)
				( attribute "CDS_PHYS_NET_NAME" "VR_PVCCIN_CPU0_PH5_VCIN"
					( Origin gPackager )
				)
				( objectStatus "VR_PVCCIN_CPU0_PH5_VCIN" )
			)
			( signal "@baseboard_fab2_lib.baseboard_fab2(sch_1):page204_vr_pvccin_cpu0_ph5_vcin"
				( attribute "VOLTAGE" "5"
					( Units "uVoltage" "V" 1.000000)
					( Origin gFrontEnd )
				)
				( objectFlag fObjectAlias )
				( objectStatus "page204_vr_pvccin_cpu0_ph5_vcin" )
			)
			( signal "@baseboard_fab2_lib.baseboard_fab2(sch_1):vr_pvccin_cpu0_phase5"
				( alias ( signalRef "@baseboard_fab2_lib.baseboard_fab2(sch_1):page204_vr_pvccin_cpu0_phase5") )
				( attribute "VOLTAGE" "5"
					( Units "uVoltage" "V" 1.000000)
					( Status sAliasFlattened )
					( Origin gFrontEnd )
				)
				( attribute "CDS_PHYS_NET_NAME" "VR_PVCCIN_CPU0_PHASE5"
					( Origin gPackager )
				)
				( objectStatus "VR_PVCCIN_CPU0_PHASE5" )
			)
			( signal "@baseboard_fab2_lib.baseboard_fab2(sch_1):page204_vr_pvccin_cpu0_phase5"
				( attribute "VOLTAGE" "5"
					( Units "uVoltage" "V" 1.000000)
					( Origin gFrontEnd )
				)
				( objectFlag fObjectAlias )
				( objectStatus "page204_vr_pvccin_cpu0_phase5" )
			)
			( signal "@baseboard_fab2_lib.baseboard_fab2(sch_1):nc_pvsa_cpu0_p31"
				( attribute "CDS_PHYS_NET_NAME" "NC_PVSA_CPU0_P31"
					( Origin gPackager )
				)
				( objectStatus "NC_PVSA_CPU0_P31" )
			)
			( signal "@baseboard_fab2_lib.baseboard_fab2(sch_1):tp_pvsa_cpu0_gl_0"
				( attribute "CDS_PHYS_NET_NAME" "TP_PVSA_CPU0_GL_0"
					( Origin gPackager )
				)
				( objectStatus "TP_PVSA_CPU0_GL_0" )
			)
			( signal "@baseboard_fab2_lib.baseboard_fab2(sch_1):tp_pvsa_cpu0_gl_1"
				( attribute "CDS_PHYS_NET_NAME" "TP_PVSA_CPU0_GL_1"
					( Origin gPackager )
				)
				( objectStatus "TP_PVSA_CPU0_GL_1" )
			)
			( signal "@baseboard_fab2_lib.baseboard_fab2(sch_1):vr_pvsa_cpu0_boot"
				( attribute "CDS_PHYS_NET_NAME" "VR_PVSA_CPU0_BOOT"
					( Origin gPackager )
				)
				( objectStatus "VR_PVSA_CPU0_BOOT" )
			)
			( signal "@baseboard_fab2_lib.baseboard_fab2(sch_1):\unnamed_236_3d01r5f-gp_i137_2\"
				( attribute "CDS_PHYS_NET_NAME" "UNNAMED_236_3D01R5F-GP_I137_2"
					( Origin gPackager )
				)
				( objectStatus "UNNAMED_236_3D01R5F-GP_I137_2" )
			)
			( signal "@baseboard_fab2_lib.baseboard_fab2(sch_1):vr_pvsa_cpu0_ocset"
				( attribute "CDS_PHYS_NET_NAME" "VR_PVSA_CPU0_OCSET"
					( Origin gPackager )
				)
				( objectStatus "VR_PVSA_CPU0_OCSET" )
			)
			( signal "@baseboard_fab2_lib.baseboard_fab2(sch_1):vr_pvsa_cpu0_phase"
				( alias ( signalRef "@baseboard_fab2_lib.baseboard_fab2(sch_1):page205_vr_pvsa_cpu0_phase") )
				( attribute "VOLTAGE" "5"
					( Units "uVoltage" "V" 1.000000)
					( Status sAliasFlattened )
					( Origin gFrontEnd )
				)
				( attribute "CDS_PHYS_NET_NAME" "VR_PVSA_CPU0_PHASE"
					( Origin gPackager )
				)
				( objectStatus "VR_PVSA_CPU0_PHASE" )
			)
			( signal "@baseboard_fab2_lib.baseboard_fab2(sch_1):page205_vr_pvsa_cpu0_phase"
				( attribute "VOLTAGE" "5"
					( Units "uVoltage" "V" 1.000000)
					( Origin gFrontEnd )
				)
				( objectFlag fObjectAlias )
				( objectStatus "page205_vr_pvsa_cpu0_phase" )
			)
			( signal "@baseboard_fab2_lib.baseboard_fab2(sch_1):vr_pvsa_cpu0_phase_sw"
				( alias ( signalRef "@baseboard_fab2_lib.baseboard_fab2(sch_1):page205_vr_pvsa_cpu0_phase_sw") )
				( attribute "VOLTAGE" "5"
					( Units "uVoltage" "V" 1.000000)
					( Status sAliasFlattened )
					( Origin gFrontEnd )
				)
				( attribute "CDS_PHYS_NET_NAME" "VR_PVSA_CPU0_PHASE_SW"
					( Origin gPackager )
				)
				( objectStatus "VR_PVSA_CPU0_PHASE_SW" )
			)
			( signal "@baseboard_fab2_lib.baseboard_fab2(sch_1):page205_vr_pvsa_cpu0_phase_sw"
				( attribute "VOLTAGE" "5"
					( Units "uVoltage" "V" 1.000000)
					( Origin gFrontEnd )
				)
				( objectFlag fObjectAlias )
				( objectStatus "page205_vr_pvsa_cpu0_phase_sw" )
			)
			( signal "@baseboard_fab2_lib.baseboard_fab2(sch_1):vr_pvsa_cpu0_vcin"
				( alias ( signalRef "@baseboard_fab2_lib.baseboard_fab2(sch_1):page205_vr_pvsa_cpu0_vcin") )
				( attribute "VOLTAGE" "5"
					( Units "uVoltage" "V" 1.000000)
					( Status sAliasFlattened )
					( Origin gFrontEnd )
				)
				( attribute "CDS_PHYS_NET_NAME" "VR_PVSA_CPU0_VCIN"
					( Origin gPackager )
				)
				( objectStatus "VR_PVSA_CPU0_VCIN" )
			)
			( signal "@baseboard_fab2_lib.baseboard_fab2(sch_1):page205_vr_pvsa_cpu0_vcin"
				( attribute "VOLTAGE" "5"
					( Units "uVoltage" "V" 1.000000)
					( Origin gFrontEnd )
				)
				( objectFlag fObjectAlias )
				( objectStatus "page205_vr_pvsa_cpu0_vcin" )
			)
			( signal "@baseboard_fab2_lib.baseboard_fab2(sch_1):a_tsense_pvccin_cpu1"
				( alias ( signalRef "@baseboard_fab2_lib.baseboard_fab2(sch_1):page206_a_tsense_pvccin_cpu1") )
				( attribute "VOLTAGE" "3.6"
					( Units "uVoltage" "V" 1.000000)
					( Status sAliasFlattened )
					( Origin gFrontEnd )
				)
				( attribute "CDS_PHYS_NET_NAME" "A_TSENSE_PVCCIN_CPU1"
					( Origin gPackager )
				)
				( objectStatus "A_TSENSE_PVCCIN_CPU1" )
			)
			( signal "@baseboard_fab2_lib.baseboard_fab2(sch_1):page206_a_tsense_pvccin_cpu1"
				( attribute "VOLTAGE" "3.6"
					( Units "uVoltage" "V" 1.000000)
					( Origin gFrontEnd )
				)
				( objectFlag fObjectAlias )
				( objectStatus "page206_a_tsense_pvccin_cpu1" )
			)
			( signal "@baseboard_fab2_lib.baseboard_fab2(sch_1):a_tsense_pvsa_cpu1"
				( attribute "CDS_PHYS_NET_NAME" "A_TSENSE_PVSA_CPU1"
					( Origin gPackager )
				)
				( objectStatus "A_TSENSE_PVSA_CPU1" )
			)
			( signal "@baseboard_fab2_lib.baseboard_fab2(sch_1):irq_pvccin_cpu1_vrhot_lvc3_r_n"
				( attribute "CDS_PHYS_NET_NAME" "IRQ_PVCCIN_CPU1_VRHOT_LVC3_R_N"
					( Origin gPackager )
				)
				( objectStatus "IRQ_PVCCIN_CPU1_VRHOT_LVC3_R_N" )
			)
			( signal "@baseboard_fab2_lib.baseboard_fab2(sch_1):isense_pvccin_cpu1_ph1_imon"
				( attribute "CDS_PHYS_NET_NAME" "ISENSE_PVCCIN_CPU1_PH1_IMON"
					( Origin gPackager )
				)
				( objectStatus "ISENSE_PVCCIN_CPU1_PH1_IMON" )
			)
			( signal "@baseboard_fab2_lib.baseboard_fab2(sch_1):isense_pvccin_cpu1_ph2_imon"
				( attribute "CDS_PHYS_NET_NAME" "ISENSE_PVCCIN_CPU1_PH2_IMON"
					( Origin gPackager )
				)
				( objectStatus "ISENSE_PVCCIN_CPU1_PH2_IMON" )
			)
			( signal "@baseboard_fab2_lib.baseboard_fab2(sch_1):isense_pvccin_cpu1_ph3_imon"
				( attribute "CDS_PHYS_NET_NAME" "ISENSE_PVCCIN_CPU1_PH3_IMON"
					( Origin gPackager )
				)
				( objectStatus "ISENSE_PVCCIN_CPU1_PH3_IMON" )
			)
			( signal "@baseboard_fab2_lib.baseboard_fab2(sch_1):isense_pvccin_cpu1_ph4_imon"
				( attribute "CDS_PHYS_NET_NAME" "ISENSE_PVCCIN_CPU1_PH4_IMON"
					( Origin gPackager )
				)
				( objectStatus "ISENSE_PVCCIN_CPU1_PH4_IMON" )
			)
			( signal "@baseboard_fab2_lib.baseboard_fab2(sch_1):isense_pvccin_cpu1_ph5_imon"
				( attribute "CDS_PHYS_NET_NAME" "ISENSE_PVCCIN_CPU1_PH5_IMON"
					( Origin gPackager )
				)
				( objectStatus "ISENSE_PVCCIN_CPU1_PH5_IMON" )
			)
			( signal "@baseboard_fab2_lib.baseboard_fab2(sch_1):isense_pvsa_cpu1_imon"
				( attribute "CDS_PHYS_NET_NAME" "ISENSE_PVSA_CPU1_IMON"
					( Origin gPackager )
				)
				( objectStatus "ISENSE_PVSA_CPU1_IMON" )
			)
			( signal "@baseboard_fab2_lib.baseboard_fab2(sch_1):pu_vr_pvccin_cpu1_flt1_smbalt_n_imon"
				( attribute "CDS_PHYS_NET_NAME" "PU_VR_PVCCIN_CPU1_FLT1_SMBALT_N"
					( Origin gPackager )
				)
				( attribute "PNN" "PU_VR_PVCCIN_CPU1_FLT1_SMBALT_N"
					( Origin gPackager )
				)
				( objectStatus "PU_VR_PVCCIN_CPU1_FLT1_SMBALT_N" )
			)
			( signal "@baseboard_fab2_lib.baseboard_fab2(sch_1):pu_vr_pvccin_cpu1_imon"
				( attribute "CDS_PHYS_NET_NAME" "PU_VR_PVCCIN_CPU1_IMON"
					( Origin gPackager )
				)
				( objectStatus "PU_VR_PVCCIN_CPU1_IMON" )
			)
			( signal "@baseboard_fab2_lib.baseboard_fab2(sch_1):pvccin_pvsa_cpu1_iinsen"
				( alias ( signalRef "@baseboard_fab2_lib.baseboard_fab2(sch_1):page206_pvccin_pvsa_cpu1_iinsen") )
				( attribute "VOLTAGE" "+1.5V"
					( Units "uVoltage" "V" 1.000000)
					( Status sAliasFlattened )
					( Origin gFrontEnd )
				)
				( attribute "CDS_PHYS_NET_NAME" "PVCCIN_PVSA_CPU1_IINSEN"
					( Origin gPackager )
				)
				( objectStatus "PVCCIN_PVSA_CPU1_IINSEN" )
			)
			( signal "@baseboard_fab2_lib.baseboard_fab2(sch_1):page206_pvccin_pvsa_cpu1_iinsen"
				( attribute "VOLTAGE" "+1.5V"
					( Units "uVoltage" "V" 1.000000)
					( Origin gFrontEnd )
				)
				( objectFlag fObjectAlias )
				( objectStatus "page206_pvccin_pvsa_cpu1_iinsen" )
			)
			( signal "@baseboard_fab2_lib.baseboard_fab2(sch_1):pwrgd_pvsa_cpu1_r"
				( attribute "CDS_PHYS_NET_NAME" "PWRGD_PVSA_CPU1_R"
					( Origin gPackager )
				)
				( objectStatus "PWRGD_PVSA_CPU1_R" )
			)
			( signal "@baseboard_fab2_lib.baseboard_fab2(sch_1):smb_vr_scl_r1"
				( attribute "CDS_PHYS_NET_NAME" "SMB_VR_SCL_R1"
					( Origin gPackager )
				)
				( objectStatus "SMB_VR_SCL_R1" )
			)
			( signal "@baseboard_fab2_lib.baseboard_fab2(sch_1):smb_vr_sda_r1"
				( attribute "CDS_PHYS_NET_NAME" "SMB_VR_SDA_R1"
					( Origin gPackager )
				)
				( objectStatus "SMB_VR_SDA_R1" )
			)
			( signal "@baseboard_fab2_lib.baseboard_fab2(sch_1):svid_valert_vccin_cpu1"
				( attribute "CDS_PHYS_NET_NAME" "SVID_VALERT_VCCIN_CPU1"
					( Origin gPackager )
				)
				( objectStatus "SVID_VALERT_VCCIN_CPU1" )
			)
			( signal "@baseboard_fab2_lib.baseboard_fab2(sch_1):svid_vclk_pvccin_cpu1"
				( attribute "CDS_PHYS_NET_NAME" "SVID_VCLK_PVCCIN_CPU1"
					( Origin gPackager )
				)
				( objectStatus "SVID_VCLK_PVCCIN_CPU1" )
			)
			( signal "@baseboard_fab2_lib.baseboard_fab2(sch_1):svid_vdio_pvccin_cpu1"
				( attribute "CDS_PHYS_NET_NAME" "SVID_VDIO_PVCCIN_CPU1"
					( Origin gPackager )
				)
				( objectStatus "SVID_VDIO_PVCCIN_CPU1" )
			)
			( signal "@baseboard_fab2_lib.baseboard_fab2(sch_1):tp_pvccin_cpu1_airef6"
				( attribute "CDS_PHYS_NET_NAME" "TP_PVCCIN_CPU1_AIREF6"
					( Origin gPackager )
				)
				( objectStatus "TP_PVCCIN_CPU1_AIREF6" )
			)
			( signal "@baseboard_fab2_lib.baseboard_fab2(sch_1):tp_pvccin_cpu1_aisen6"
				( attribute "CDS_PHYS_NET_NAME" "TP_PVCCIN_CPU1_AISEN6"
					( Origin gPackager )
				)
				( objectStatus "TP_PVCCIN_CPU1_AISEN6" )
			)
			( signal "@baseboard_fab2_lib.baseboard_fab2(sch_1):tp_pvccin_cpu1_apwm6"
				( attribute "CDS_PHYS_NET_NAME" "TP_PVCCIN_CPU1_APWM6"
					( Origin gPackager )
				)
				( objectStatus "TP_PVCCIN_CPU1_APWM6" )
			)
			( signal "@baseboard_fab2_lib.baseboard_fab2(sch_1):tp_pvccin_cpu1_fault1_20"
				( attribute "CDS_PHYS_NET_NAME" "TP_PVCCIN_CPU1_FAULT1_20"
					( Origin gPackager )
				)
				( objectStatus "TP_PVCCIN_CPU1_FAULT1_20" )
			)
			( signal "@baseboard_fab2_lib.baseboard_fab2(sch_1):tp_pvccin_cpu1_gp1"
				( attribute "CDS_PHYS_NET_NAME" "TP_PVCCIN_CPU1_GP1"
					( Origin gPackager )
				)
				( objectStatus "TP_PVCCIN_CPU1_GP1" )
			)
			( signal "@baseboard_fab2_lib.baseboard_fab2(sch_1):tp_pvccin_cpu1_reset_n"
				( attribute "CDS_PHYS_NET_NAME" "TP_PVCCIN_CPU1_RESET_N"
					( Origin gPackager )
				)
				( objectStatus "TP_PVCCIN_CPU1_RESET_N" )
			)
			( signal "@baseboard_fab2_lib.baseboard_fab2(sch_1):vr_fet_sw_p12v_stby_pvccin_cpu1"
				( alias ( signalRef "@baseboard_fab2_lib.baseboard_fab2(sch_1):page206_vr_fet_sw_p12v_stby_pvccin_cpu1") )
				( alias ( signalRef "@baseboard_fab2_lib.baseboard_fab2(sch_1):page207_vr_fet_sw_p12v_stby_pvccin_cpu1") )
				( alias ( signalRef "@baseboard_fab2_lib.baseboard_fab2(sch_1):page208_vr_fet_sw_p12v_stby_pvccin_cpu1") )
				( alias ( signalRef "@baseboard_fab2_lib.baseboard_fab2(sch_1):page209_vr_fet_sw_p12v_stby_pvccin_cpu1") )
				( alias ( signalRef "@baseboard_fab2_lib.baseboard_fab2(sch_1):page210_vr_fet_sw_p12v_stby_pvccin_cpu1") )
				( attribute "VOLTAGE" "12"
					( Units "uVoltage" "V" 1.000000)
					( Status sAliasFlattened )
					( Origin gFrontEnd )
				)
				( attribute "CDS_PHYS_NET_NAME" "VR_FET_SW_P12V_STBY_PVCCIN_CPU1"
					( Origin gPackager )
				)
				( objectStatus "VR_FET_SW_P12V_STBY_PVCCIN_CPU1" )
			)
			( signal "@baseboard_fab2_lib.baseboard_fab2(sch_1):page206_vr_fet_sw_p12v_stby_pvccin_cpu1"
				( attribute "VOLTAGE" "12"
					( Units "uVoltage" "V" 1.000000)
					( Origin gFrontEnd )
				)
				( objectFlag fObjectAlias )
				( objectStatus "page206_vr_fet_sw_p12v_stby_pvccin_cpu1" )
			)
			( signal "@baseboard_fab2_lib.baseboard_fab2(sch_1):page207_vr_fet_sw_p12v_stby_pvccin_cpu1"
				( objectFlag fObjectAlias )
				( objectStatus "page207_vr_fet_sw_p12v_stby_pvccin_cpu1" )
			)
			( signal "@baseboard_fab2_lib.baseboard_fab2(sch_1):page208_vr_fet_sw_p12v_stby_pvccin_cpu1"
				( objectFlag fObjectAlias )
				( objectStatus "page208_vr_fet_sw_p12v_stby_pvccin_cpu1" )
			)
			( signal "@baseboard_fab2_lib.baseboard_fab2(sch_1):page209_vr_fet_sw_p12v_stby_pvccin_cpu1"
				( objectFlag fObjectAlias )
				( objectStatus "page209_vr_fet_sw_p12v_stby_pvccin_cpu1" )
			)
			( signal "@baseboard_fab2_lib.baseboard_fab2(sch_1):page210_vr_fet_sw_p12v_stby_pvccin_cpu1"
				( objectFlag fObjectAlias )
				( objectStatus "page210_vr_fet_sw_p12v_stby_pvccin_cpu1" )
			)
			( signal "@baseboard_fab2_lib.baseboard_fab2(sch_1):vr_pvccin_cpu1_airef1"
				( attribute "CDS_PHYS_NET_NAME" "VR_PVCCIN_CPU1_AIREF1"
					( Origin gPackager )
				)
				( objectStatus "VR_PVCCIN_CPU1_AIREF1" )
			)
			( signal "@baseboard_fab2_lib.baseboard_fab2(sch_1):vr_pvccin_cpu1_airef2"
				( attribute "CDS_PHYS_NET_NAME" "VR_PVCCIN_CPU1_AIREF2"
					( Origin gPackager )
				)
				( objectStatus "VR_PVCCIN_CPU1_AIREF2" )
			)
			( signal "@baseboard_fab2_lib.baseboard_fab2(sch_1):vr_pvccin_cpu1_airef3"
				( attribute "CDS_PHYS_NET_NAME" "VR_PVCCIN_CPU1_AIREF3"
					( Origin gPackager )
				)
				( objectStatus "VR_PVCCIN_CPU1_AIREF3" )
			)
			( signal "@baseboard_fab2_lib.baseboard_fab2(sch_1):vr_pvccin_cpu1_airef4"
				( attribute "CDS_PHYS_NET_NAME" "VR_PVCCIN_CPU1_AIREF4"
					( Origin gPackager )
				)
				( objectStatus "VR_PVCCIN_CPU1_AIREF4" )
			)
			( signal "@baseboard_fab2_lib.baseboard_fab2(sch_1):vr_pvccin_cpu1_airef5"
				( attribute "CDS_PHYS_NET_NAME" "VR_PVCCIN_CPU1_AIREF5"
					( Origin gPackager )
				)
				( objectStatus "VR_PVCCIN_CPU1_AIREF5" )
			)
			( signal "@baseboard_fab2_lib.baseboard_fab2(sch_1):vr_pvccin_cpu1_avinsen"
				( alias ( signalRef "@baseboard_fab2_lib.baseboard_fab2(sch_1):page206_vr_pvccin_cpu1_avinsen") )
				( attribute "VOLTAGE" "0.8"
					( Units "uVoltage" "V" 1.000000)
					( Status sAliasFlattened )
					( Origin gFrontEnd )
				)
				( attribute "CDS_PHYS_NET_NAME" "VR_PVCCIN_CPU1_AVINSEN"
					( Origin gPackager )
				)
				( objectStatus "VR_PVCCIN_CPU1_AVINSEN" )
			)
			( signal "@baseboard_fab2_lib.baseboard_fab2(sch_1):page206_vr_pvccin_cpu1_avinsen"
				( attribute "VOLTAGE" "0.8"
					( Units "uVoltage" "V" 1.000000)
					( Origin gFrontEnd )
				)
				( objectFlag fObjectAlias )
				( objectStatus "page206_vr_pvccin_cpu1_avinsen" )
			)
			( signal "@baseboard_fab2_lib.baseboard_fab2(sch_1):vr_pvccin_cpu1_pwm1"
				( alias ( signalRef "@baseboard_fab2_lib.baseboard_fab2(sch_1):page206_vr_pvccin_cpu1_pwm1") )
				( attribute "VOLTAGE" "3.6"
					( Units "uVoltage" "V" 1.000000)
					( Status sAliasFlattened )
					( Origin gFrontEnd )
				)
				( attribute "CDS_PHYS_NET_NAME" "VR_PVCCIN_CPU1_PWM1"
					( Origin gPackager )
				)
				( objectStatus "VR_PVCCIN_CPU1_PWM1" )
			)
			( signal "@baseboard_fab2_lib.baseboard_fab2(sch_1):page206_vr_pvccin_cpu1_pwm1"
				( attribute "VOLTAGE" "3.6"
					( Units "uVoltage" "V" 1.000000)
					( Origin gFrontEnd )
				)
				( objectFlag fObjectAlias )
				( objectStatus "page206_vr_pvccin_cpu1_pwm1" )
			)
			( signal "@baseboard_fab2_lib.baseboard_fab2(sch_1):vr_pvccin_cpu1_pwm2"
				( alias ( signalRef "@baseboard_fab2_lib.baseboard_fab2(sch_1):page206_vr_pvccin_cpu1_pwm2") )
				( attribute "VOLTAGE" "3.6"
					( Units "uVoltage" "V" 1.000000)
					( Status sAliasFlattened )
					( Origin gFrontEnd )
				)
				( attribute "CDS_PHYS_NET_NAME" "VR_PVCCIN_CPU1_PWM2"
					( Origin gPackager )
				)
				( objectStatus "VR_PVCCIN_CPU1_PWM2" )
			)
			( signal "@baseboard_fab2_lib.baseboard_fab2(sch_1):page206_vr_pvccin_cpu1_pwm2"
				( attribute "VOLTAGE" "3.6"
					( Units "uVoltage" "V" 1.000000)
					( Origin gFrontEnd )
				)
				( objectFlag fObjectAlias )
				( objectStatus "page206_vr_pvccin_cpu1_pwm2" )
			)
			( signal "@baseboard_fab2_lib.baseboard_fab2(sch_1):vr_pvccin_cpu1_pwm3"
				( alias ( signalRef "@baseboard_fab2_lib.baseboard_fab2(sch_1):page206_vr_pvccin_cpu1_pwm3") )
				( attribute "VOLTAGE" "3.6"
					( Units "uVoltage" "V" 1.000000)
					( Status sAliasFlattened )
					( Origin gFrontEnd )
				)
				( attribute "CDS_PHYS_NET_NAME" "VR_PVCCIN_CPU1_PWM3"
					( Origin gPackager )
				)
				( objectStatus "VR_PVCCIN_CPU1_PWM3" )
			)
			( signal "@baseboard_fab2_lib.baseboard_fab2(sch_1):page206_vr_pvccin_cpu1_pwm3"
				( attribute "VOLTAGE" "3.6"
					( Units "uVoltage" "V" 1.000000)
					( Origin gFrontEnd )
				)
				( objectFlag fObjectAlias )
				( objectStatus "page206_vr_pvccin_cpu1_pwm3" )
			)
			( signal "@baseboard_fab2_lib.baseboard_fab2(sch_1):vr_pvccin_cpu1_pwm4"
				( alias ( signalRef "@baseboard_fab2_lib.baseboard_fab2(sch_1):page206_vr_pvccin_cpu1_pwm4") )
				( attribute "VOLTAGE" "3.6"
					( Units "uVoltage" "V" 1.000000)
					( Status sAliasFlattened )
					( Origin gFrontEnd )
				)
				( attribute "CDS_PHYS_NET_NAME" "VR_PVCCIN_CPU1_PWM4"
					( Origin gPackager )
				)
				( objectStatus "VR_PVCCIN_CPU1_PWM4" )
			)
			( signal "@baseboard_fab2_lib.baseboard_fab2(sch_1):page206_vr_pvccin_cpu1_pwm4"
				( attribute "VOLTAGE" "3.6"
					( Units "uVoltage" "V" 1.000000)
					( Origin gFrontEnd )
				)
				( objectFlag fObjectAlias )
				( objectStatus "page206_vr_pvccin_cpu1_pwm4" )
			)
			( signal "@baseboard_fab2_lib.baseboard_fab2(sch_1):vr_pvccin_cpu1_pwm5"
				( alias ( signalRef "@baseboard_fab2_lib.baseboard_fab2(sch_1):page209_vr_pvccin_cpu1_pwm5") )
				( attribute "VOLTAGE" "3.6"
					( Units "uVoltage" "V" 1.000000)
					( Status sAliasFlattened )
					( Origin gFrontEnd )
				)
				( attribute "CDS_PHYS_NET_NAME" "VR_PVCCIN_CPU1_PWM5"
					( Origin gPackager )
				)
				( objectStatus "VR_PVCCIN_CPU1_PWM5" )
			)
			( signal "@baseboard_fab2_lib.baseboard_fab2(sch_1):page209_vr_pvccin_cpu1_pwm5"
				( attribute "VOLTAGE" "3.6"
					( Units "uVoltage" "V" 1.000000)
					( Origin gFrontEnd )
				)
				( objectFlag fObjectAlias )
				( objectStatus "page209_vr_pvccin_cpu1_pwm5" )
			)
			( signal "@baseboard_fab2_lib.baseboard_fab2(sch_1):vr_pvccin_cpu1_vd12"
				( attribute "CDS_PHYS_NET_NAME" "VR_PVCCIN_CPU1_VD12"
					( Origin gPackager )
				)
				( objectStatus "VR_PVCCIN_CPU1_VD12" )
			)
			( signal "@baseboard_fab2_lib.baseboard_fab2(sch_1):vr_pvccin_cpu1_vdd"
				( alias ( signalRef "@baseboard_fab2_lib.baseboard_fab2(sch_1):page206_vr_pvccin_cpu1_vdd") )
				( attribute "VOLTAGE" "3.3"
					( Units "uVoltage" "V" 1.000000)
					( Status sAliasFlattened )
					( Origin gFrontEnd )
				)
				( attribute "CDS_PHYS_NET_NAME" "VR_PVCCIN_CPU1_VDD"
					( Origin gPackager )
				)
				( objectStatus "VR_PVCCIN_CPU1_VDD" )
			)
			( signal "@baseboard_fab2_lib.baseboard_fab2(sch_1):page206_vr_pvccin_cpu1_vdd"
				( attribute "VOLTAGE" "3.3"
					( Units "uVoltage" "V" 1.000000)
					( Origin gFrontEnd )
				)
				( objectFlag fObjectAlias )
				( objectStatus "page206_vr_pvccin_cpu1_vdd" )
			)
			( signal "@baseboard_fab2_lib.baseboard_fab2(sch_1):vr_pvccin_cpu1_vren"
				( alias ( signalRef "@baseboard_fab2_lib.baseboard_fab2(sch_1):page206_vr_pvccin_cpu1_vren") )
				( attribute "VOLTAGE" "3.3"
					( Units "uVoltage" "V" 1.000000)
					( Status sAliasFlattened )
					( Origin gFrontEnd )
				)
				( attribute "CDS_PHYS_NET_NAME" "VR_PVCCIN_CPU1_VREN"
					( Origin gPackager )
				)
				( objectStatus "VR_PVCCIN_CPU1_VREN" )
			)
			( signal "@baseboard_fab2_lib.baseboard_fab2(sch_1):page206_vr_pvccin_cpu1_vren"
				( attribute "VOLTAGE" "3.3"
					( Units "uVoltage" "V" 1.000000)
					( Origin gFrontEnd )
				)
				( objectFlag fObjectAlias )
				( objectStatus "page206_vr_pvccin_cpu1_vren" )
			)
			( signal "@baseboard_fab2_lib.baseboard_fab2(sch_1):vr_pvccin_cpu1_xaddr1"
				( alias ( signalRef "@baseboard_fab2_lib.baseboard_fab2(sch_1):page206_vr_pvccin_cpu1_xaddr1") )
				( attribute "VOLTAGE" "3.3"
					( Units "uVoltage" "V" 1.000000)
					( Status sAliasFlattened )
					( Origin gFrontEnd )
				)
				( attribute "CDS_PHYS_NET_NAME" "VR_PVCCIN_CPU1_XADDR1"
					( Origin gPackager )
				)
				( objectStatus "VR_PVCCIN_CPU1_XADDR1" )
			)
			( signal "@baseboard_fab2_lib.baseboard_fab2(sch_1):page206_vr_pvccin_cpu1_xaddr1"
				( attribute "VOLTAGE" "3.3"
					( Units "uVoltage" "V" 1.000000)
					( Origin gFrontEnd )
				)
				( objectFlag fObjectAlias )
				( objectStatus "page206_vr_pvccin_cpu1_xaddr1" )
			)
			( signal "@baseboard_fab2_lib.baseboard_fab2(sch_1):vr_pvccin_cpu1_xaddr2"
				( alias ( signalRef "@baseboard_fab2_lib.baseboard_fab2(sch_1):page206_vr_pvccin_cpu1_xaddr2") )
				( attribute "VOLTAGE" "3.3"
					( Units "uVoltage" "V" 1.000000)
					( Status sAliasFlattened )
					( Origin gFrontEnd )
				)
				( attribute "CDS_PHYS_NET_NAME" "VR_PVCCIN_CPU1_XADDR2"
					( Origin gPackager )
				)
				( objectStatus "VR_PVCCIN_CPU1_XADDR2" )
			)
			( signal "@baseboard_fab2_lib.baseboard_fab2(sch_1):page206_vr_pvccin_cpu1_xaddr2"
				( attribute "VOLTAGE" "3.3"
					( Units "uVoltage" "V" 1.000000)
					( Origin gFrontEnd )
				)
				( objectFlag fObjectAlias )
				( objectStatus "page206_vr_pvccin_cpu1_xaddr2" )
			)
			( signal "@baseboard_fab2_lib.baseboard_fab2(sch_1):vr_pvsa_cpu1_biref1"
				( attribute "CDS_PHYS_NET_NAME" "VR_PVSA_CPU1_BIREF1"
					( Origin gPackager )
				)
				( objectStatus "VR_PVSA_CPU1_BIREF1" )
			)
			( signal "@baseboard_fab2_lib.baseboard_fab2(sch_1):vr_pvsa_cpu1_pwm"
				( alias ( signalRef "@baseboard_fab2_lib.baseboard_fab2(sch_1):page206_vr_pvsa_cpu1_pwm") )
				( attribute "VOLTAGE" "3.6"
					( Units "uVoltage" "V" 1.000000)
					( Status sAliasFlattened )
					( Origin gFrontEnd )
				)
				( attribute "CDS_PHYS_NET_NAME" "VR_PVSA_CPU1_PWM"
					( Origin gPackager )
				)
				( objectStatus "VR_PVSA_CPU1_PWM" )
			)
			( signal "@baseboard_fab2_lib.baseboard_fab2(sch_1):page206_vr_pvsa_cpu1_pwm"
				( attribute "VOLTAGE" "3.6"
					( Units "uVoltage" "V" 1.000000)
					( Origin gFrontEnd )
				)
				( objectFlag fObjectAlias )
				( objectStatus "page206_vr_pvsa_cpu1_pwm" )
			)
			( signal "@baseboard_fab2_lib.baseboard_fab2(sch_1):vr_vrrdy_pvccin_cpu1"
				( attribute "CDS_PHYS_NET_NAME" "VR_VRRDY_PVCCIN_CPU1"
					( Origin gPackager )
				)
				( objectStatus "VR_VRRDY_PVCCIN_CPU1" )
			)
			( signal "@baseboard_fab2_lib.baseboard_fab2(sch_1):vsense_pvccin_cpu1_avsp"
				( attribute "CDS_PHYS_NET_NAME" "VSENSE_PVCCIN_CPU1_AVSP"
					( Origin gPackager )
				)
				( objectStatus "VSENSE_PVCCIN_CPU1_AVSP" )
			)
			( signal "@baseboard_fab2_lib.baseboard_fab2(sch_1):vsense_pvccin_cpu1_n"
				( attribute "CDS_PHYS_NET_NAME" "VSENSE_PVCCIN_CPU1_N"
					( Origin gPackager )
				)
				( objectStatus "VSENSE_PVCCIN_CPU1_N" )
			)
			( signal "@baseboard_fab2_lib.baseboard_fab2(sch_1):vsense_pvccin_cpu1_p"
				( attribute "CDS_PHYS_NET_NAME" "VSENSE_PVCCIN_CPU1_P"
					( Origin gPackager )
				)
				( objectStatus "VSENSE_PVCCIN_CPU1_P" )
			)
			( signal "@baseboard_fab2_lib.baseboard_fab2(sch_1):vsense_pvsa_cpu1_bvsp"
				( attribute "CDS_PHYS_NET_NAME" "VSENSE_PVSA_CPU1_BVSP"
					( Origin gPackager )
				)
				( objectStatus "VSENSE_PVSA_CPU1_BVSP" )
			)
			( signal "@baseboard_fab2_lib.baseboard_fab2(sch_1):vsense_pvsa_cpu1_n"
				( attribute "CDS_PHYS_NET_NAME" "VSENSE_PVSA_CPU1_N"
					( Origin gPackager )
				)
				( objectStatus "VSENSE_PVSA_CPU1_N" )
			)
			( signal "@baseboard_fab2_lib.baseboard_fab2(sch_1):vsense_pvsa_cpu1_p"
				( attribute "CDS_PHYS_NET_NAME" "VSENSE_PVSA_CPU1_P"
					( Origin gPackager )
				)
				( objectStatus "VSENSE_PVSA_CPU1_P" )
			)
			( signal "@baseboard_fab2_lib.baseboard_fab2(sch_1):nc_pvccin_cpu1_ph1_p31"
				( attribute "CDS_PHYS_NET_NAME" "NC_PVCCIN_CPU1_PH1_P31"
					( Origin gPackager )
				)
				( objectStatus "NC_PVCCIN_CPU1_PH1_P31" )
			)
			( signal "@baseboard_fab2_lib.baseboard_fab2(sch_1):nc_pvccin_cpu1_ph2_p31"
				( attribute "CDS_PHYS_NET_NAME" "NC_PVCCIN_CPU1_PH2_P31"
					( Origin gPackager )
				)
				( objectStatus "NC_PVCCIN_CPU1_PH2_P31" )
			)
			( signal "@baseboard_fab2_lib.baseboard_fab2(sch_1):tp_pvccinc_cpu1_ph1_gl_0"
				( attribute "CDS_PHYS_NET_NAME" "TP_PVCCINC_CPU1_PH1_GL_0"
					( Origin gPackager )
				)
				( objectStatus "TP_PVCCINC_CPU1_PH1_GL_0" )
			)
			( signal "@baseboard_fab2_lib.baseboard_fab2(sch_1):tp_pvccinc_cpu1_ph1_gl_1"
				( attribute "CDS_PHYS_NET_NAME" "TP_PVCCINC_CPU1_PH1_GL_1"
					( Origin gPackager )
				)
				( objectStatus "TP_PVCCINC_CPU1_PH1_GL_1" )
			)
			( signal "@baseboard_fab2_lib.baseboard_fab2(sch_1):tp_pvccinc_cpu1_ph2_gl_0"
				( attribute "CDS_PHYS_NET_NAME" "TP_PVCCINC_CPU1_PH2_GL_0"
					( Origin gPackager )
				)
				( objectStatus "TP_PVCCINC_CPU1_PH2_GL_0" )
			)
			( signal "@baseboard_fab2_lib.baseboard_fab2(sch_1):tp_pvccinc_cpu1_ph2_gl_1"
				( attribute "CDS_PHYS_NET_NAME" "TP_PVCCINC_CPU1_PH2_GL_1"
					( Origin gPackager )
				)
				( objectStatus "TP_PVCCINC_CPU1_PH2_GL_1" )
			)
			( signal "@baseboard_fab2_lib.baseboard_fab2(sch_1):vr_pvccin_cpu1_ph1_boot"
				( attribute "CDS_PHYS_NET_NAME" "VR_PVCCIN_CPU1_PH1_BOOT"
					( Origin gPackager )
				)
				( objectStatus "VR_PVCCIN_CPU1_PH1_BOOT" )
			)
			( signal "@baseboard_fab2_lib.baseboard_fab2(sch_1):\unnamed_204_3d01r5f-gp_i91_2\"
				( attribute "CDS_PHYS_NET_NAME" "UNNAMED_204_3D01R5F-GP_I91_2"
					( Origin gPackager )
				)
				( objectStatus "UNNAMED_204_3D01R5F-GP_I91_2" )
			)
			( signal "@baseboard_fab2_lib.baseboard_fab2(sch_1):vr_pvccin_cpu1_ph1_ocset"
				( attribute "CDS_PHYS_NET_NAME" "VR_PVCCIN_CPU1_PH1_OCSET"
					( Origin gPackager )
				)
				( objectStatus "VR_PVCCIN_CPU1_PH1_OCSET" )
			)
			( signal "@baseboard_fab2_lib.baseboard_fab2(sch_1):vr_pvccin_cpu1_ph1_phase"
				( alias ( signalRef "@baseboard_fab2_lib.baseboard_fab2(sch_1):page207_vr_pvccin_cpu1_ph1_phase") )
				( attribute "VOLTAGE" "5"
					( Units "uVoltage" "V" 1.000000)
					( Status sAliasFlattened )
					( Origin gFrontEnd )
				)
				( attribute "CDS_PHYS_NET_NAME" "VR_PVCCIN_CPU1_PH1_PHASE"
					( Origin gPackager )
				)
				( objectStatus "VR_PVCCIN_CPU1_PH1_PHASE" )
			)
			( signal "@baseboard_fab2_lib.baseboard_fab2(sch_1):page207_vr_pvccin_cpu1_ph1_phase"
				( attribute "VOLTAGE" "5"
					( Units "uVoltage" "V" 1.000000)
					( Origin gFrontEnd )
				)
				( objectFlag fObjectAlias )
				( objectStatus "page207_vr_pvccin_cpu1_ph1_phase" )
			)
			( signal "@baseboard_fab2_lib.baseboard_fab2(sch_1):vr_pvccin_cpu1_ph1_vcin"
				( alias ( signalRef "@baseboard_fab2_lib.baseboard_fab2(sch_1):page207_vr_pvccin_cpu1_ph1_vcin") )
				( attribute "VOLTAGE" "5"
					( Units "uVoltage" "V" 1.000000)
					( Status sAliasFlattened )
					( Origin gFrontEnd )
				)
				( attribute "CDS_PHYS_NET_NAME" "VR_PVCCIN_CPU1_PH1_VCIN"
					( Origin gPackager )
				)
				( objectStatus "VR_PVCCIN_CPU1_PH1_VCIN" )
			)
			( signal "@baseboard_fab2_lib.baseboard_fab2(sch_1):page207_vr_pvccin_cpu1_ph1_vcin"
				( attribute "VOLTAGE" "5"
					( Units "uVoltage" "V" 1.000000)
					( Origin gFrontEnd )
				)
				( objectFlag fObjectAlias )
				( objectStatus "page207_vr_pvccin_cpu1_ph1_vcin" )
			)
			( signal "@baseboard_fab2_lib.baseboard_fab2(sch_1):vr_pvccin_cpu1_ph2_boot"
				( attribute "CDS_PHYS_NET_NAME" "VR_PVCCIN_CPU1_PH2_BOOT"
					( Origin gPackager )
				)
				( objectStatus "VR_PVCCIN_CPU1_PH2_BOOT" )
			)
			( signal "@baseboard_fab2_lib.baseboard_fab2(sch_1):vr_pvccin_cpu1_ph2_ocset"
				( attribute "CDS_PHYS_NET_NAME" "VR_PVCCIN_CPU1_PH2_OCSET"
					( Origin gPackager )
				)
				( objectStatus "VR_PVCCIN_CPU1_PH2_OCSET" )
			)
			( signal "@baseboard_fab2_lib.baseboard_fab2(sch_1):vr_pvccin_cpu1_ph2_phase"
				( alias ( signalRef "@baseboard_fab2_lib.baseboard_fab2(sch_1):page207_vr_pvccin_cpu1_ph2_phase") )
				( attribute "VOLTAGE" "5"
					( Units "uVoltage" "V" 1.000000)
					( Status sAliasFlattened )
					( Origin gFrontEnd )
				)
				( attribute "CDS_PHYS_NET_NAME" "VR_PVCCIN_CPU1_PH2_PHASE"
					( Origin gPackager )
				)
				( objectStatus "VR_PVCCIN_CPU1_PH2_PHASE" )
			)
			( signal "@baseboard_fab2_lib.baseboard_fab2(sch_1):page207_vr_pvccin_cpu1_ph2_phase"
				( attribute "VOLTAGE" "5"
					( Units "uVoltage" "V" 1.000000)
					( Origin gFrontEnd )
				)
				( objectFlag fObjectAlias )
				( objectStatus "page207_vr_pvccin_cpu1_ph2_phase" )
			)
			( signal "@baseboard_fab2_lib.baseboard_fab2(sch_1):vr_pvccin_cpu1_ph2_vcin"
				( alias ( signalRef "@baseboard_fab2_lib.baseboard_fab2(sch_1):page207_vr_pvccin_cpu1_ph2_vcin") )
				( attribute "VOLTAGE" "5"
					( Units "uVoltage" "V" 1.000000)
					( Status sAliasFlattened )
					( Origin gFrontEnd )
				)
				( attribute "CDS_PHYS_NET_NAME" "VR_PVCCIN_CPU1_PH2_VCIN"
					( Origin gPackager )
				)
				( objectStatus "VR_PVCCIN_CPU1_PH2_VCIN" )
			)
			( signal "@baseboard_fab2_lib.baseboard_fab2(sch_1):page207_vr_pvccin_cpu1_ph2_vcin"
				( attribute "VOLTAGE" "5"
					( Units "uVoltage" "V" 1.000000)
					( Origin gFrontEnd )
				)
				( objectFlag fObjectAlias )
				( objectStatus "page207_vr_pvccin_cpu1_ph2_vcin" )
			)
			( signal "@baseboard_fab2_lib.baseboard_fab2(sch_1):vr_pvccin_cpu1_phase1"
				( alias ( signalRef "@baseboard_fab2_lib.baseboard_fab2(sch_1):page207_vr_pvccin_cpu1_phase1") )
				( attribute "VOLTAGE" "5"
					( Units "uVoltage" "V" 1.000000)
					( Status sAliasFlattened )
					( Origin gFrontEnd )
				)
				( attribute "CDS_PHYS_NET_NAME" "VR_PVCCIN_CPU1_PHASE1"
					( Origin gPackager )
				)
				( objectStatus "VR_PVCCIN_CPU1_PHASE1" )
			)
			( signal "@baseboard_fab2_lib.baseboard_fab2(sch_1):page207_vr_pvccin_cpu1_phase1"
				( attribute "VOLTAGE" "5"
					( Units "uVoltage" "V" 1.000000)
					( Origin gFrontEnd )
				)
				( objectFlag fObjectAlias )
				( objectStatus "page207_vr_pvccin_cpu1_phase1" )
			)
			( signal "@baseboard_fab2_lib.baseboard_fab2(sch_1):vr_pvccin_cpu1_phase2"
				( alias ( signalRef "@baseboard_fab2_lib.baseboard_fab2(sch_1):page207_vr_pvccin_cpu1_phase2") )
				( attribute "VOLTAGE" "5"
					( Units "uVoltage" "V" 1.000000)
					( Status sAliasFlattened )
					( Origin gFrontEnd )
				)
				( attribute "CDS_PHYS_NET_NAME" "VR_PVCCIN_CPU1_PHASE2"
					( Origin gPackager )
				)
				( objectStatus "VR_PVCCIN_CPU1_PHASE2" )
			)
			( signal "@baseboard_fab2_lib.baseboard_fab2(sch_1):page207_vr_pvccin_cpu1_phase2"
				( attribute "VOLTAGE" "5"
					( Units "uVoltage" "V" 1.000000)
					( Origin gFrontEnd )
				)
				( objectFlag fObjectAlias )
				( objectStatus "page207_vr_pvccin_cpu1_phase2" )
			)
			( signal "@baseboard_fab2_lib.baseboard_fab2(sch_1):nc_pvccin_cpu1_ph3_p31"
				( attribute "CDS_PHYS_NET_NAME" "NC_PVCCIN_CPU1_PH3_P31"
					( Origin gPackager )
				)
				( objectStatus "NC_PVCCIN_CPU1_PH3_P31" )
			)
			( signal "@baseboard_fab2_lib.baseboard_fab2(sch_1):nc_pvccin_cpu1_ph4_p31"
				( attribute "CDS_PHYS_NET_NAME" "NC_PVCCIN_CPU1_PH4_P31"
					( Origin gPackager )
				)
				( objectStatus "NC_PVCCIN_CPU1_PH4_P31" )
			)
			( signal "@baseboard_fab2_lib.baseboard_fab2(sch_1):tp_pvccin_cpu1_ph3_gl_0"
				( attribute "CDS_PHYS_NET_NAME" "TP_PVCCIN_CPU1_PH3_GL_0"
					( Origin gPackager )
				)
				( objectStatus "TP_PVCCIN_CPU1_PH3_GL_0" )
			)
			( signal "@baseboard_fab2_lib.baseboard_fab2(sch_1):tp_pvccin_cpu1_ph3_gl_1"
				( attribute "CDS_PHYS_NET_NAME" "TP_PVCCIN_CPU1_PH3_GL_1"
					( Origin gPackager )
				)
				( objectStatus "TP_PVCCIN_CPU1_PH3_GL_1" )
			)
			( signal "@baseboard_fab2_lib.baseboard_fab2(sch_1):tp_pvccin_cpu1_ph4_gl_0"
				( attribute "CDS_PHYS_NET_NAME" "TP_PVCCIN_CPU1_PH4_GL_0"
					( Origin gPackager )
				)
				( objectStatus "TP_PVCCIN_CPU1_PH4_GL_0" )
			)
			( signal "@baseboard_fab2_lib.baseboard_fab2(sch_1):tp_pvccin_cpu1_ph4_gl_1"
				( attribute "CDS_PHYS_NET_NAME" "TP_PVCCIN_CPU1_PH4_GL_1"
					( Origin gPackager )
				)
				( objectStatus "TP_PVCCIN_CPU1_PH4_GL_1" )
			)
			( signal "@baseboard_fab2_lib.baseboard_fab2(sch_1):vr_pvccin_cpu1_ph3_boot"
				( attribute "CDS_PHYS_NET_NAME" "VR_PVCCIN_CPU1_PH3_BOOT"
					( Origin gPackager )
				)
				( objectStatus "VR_PVCCIN_CPU1_PH3_BOOT" )
			)
			( signal "@baseboard_fab2_lib.baseboard_fab2(sch_1):vr_pvccin_cpu1_ph3_ocset"
				( attribute "CDS_PHYS_NET_NAME" "VR_PVCCIN_CPU1_PH3_OCSET"
					( Origin gPackager )
				)
				( objectStatus "VR_PVCCIN_CPU1_PH3_OCSET" )
			)
			( signal "@baseboard_fab2_lib.baseboard_fab2(sch_1):vr_pvccin_cpu1_ph3_phase"
				( attribute "CDS_PHYS_NET_NAME" "VR_PVCCIN_CPU1_PH3_PHASE"
					( Origin gPackager )
				)
				( objectStatus "VR_PVCCIN_CPU1_PH3_PHASE" )
			)
			( signal "@baseboard_fab2_lib.baseboard_fab2(sch_1):vr_pvccin_cpu1_ph3_vcin"
				( alias ( signalRef "@baseboard_fab2_lib.baseboard_fab2(sch_1):page208_vr_pvccin_cpu1_ph3_vcin") )
				( attribute "VOLTAGE" "5"
					( Units "uVoltage" "V" 1.000000)
					( Status sAliasFlattened )
					( Origin gFrontEnd )
				)
				( attribute "CDS_PHYS_NET_NAME" "VR_PVCCIN_CPU1_PH3_VCIN"
					( Origin gPackager )
				)
				( objectStatus "VR_PVCCIN_CPU1_PH3_VCIN" )
			)
			( signal "@baseboard_fab2_lib.baseboard_fab2(sch_1):page208_vr_pvccin_cpu1_ph3_vcin"
				( attribute "VOLTAGE" "5"
					( Units "uVoltage" "V" 1.000000)
					( Origin gFrontEnd )
				)
				( objectFlag fObjectAlias )
				( objectStatus "page208_vr_pvccin_cpu1_ph3_vcin" )
			)
			( signal "@baseboard_fab2_lib.baseboard_fab2(sch_1):vr_pvccin_cpu1_ph4_boot"
				( attribute "CDS_PHYS_NET_NAME" "VR_PVCCIN_CPU1_PH4_BOOT"
					( Origin gPackager )
				)
				( objectStatus "VR_PVCCIN_CPU1_PH4_BOOT" )
			)
			( signal "@baseboard_fab2_lib.baseboard_fab2(sch_1):vr_pvccin_cpu1_ph4_ocset"
				( attribute "CDS_PHYS_NET_NAME" "VR_PVCCIN_CPU1_PH4_OCSET"
					( Origin gPackager )
				)
				( objectStatus "VR_PVCCIN_CPU1_PH4_OCSET" )
			)
			( signal "@baseboard_fab2_lib.baseboard_fab2(sch_1):vr_pvccin_cpu1_ph4_phase"
				( alias ( signalRef "@baseboard_fab2_lib.baseboard_fab2(sch_1):page208_vr_pvccin_cpu1_ph4_phase") )
				( attribute "VOLTAGE" "5"
					( Units "uVoltage" "V" 1.000000)
					( Status sAliasFlattened )
					( Origin gFrontEnd )
				)
				( attribute "CDS_PHYS_NET_NAME" "VR_PVCCIN_CPU1_PH4_PHASE"
					( Origin gPackager )
				)
				( objectStatus "VR_PVCCIN_CPU1_PH4_PHASE" )
			)
			( signal "@baseboard_fab2_lib.baseboard_fab2(sch_1):page208_vr_pvccin_cpu1_ph4_phase"
				( attribute "VOLTAGE" "5"
					( Units "uVoltage" "V" 1.000000)
					( Origin gFrontEnd )
				)
				( objectFlag fObjectAlias )
				( objectStatus "page208_vr_pvccin_cpu1_ph4_phase" )
			)
			( signal "@baseboard_fab2_lib.baseboard_fab2(sch_1):vr_pvccin_cpu1_ph4_vcin"
				( alias ( signalRef "@baseboard_fab2_lib.baseboard_fab2(sch_1):page208_vr_pvccin_cpu1_ph4_vcin") )
				( attribute "VOLTAGE" "5"
					( Units "uVoltage" "V" 1.000000)
					( Status sAliasFlattened )
					( Origin gFrontEnd )
				)
				( attribute "CDS_PHYS_NET_NAME" "VR_PVCCIN_CPU1_PH4_VCIN"
					( Origin gPackager )
				)
				( objectStatus "VR_PVCCIN_CPU1_PH4_VCIN" )
			)
			( signal "@baseboard_fab2_lib.baseboard_fab2(sch_1):page208_vr_pvccin_cpu1_ph4_vcin"
				( attribute "VOLTAGE" "5"
					( Units "uVoltage" "V" 1.000000)
					( Origin gFrontEnd )
				)
				( objectFlag fObjectAlias )
				( objectStatus "page208_vr_pvccin_cpu1_ph4_vcin" )
			)
			( signal "@baseboard_fab2_lib.baseboard_fab2(sch_1):vr_pvccin_cpu1_phase3"
				( alias ( signalRef "@baseboard_fab2_lib.baseboard_fab2(sch_1):page208_vr_pvccin_cpu1_phase3") )
				( attribute "VOLTAGE" "5"
					( Units "uVoltage" "V" 1.000000)
					( Status sAliasFlattened )
					( Origin gFrontEnd )
				)
				( attribute "CDS_PHYS_NET_NAME" "VR_PVCCIN_CPU1_PHASE3"
					( Origin gPackager )
				)
				( objectStatus "VR_PVCCIN_CPU1_PHASE3" )
			)
			( signal "@baseboard_fab2_lib.baseboard_fab2(sch_1):page208_vr_pvccin_cpu1_phase3"
				( attribute "VOLTAGE" "5"
					( Units "uVoltage" "V" 1.000000)
					( Origin gFrontEnd )
				)
				( objectFlag fObjectAlias )
				( objectStatus "page208_vr_pvccin_cpu1_phase3" )
			)
			( signal "@baseboard_fab2_lib.baseboard_fab2(sch_1):vr_pvccin_cpu1_phase4"
				( alias ( signalRef "@baseboard_fab2_lib.baseboard_fab2(sch_1):page208_vr_pvccin_cpu1_phase4") )
				( attribute "VOLTAGE" "5"
					( Units "uVoltage" "V" 1.000000)
					( Status sAliasFlattened )
					( Origin gFrontEnd )
				)
				( attribute "CDS_PHYS_NET_NAME" "VR_PVCCIN_CPU1_PHASE4"
					( Origin gPackager )
				)
				( objectStatus "VR_PVCCIN_CPU1_PHASE4" )
			)
			( signal "@baseboard_fab2_lib.baseboard_fab2(sch_1):page208_vr_pvccin_cpu1_phase4"
				( attribute "VOLTAGE" "5"
					( Units "uVoltage" "V" 1.000000)
					( Origin gFrontEnd )
				)
				( objectFlag fObjectAlias )
				( objectStatus "page208_vr_pvccin_cpu1_phase4" )
			)
			( signal "@baseboard_fab2_lib.baseboard_fab2(sch_1):nc_pvccin_cpu1_ph5_p31"
				( attribute "CDS_PHYS_NET_NAME" "NC_PVCCIN_CPU1_PH5_P31"
					( Origin gPackager )
				)
				( objectStatus "NC_PVCCIN_CPU1_PH5_P31" )
			)
			( signal "@baseboard_fab2_lib.baseboard_fab2(sch_1):tp_pvccin_cpu1_ph5_gl_0"
				( attribute "CDS_PHYS_NET_NAME" "TP_PVCCIN_CPU1_PH5_GL_0"
					( Origin gPackager )
				)
				( objectStatus "TP_PVCCIN_CPU1_PH5_GL_0" )
			)
			( signal "@baseboard_fab2_lib.baseboard_fab2(sch_1):tp_pvccin_cpu1_ph5_gl_1"
				( attribute "CDS_PHYS_NET_NAME" "TP_PVCCIN_CPU1_PH5_GL_1"
					( Origin gPackager )
				)
				( objectStatus "TP_PVCCIN_CPU1_PH5_GL_1" )
			)
			( signal "@baseboard_fab2_lib.baseboard_fab2(sch_1):vr_fet_sw_p12v_pvccin_cpu1_r"
				( attribute "CDS_PHYS_NET_NAME" "VR_FET_SW_P12V_PVCCIN_CPU1_R"
					( Origin gPackager )
				)
				( objectStatus "VR_FET_SW_P12V_PVCCIN_CPU1_R" )
			)
			( signal "@baseboard_fab2_lib.baseboard_fab2(sch_1):vr_pvccin_cpu1_ph5_boot"
				( attribute "CDS_PHYS_NET_NAME" "VR_PVCCIN_CPU1_PH5_BOOT"
					( Origin gPackager )
				)
				( objectStatus "VR_PVCCIN_CPU1_PH5_BOOT" )
			)
			( signal "@baseboard_fab2_lib.baseboard_fab2(sch_1):\unnamed_207_3d01r5f-gp_i85_2\"
				( attribute "CDS_PHYS_NET_NAME" "UNNAMED_207_3D01R5F-GP_I85_2"
					( Origin gPackager )
				)
				( objectStatus "UNNAMED_207_3D01R5F-GP_I85_2" )
			)
			( signal "@baseboard_fab2_lib.baseboard_fab2(sch_1):vr_pvccin_cpu1_ph5_ocset"
				( attribute "CDS_PHYS_NET_NAME" "VR_PVCCIN_CPU1_PH5_OCSET"
					( Origin gPackager )
				)
				( objectStatus "VR_PVCCIN_CPU1_PH5_OCSET" )
			)
			( signal "@baseboard_fab2_lib.baseboard_fab2(sch_1):vr_pvccin_cpu1_ph5_phase"
				( alias ( signalRef "@baseboard_fab2_lib.baseboard_fab2(sch_1):page209_vr_pvccin_cpu1_ph5_phase") )
				( attribute "VOLTAGE" "5"
					( Units "uVoltage" "V" 1.000000)
					( Status sAliasFlattened )
					( Origin gFrontEnd )
				)
				( attribute "CDS_PHYS_NET_NAME" "VR_PVCCIN_CPU1_PH5_PHASE"
					( Origin gPackager )
				)
				( objectStatus "VR_PVCCIN_CPU1_PH5_PHASE" )
			)
			( signal "@baseboard_fab2_lib.baseboard_fab2(sch_1):page209_vr_pvccin_cpu1_ph5_phase"
				( attribute "VOLTAGE" "5"
					( Units "uVoltage" "V" 1.000000)
					( Origin gFrontEnd )
				)
				( objectFlag fObjectAlias )
				( objectStatus "page209_vr_pvccin_cpu1_ph5_phase" )
			)
			( signal "@baseboard_fab2_lib.baseboard_fab2(sch_1):vr_pvccin_cpu1_ph5_vcin"
				( alias ( signalRef "@baseboard_fab2_lib.baseboard_fab2(sch_1):page209_vr_pvccin_cpu1_ph5_vcin") )
				( attribute "VOLTAGE" "5"
					( Units "uVoltage" "V" 1.000000)
					( Status sAliasFlattened )
					( Origin gFrontEnd )
				)
				( attribute "CDS_PHYS_NET_NAME" "VR_PVCCIN_CPU1_PH5_VCIN"
					( Origin gPackager )
				)
				( objectStatus "VR_PVCCIN_CPU1_PH5_VCIN" )
			)
			( signal "@baseboard_fab2_lib.baseboard_fab2(sch_1):page209_vr_pvccin_cpu1_ph5_vcin"
				( attribute "VOLTAGE" "5"
					( Units "uVoltage" "V" 1.000000)
					( Origin gFrontEnd )
				)
				( objectFlag fObjectAlias )
				( objectStatus "page209_vr_pvccin_cpu1_ph5_vcin" )
			)
			( signal "@baseboard_fab2_lib.baseboard_fab2(sch_1):vr_pvccin_cpu1_phase5"
				( alias ( signalRef "@baseboard_fab2_lib.baseboard_fab2(sch_1):page209_vr_pvccin_cpu1_phase5") )
				( attribute "VOLTAGE" "5"
					( Units "uVoltage" "V" 1.000000)
					( Status sAliasFlattened )
					( Origin gFrontEnd )
				)
				( attribute "CDS_PHYS_NET_NAME" "VR_PVCCIN_CPU1_PHASE5"
					( Origin gPackager )
				)
				( objectStatus "VR_PVCCIN_CPU1_PHASE5" )
			)
			( signal "@baseboard_fab2_lib.baseboard_fab2(sch_1):page209_vr_pvccin_cpu1_phase5"
				( attribute "VOLTAGE" "5"
					( Units "uVoltage" "V" 1.000000)
					( Origin gFrontEnd )
				)
				( objectFlag fObjectAlias )
				( objectStatus "page209_vr_pvccin_cpu1_phase5" )
			)
			( signal "@baseboard_fab2_lib.baseboard_fab2(sch_1):nc_pvsa_cpu1_p31"
				( attribute "CDS_PHYS_NET_NAME" "NC_PVSA_CPU1_P31"
					( Origin gPackager )
				)
				( objectStatus "NC_PVSA_CPU1_P31" )
			)
			( signal "@baseboard_fab2_lib.baseboard_fab2(sch_1):tp_pvsa_cpu1_gl_0"
				( attribute "CDS_PHYS_NET_NAME" "TP_PVSA_CPU1_GL_0"
					( Origin gPackager )
				)
				( objectStatus "TP_PVSA_CPU1_GL_0" )
			)
			( signal "@baseboard_fab2_lib.baseboard_fab2(sch_1):tp_pvsa_cpu1_gl_1"
				( attribute "CDS_PHYS_NET_NAME" "TP_PVSA_CPU1_GL_1"
					( Origin gPackager )
				)
				( objectStatus "TP_PVSA_CPU1_GL_1" )
			)
			( signal "@baseboard_fab2_lib.baseboard_fab2(sch_1):vr_pvsa_cpu1_boot"
				( attribute "CDS_PHYS_NET_NAME" "VR_PVSA_CPU1_BOOT"
					( Origin gPackager )
				)
				( objectStatus "VR_PVSA_CPU1_BOOT" )
			)
			( signal "@baseboard_fab2_lib.baseboard_fab2(sch_1):\unnamed_214_3d01r5f-gp_i132_2\"
				( attribute "CDS_PHYS_NET_NAME" "UNNAMED_214_3D01R5F-GP_I132_2"
					( Origin gPackager )
				)
				( objectStatus "UNNAMED_214_3D01R5F-GP_I132_2" )
			)
			( signal "@baseboard_fab2_lib.baseboard_fab2(sch_1):vr_pvsa_cpu1_ocset"
				( attribute "CDS_PHYS_NET_NAME" "VR_PVSA_CPU1_OCSET"
					( Origin gPackager )
				)
				( objectStatus "VR_PVSA_CPU1_OCSET" )
			)
			( signal "@baseboard_fab2_lib.baseboard_fab2(sch_1):vr_pvsa_cpu1_phase"
				( alias ( signalRef "@baseboard_fab2_lib.baseboard_fab2(sch_1):page210_vr_pvsa_cpu1_phase") )
				( attribute "VOLTAGE" "5"
					( Units "uVoltage" "V" 1.000000)
					( Status sAliasFlattened )
					( Origin gFrontEnd )
				)
				( attribute "CDS_PHYS_NET_NAME" "VR_PVSA_CPU1_PHASE"
					( Origin gPackager )
				)
				( objectStatus "VR_PVSA_CPU1_PHASE" )
			)
			( signal "@baseboard_fab2_lib.baseboard_fab2(sch_1):page210_vr_pvsa_cpu1_phase"
				( attribute "VOLTAGE" "5"
					( Units "uVoltage" "V" 1.000000)
					( Origin gFrontEnd )
				)
				( objectFlag fObjectAlias )
				( objectStatus "page210_vr_pvsa_cpu1_phase" )
			)
			( signal "@baseboard_fab2_lib.baseboard_fab2(sch_1):vr_pvsa_cpu1_phase_sw"
				( alias ( signalRef "@baseboard_fab2_lib.baseboard_fab2(sch_1):page210_vr_pvsa_cpu1_phase_sw") )
				( attribute "VOLTAGE" "5"
					( Units "uVoltage" "V" 1.000000)
					( Status sAliasFlattened )
					( Origin gFrontEnd )
				)
				( attribute "CDS_PHYS_NET_NAME" "VR_PVSA_CPU1_PHASE_SW"
					( Origin gPackager )
				)
				( objectStatus "VR_PVSA_CPU1_PHASE_SW" )
			)
			( signal "@baseboard_fab2_lib.baseboard_fab2(sch_1):page210_vr_pvsa_cpu1_phase_sw"
				( attribute "VOLTAGE" "5"
					( Units "uVoltage" "V" 1.000000)
					( Origin gFrontEnd )
				)
				( objectFlag fObjectAlias )
				( objectStatus "page210_vr_pvsa_cpu1_phase_sw" )
			)
			( signal "@baseboard_fab2_lib.baseboard_fab2(sch_1):vr_pvsa_cpu1_vcin"
				( alias ( signalRef "@baseboard_fab2_lib.baseboard_fab2(sch_1):page210_vr_pvsa_cpu1_vcin") )
				( attribute "VOLTAGE" "5"
					( Units "uVoltage" "V" 1.000000)
					( Status sAliasFlattened )
					( Origin gFrontEnd )
				)
				( attribute "CDS_PHYS_NET_NAME" "VR_PVSA_CPU1_VCIN"
					( Origin gPackager )
				)
				( objectStatus "VR_PVSA_CPU1_VCIN" )
			)
			( signal "@baseboard_fab2_lib.baseboard_fab2(sch_1):page210_vr_pvsa_cpu1_vcin"
				( attribute "VOLTAGE" "5"
					( Units "uVoltage" "V" 1.000000)
					( Origin gFrontEnd )
				)
				( objectFlag fObjectAlias )
				( objectStatus "page210_vr_pvsa_cpu1_vcin" )
			)
			( signal "@baseboard_fab2_lib.baseboard_fab2(sch_1):a_tsense_pvccio_cpu0"
				( alias ( signalRef "@baseboard_fab2_lib.baseboard_fab2(sch_1):page211_a_tsense_pvccio_cpu0") )
				( attribute "VOLTAGE" "3.6"
					( Units "uVoltage" "V" 1.000000)
					( Status sAliasFlattened )
					( Origin gFrontEnd )
				)
				( attribute "CDS_PHYS_NET_NAME" "A_TSENSE_PVCCIO_CPU0"
					( Origin gPackager )
				)
				( objectStatus "A_TSENSE_PVCCIO_CPU0" )
			)
			( signal "@baseboard_fab2_lib.baseboard_fab2(sch_1):page211_a_tsense_pvccio_cpu0"
				( attribute "VOLTAGE" "3.6"
					( Units "uVoltage" "V" 1.000000)
					( Origin gFrontEnd )
				)
				( objectFlag fObjectAlias )
				( objectStatus "page211_a_tsense_pvccio_cpu0" )
			)
			( signal "@baseboard_fab2_lib.baseboard_fab2(sch_1):irq_pvccio_cpu0_vrhot_n"
				( attribute "CDS_PHYS_NET_NAME" "IRQ_PVCCIO_CPU0_VRHOT_N"
					( Origin gPackager )
				)
				( objectStatus "IRQ_PVCCIO_CPU0_VRHOT_N" )
			)
			( signal "@baseboard_fab2_lib.baseboard_fab2(sch_1):isense_pvccio_cpu0_ph1_imon"
				( attribute "CDS_PHYS_NET_NAME" "ISENSE_PVCCIO_CPU0_PH1_IMON"
					( Origin gPackager )
				)
				( objectStatus "ISENSE_PVCCIO_CPU0_PH1_IMON" )
			)
			( signal "@baseboard_fab2_lib.baseboard_fab2(sch_1):nc_pvccio_cpu0_dnc0"
				( attribute "CDS_PHYS_NET_NAME" "NC_PVCCIO_CPU0_DNC0"
					( Origin gPackager )
				)
				( objectStatus "NC_PVCCIO_CPU0_DNC0" )
			)
			( signal "@baseboard_fab2_lib.baseboard_fab2(sch_1):nc_pvccio_cpu0_dnc1"
				( attribute "CDS_PHYS_NET_NAME" "NC_PVCCIO_CPU0_DNC1"
					( Origin gPackager )
				)
				( objectStatus "NC_PVCCIO_CPU0_DNC1" )
			)
			( signal "@baseboard_fab2_lib.baseboard_fab2(sch_1):nc_pvccio_cpu0_dnc2"
				( attribute "CDS_PHYS_NET_NAME" "NC_PVCCIO_CPU0_DNC2"
					( Origin gPackager )
				)
				( objectStatus "NC_PVCCIO_CPU0_DNC2" )
			)
			( signal "@baseboard_fab2_lib.baseboard_fab2(sch_1):nc_pvccio_cpu0_dnc3"
				( attribute "CDS_PHYS_NET_NAME" "NC_PVCCIO_CPU0_DNC3"
					( Origin gPackager )
				)
				( objectStatus "NC_PVCCIO_CPU0_DNC3" )
			)
			( signal "@baseboard_fab2_lib.baseboard_fab2(sch_1):nc_pvccio_cpu0_dnc4"
				( attribute "CDS_PHYS_NET_NAME" "NC_PVCCIO_CPU0_DNC4"
					( Origin gPackager )
				)
				( objectStatus "NC_PVCCIO_CPU0_DNC4" )
			)
			( signal "@baseboard_fab2_lib.baseboard_fab2(sch_1):pu_vr_pvccio_cpu0_fault1"
				( attribute "CDS_PHYS_NET_NAME" "PU_VR_PVCCIO_CPU0_FAULT1"
					( Origin gPackager )
				)
				( objectStatus "PU_VR_PVCCIO_CPU0_FAULT1" )
			)
			( signal "@baseboard_fab2_lib.baseboard_fab2(sch_1):pwrgd_pvccio_cpu0_r"
				( attribute "CDS_PHYS_NET_NAME" "PWRGD_PVCCIO_CPU0_R"
					( Origin gPackager )
				)
				( objectStatus "PWRGD_PVCCIO_CPU0_R" )
			)
			( signal "@baseboard_fab2_lib.baseboard_fab2(sch_1):smb_vr_scl_pvccio_cpu0"
				( attribute "CDS_PHYS_NET_NAME" "SMB_VR_SCL_PVCCIO_CPU0"
					( Origin gPackager )
				)
				( objectStatus "SMB_VR_SCL_PVCCIO_CPU0" )
			)
			( signal "@baseboard_fab2_lib.baseboard_fab2(sch_1):smb_vr_sda_pvccio_cpu0"
				( attribute "CDS_PHYS_NET_NAME" "SMB_VR_SDA_PVCCIO_CPU0"
					( Origin gPackager )
				)
				( objectStatus "SMB_VR_SDA_PVCCIO_CPU0" )
			)
			( signal "@baseboard_fab2_lib.baseboard_fab2(sch_1):svid_alert_pvccio_cpu0"
				( attribute "CDS_PHYS_NET_NAME" "SVID_ALERT_PVCCIO_CPU0"
					( Origin gPackager )
				)
				( objectStatus "SVID_ALERT_PVCCIO_CPU0" )
			)
			( signal "@baseboard_fab2_lib.baseboard_fab2(sch_1):svid_clk_pvccio_cpu0"
				( attribute "CDS_PHYS_NET_NAME" "SVID_CLK_PVCCIO_CPU0"
					( Origin gPackager )
				)
				( objectStatus "SVID_CLK_PVCCIO_CPU0" )
			)
			( signal "@baseboard_fab2_lib.baseboard_fab2(sch_1):svid_vdio_pvccio_cpu0"
				( attribute "CDS_PHYS_NET_NAME" "SVID_VDIO_PVCCIO_CPU0"
					( Origin gPackager )
				)
				( objectStatus "SVID_VDIO_PVCCIO_CPU0" )
			)
			( signal "@baseboard_fab2_lib.baseboard_fab2(sch_1):tp_pvccio_cpu0_biref1"
				( attribute "CDS_PHYS_NET_NAME" "TP_PVCCIO_CPU0_BIREF1"
					( Origin gPackager )
				)
				( objectStatus "TP_PVCCIO_CPU0_BIREF1" )
			)
			( signal "@baseboard_fab2_lib.baseboard_fab2(sch_1):tp_pvccio_cpu0_bpwm1"
				( attribute "CDS_PHYS_NET_NAME" "TP_PVCCIO_CPU0_BPWM1"
					( Origin gPackager )
				)
				( objectStatus "TP_PVCCIO_CPU0_BPWM1" )
			)
			( signal "@baseboard_fab2_lib.baseboard_fab2(sch_1):tp_pvccio_cpu0_btsen"
				( attribute "CDS_PHYS_NET_NAME" "TP_PVCCIO_CPU0_BTSEN"
					( Origin gPackager )
				)
				( objectStatus "TP_PVCCIO_CPU0_BTSEN" )
			)
			( signal "@baseboard_fab2_lib.baseboard_fab2(sch_1):tp_pvccio_cpu0_bvref"
				( attribute "CDS_PHYS_NET_NAME" "TP_PVCCIO_CPU0_BVREF"
					( Origin gPackager )
				)
				( objectStatus "TP_PVCCIO_CPU0_BVREF" )
			)
			( signal "@baseboard_fab2_lib.baseboard_fab2(sch_1):tp_pvccio_cpu0_bvsen"
				( attribute "CDS_PHYS_NET_NAME" "TP_PVCCIO_CPU0_BVSEN"
					( Origin gPackager )
				)
				( objectStatus "TP_PVCCIO_CPU0_BVSEN" )
			)
			( signal "@baseboard_fab2_lib.baseboard_fab2(sch_1):tp_pvccio_cpu0_pinalrt_n"
				( attribute "CDS_PHYS_NET_NAME" "TP_PVCCIO_CPU0_PINALRT_N"
					( Origin gPackager )
				)
				( objectStatus "TP_PVCCIO_CPU0_PINALRT_N" )
			)
			( signal "@baseboard_fab2_lib.baseboard_fab2(sch_1):tp_pvccio_cpu0_reset_n"
				( attribute "CDS_PHYS_NET_NAME" "TP_PVCCIO_CPU0_RESET_N"
					( Origin gPackager )
				)
				( objectStatus "TP_PVCCIO_CPU0_RESET_N" )
			)
			( signal "@baseboard_fab2_lib.baseboard_fab2(sch_1):tp_vr_pvccio_cpu0_aiinsen"
				( attribute "CDS_PHYS_NET_NAME" "TP_VR_PVCCIO_CPU0_AIINSEN"
					( Origin gPackager )
				)
				( objectStatus "TP_VR_PVCCIO_CPU0_AIINSEN" )
			)
			( signal "@baseboard_fab2_lib.baseboard_fab2(sch_1):tp_vr_pvccio_cpu0_mp0"
				( attribute "CDS_PHYS_NET_NAME" "TP_VR_PVCCIO_CPU0_MP0"
					( Origin gPackager )
				)
				( objectStatus "TP_VR_PVCCIO_CPU0_MP0" )
			)
			( signal "@baseboard_fab2_lib.baseboard_fab2(sch_1):tp_vr_pvccio_cpu0_mp1"
				( attribute "CDS_PHYS_NET_NAME" "TP_VR_PVCCIO_CPU0_MP1"
					( Origin gPackager )
				)
				( objectStatus "TP_VR_PVCCIO_CPU0_MP1" )
			)
			( signal "@baseboard_fab2_lib.baseboard_fab2(sch_1):tp_vr_pvccio_cpu0_mp2"
				( attribute "CDS_PHYS_NET_NAME" "TP_VR_PVCCIO_CPU0_MP2"
					( Origin gPackager )
				)
				( objectStatus "TP_VR_PVCCIO_CPU0_MP2" )
			)
			( signal "@baseboard_fab2_lib.baseboard_fab2(sch_1):tp_vr_pvccio_cpu0_mp3"
				( attribute "CDS_PHYS_NET_NAME" "TP_VR_PVCCIO_CPU0_MP3"
					( Origin gPackager )
				)
				( objectStatus "TP_VR_PVCCIO_CPU0_MP3" )
			)
			( signal "@baseboard_fab2_lib.baseboard_fab2(sch_1):vr_fet_sw_p12v_stby_pvccio_cpu0"
				( alias ( signalRef "@baseboard_fab2_lib.baseboard_fab2(sch_1):page211_vr_fet_sw_p12v_stby_pvccio_cpu0") )
				( alias ( signalRef "@baseboard_fab2_lib.baseboard_fab2(sch_1):page212_vr_fet_sw_p12v_stby_pvccio_cpu0") )
				( attribute "VOLTAGE" "12"
					( Units "uVoltage" "V" 1.000000)
					( Status sAliasFlattened )
					( Origin gFrontEnd )
				)
				( attribute "CDS_PHYS_NET_NAME" "VR_FET_SW_P12V_STBY_PVCCIO_CPU0"
					( Origin gPackager )
				)
				( objectStatus "VR_FET_SW_P12V_STBY_PVCCIO_CPU0" )
			)
			( signal "@baseboard_fab2_lib.baseboard_fab2(sch_1):page211_vr_fet_sw_p12v_stby_pvccio_cpu0"
				( objectFlag fObjectAlias )
				( objectStatus "page211_vr_fet_sw_p12v_stby_pvccio_cpu0" )
			)
			( signal "@baseboard_fab2_lib.baseboard_fab2(sch_1):page212_vr_fet_sw_p12v_stby_pvccio_cpu0"
				( attribute "VOLTAGE" "12"
					( Units "uVoltage" "V" 1.000000)
					( Origin gFrontEnd )
				)
				( objectFlag fObjectAlias )
				( objectStatus "page212_vr_fet_sw_p12v_stby_pvccio_cpu0" )
			)
			( signal "@baseboard_fab2_lib.baseboard_fab2(sch_1):vr_pvccio_cpu0_airef1"
				( attribute "CDS_PHYS_NET_NAME" "VR_PVCCIO_CPU0_AIREF1"
					( Origin gPackager )
				)
				( objectStatus "VR_PVCCIO_CPU0_AIREF1" )
			)
			( signal "@baseboard_fab2_lib.baseboard_fab2(sch_1):vr_pvccio_cpu0_avsp"
				( alias ( signalRef "@baseboard_fab2_lib.baseboard_fab2(sch_1):page211_vr_pvccio_cpu0_avsp") )
				( attribute "VOLTAGE" "2"
					( Units "uVoltage" "V" 1.000000)
					( Status sAliasFlattened )
					( Origin gFrontEnd )
				)
				( attribute "CDS_PHYS_NET_NAME" "VR_PVCCIO_CPU0_AVSP"
					( Origin gPackager )
				)
				( objectStatus "VR_PVCCIO_CPU0_AVSP" )
			)
			( signal "@baseboard_fab2_lib.baseboard_fab2(sch_1):page211_vr_pvccio_cpu0_avsp"
				( attribute "VOLTAGE" "2"
					( Units "uVoltage" "V" 1.000000)
					( Origin gFrontEnd )
				)
				( objectFlag fObjectAlias )
				( objectStatus "page211_vr_pvccio_cpu0_avsp" )
			)
			( signal "@baseboard_fab2_lib.baseboard_fab2(sch_1):vr_pvccio_cpu0_en"
				( attribute "CDS_PHYS_NET_NAME" "VR_PVCCIO_CPU0_EN"
					( Origin gPackager )
				)
				( objectStatus "VR_PVCCIO_CPU0_EN" )
			)
			( signal "@baseboard_fab2_lib.baseboard_fab2(sch_1):vr_pvccio_cpu0_pwm1"
				( alias ( signalRef "@baseboard_fab2_lib.baseboard_fab2(sch_1):page211_vr_pvccio_cpu0_pwm1") )
				( attribute "VOLTAGE" "3.3"
					( Units "uVoltage" "V" 1.000000)
					( Status sAliasFlattened )
					( Origin gFrontEnd )
				)
				( attribute "CDS_PHYS_NET_NAME" "VR_PVCCIO_CPU0_PWM1"
					( Origin gPackager )
				)
				( objectStatus "VR_PVCCIO_CPU0_PWM1" )
			)
			( signal "@baseboard_fab2_lib.baseboard_fab2(sch_1):page211_vr_pvccio_cpu0_pwm1"
				( attribute "VOLTAGE" "3.3"
					( Units "uVoltage" "V" 1.000000)
					( Origin gFrontEnd )
				)
				( objectFlag fObjectAlias )
				( objectStatus "page211_vr_pvccio_cpu0_pwm1" )
			)
			( signal "@baseboard_fab2_lib.baseboard_fab2(sch_1):vr_pvccio_cpu0_vd12"
				( attribute "CDS_PHYS_NET_NAME" "VR_PVCCIO_CPU0_VD12"
					( Origin gPackager )
				)
				( objectStatus "VR_PVCCIO_CPU0_VD12" )
			)
			( signal "@baseboard_fab2_lib.baseboard_fab2(sch_1):vr_pvccio_cpu0_vdd"
				( attribute "CDS_PHYS_NET_NAME" "VR_PVCCIO_CPU0_VDD"
					( Origin gPackager )
				)
				( objectStatus "VR_PVCCIO_CPU0_VDD" )
			)
			( signal "@baseboard_fab2_lib.baseboard_fab2(sch_1):vr_pvccio_cpu0_vinsen"
				( alias ( signalRef "@baseboard_fab2_lib.baseboard_fab2(sch_1):page211_vr_pvccio_cpu0_vinsen") )
				( attribute "VOLTAGE" "0.8"
					( Units "uVoltage" "V" 1.000000)
					( Status sAliasFlattened )
					( Origin gFrontEnd )
				)
				( attribute "CDS_PHYS_NET_NAME" "VR_PVCCIO_CPU0_VINSEN"
					( Origin gPackager )
				)
				( objectStatus "VR_PVCCIO_CPU0_VINSEN" )
			)
			( signal "@baseboard_fab2_lib.baseboard_fab2(sch_1):page211_vr_pvccio_cpu0_vinsen"
				( attribute "VOLTAGE" "0.8"
					( Units "uVoltage" "V" 1.000000)
					( Origin gFrontEnd )
				)
				( objectFlag fObjectAlias )
				( objectStatus "page211_vr_pvccio_cpu0_vinsen" )
			)
			( signal "@baseboard_fab2_lib.baseboard_fab2(sch_1):vr_pvccio_cpu0_xaddr1"
				( alias ( signalRef "@baseboard_fab2_lib.baseboard_fab2(sch_1):page211_vr_pvccio_cpu0_xaddr1") )
				( attribute "VOLTAGE" "3.3"
					( Units "uVoltage" "V" 1.000000)
					( Status sAliasFlattened )
					( Origin gFrontEnd )
				)
				( attribute "CDS_PHYS_NET_NAME" "VR_PVCCIO_CPU0_XADDR1"
					( Origin gPackager )
				)
				( objectStatus "VR_PVCCIO_CPU0_XADDR1" )
			)
			( signal "@baseboard_fab2_lib.baseboard_fab2(sch_1):page211_vr_pvccio_cpu0_xaddr1"
				( attribute "VOLTAGE" "3.3"
					( Units "uVoltage" "V" 1.000000)
					( Origin gFrontEnd )
				)
				( objectFlag fObjectAlias )
				( objectStatus "page211_vr_pvccio_cpu0_xaddr1" )
			)
			( signal "@baseboard_fab2_lib.baseboard_fab2(sch_1):vr_pvccio_cpu0_xaddr2"
				( alias ( signalRef "@baseboard_fab2_lib.baseboard_fab2(sch_1):page211_vr_pvccio_cpu0_xaddr2") )
				( attribute "VOLTAGE" "3.3V"
					( Units "uVoltage" "V" 1.000000)
					( Status sAliasFlattened )
					( Origin gFrontEnd )
				)
				( attribute "CDS_PHYS_NET_NAME" "VR_PVCCIO_CPU0_XADDR2"
					( Origin gPackager )
				)
				( objectStatus "VR_PVCCIO_CPU0_XADDR2" )
			)
			( signal "@baseboard_fab2_lib.baseboard_fab2(sch_1):page211_vr_pvccio_cpu0_xaddr2"
				( attribute "VOLTAGE" "3.3V"
					( Units "uVoltage" "V" 1.000000)
					( Origin gFrontEnd )
				)
				( objectFlag fObjectAlias )
				( objectStatus "page211_vr_pvccio_cpu0_xaddr2" )
			)
			( signal "@baseboard_fab2_lib.baseboard_fab2(sch_1):vsense_pvccio_cpu0_avsn"
				( attribute "CDS_PHYS_NET_NAME" "VSENSE_PVCCIO_CPU0_AVSN"
					( Origin gPackager )
				)
				( objectStatus "VSENSE_PVCCIO_CPU0_AVSN" )
			)
			( signal "@baseboard_fab2_lib.baseboard_fab2(sch_1):vsense_pvccio_cpu0_avsp"
				( attribute "CDS_PHYS_NET_NAME" "VSENSE_PVCCIO_CPU0_AVSP"
					( Origin gPackager )
				)
				( objectStatus "VSENSE_PVCCIO_CPU0_AVSP" )
			)
			( signal "@baseboard_fab2_lib.baseboard_fab2(sch_1):nc_pvccio_cpu0_ph1_p31"
				( attribute "CDS_PHYS_NET_NAME" "NC_PVCCIO_CPU0_PH1_P31"
					( Origin gPackager )
				)
				( objectStatus "NC_PVCCIO_CPU0_PH1_P31" )
			)
			( signal "@baseboard_fab2_lib.baseboard_fab2(sch_1):tp_pvccio_cpu0_gl_0"
				( attribute "CDS_PHYS_NET_NAME" "TP_PVCCIO_CPU0_GL_0"
					( Origin gPackager )
				)
				( objectStatus "TP_PVCCIO_CPU0_GL_0" )
			)
			( signal "@baseboard_fab2_lib.baseboard_fab2(sch_1):tp_pvccio_cpu0_gl_1"
				( attribute "CDS_PHYS_NET_NAME" "TP_PVCCIO_CPU0_GL_1"
					( Origin gPackager )
				)
				( objectStatus "TP_PVCCIO_CPU0_GL_1" )
			)
			( signal "@baseboard_fab2_lib.baseboard_fab2(sch_1):vr_pvccio_cpu0_ocset"
				( attribute "CDS_PHYS_NET_NAME" "VR_PVCCIO_CPU0_OCSET"
					( Origin gPackager )
				)
				( objectStatus "VR_PVCCIO_CPU0_OCSET" )
			)
			( signal "@baseboard_fab2_lib.baseboard_fab2(sch_1):vr_pvccio_cpu0_ph1_boot"
				( attribute "CDS_PHYS_NET_NAME" "VR_PVCCIO_CPU0_PH1_BOOT"
					( Origin gPackager )
				)
				( objectStatus "VR_PVCCIO_CPU0_PH1_BOOT" )
			)
			( signal "@baseboard_fab2_lib.baseboard_fab2(sch_1):\unnamed_207_3d01r5f-gp_i76_2\"
				( attribute "CDS_PHYS_NET_NAME" "UNNAMED_207_3D01R5F-GP_I76_2"
					( Origin gPackager )
				)
				( objectStatus "UNNAMED_207_3D01R5F-GP_I76_2" )
			)
			( signal "@baseboard_fab2_lib.baseboard_fab2(sch_1):vr_pvccio_cpu0_ph1_phase"
				( alias ( signalRef "@baseboard_fab2_lib.baseboard_fab2(sch_1):page212_vr_pvccio_cpu0_ph1_phase") )
				( attribute "VOLTAGE" "5"
					( Units "uVoltage" "V" 1.000000)
					( Status sAliasFlattened )
					( Origin gFrontEnd )
				)
				( attribute "CDS_PHYS_NET_NAME" "VR_PVCCIO_CPU0_PH1_PHASE"
					( Origin gPackager )
				)
				( objectStatus "VR_PVCCIO_CPU0_PH1_PHASE" )
			)
			( signal "@baseboard_fab2_lib.baseboard_fab2(sch_1):page212_vr_pvccio_cpu0_ph1_phase"
				( attribute "VOLTAGE" "5"
					( Units "uVoltage" "V" 1.000000)
					( Origin gFrontEnd )
				)
				( objectFlag fObjectAlias )
				( objectStatus "page212_vr_pvccio_cpu0_ph1_phase" )
			)
			( signal "@baseboard_fab2_lib.baseboard_fab2(sch_1):vr_pvccio_cpu0_ph1_sw"
				( alias ( signalRef "@baseboard_fab2_lib.baseboard_fab2(sch_1):page212_vr_pvccio_cpu0_ph1_sw") )
				( attribute "VOLTAGE" "5"
					( Units "uVoltage" "V" 1.000000)
					( Status sAliasFlattened )
					( Origin gFrontEnd )
				)
				( attribute "CDS_PHYS_NET_NAME" "VR_PVCCIO_CPU0_PH1_SW"
					( Origin gPackager )
				)
				( objectStatus "VR_PVCCIO_CPU0_PH1_SW" )
			)
			( signal "@baseboard_fab2_lib.baseboard_fab2(sch_1):page212_vr_pvccio_cpu0_ph1_sw"
				( attribute "VOLTAGE" "5"
					( Units "uVoltage" "V" 1.000000)
					( Origin gFrontEnd )
				)
				( objectFlag fObjectAlias )
				( objectStatus "page212_vr_pvccio_cpu0_ph1_sw" )
			)
			( signal "@baseboard_fab2_lib.baseboard_fab2(sch_1):vr_pvccio_cpu0_ph1_vcin"
				( alias ( signalRef "@baseboard_fab2_lib.baseboard_fab2(sch_1):page212_vr_pvccio_cpu0_ph1_vcin") )
				( attribute "VOLTAGE" "5"
					( Units "uVoltage" "V" 1.000000)
					( Status sAliasFlattened )
					( Origin gFrontEnd )
				)
				( attribute "CDS_PHYS_NET_NAME" "VR_PVCCIO_CPU0_PH1_VCIN"
					( Origin gPackager )
				)
				( objectStatus "VR_PVCCIO_CPU0_PH1_VCIN" )
			)
			( signal "@baseboard_fab2_lib.baseboard_fab2(sch_1):page212_vr_pvccio_cpu0_ph1_vcin"
				( attribute "VOLTAGE" "5"
					( Units "uVoltage" "V" 1.000000)
					( Origin gFrontEnd )
				)
				( objectFlag fObjectAlias )
				( objectStatus "page212_vr_pvccio_cpu0_ph1_vcin" )
			)
			( signal "@baseboard_fab2_lib.baseboard_fab2(sch_1):a_tsense_pvccio_cpu1"
				( attribute "CDS_PHYS_NET_NAME" "A_TSENSE_PVCCIO_CPU1"
					( Origin gPackager )
				)
				( objectStatus "A_TSENSE_PVCCIO_CPU1" )
			)
			( signal "@baseboard_fab2_lib.baseboard_fab2(sch_1):irq_pvccio_cpu1_vrhot_n"
				( attribute "CDS_PHYS_NET_NAME" "IRQ_PVCCIO_CPU1_VRHOT_N"
					( Origin gPackager )
				)
				( objectStatus "IRQ_PVCCIO_CPU1_VRHOT_N" )
			)
			( signal "@baseboard_fab2_lib.baseboard_fab2(sch_1):isense_pvccio_cpu1_ph1_imon"
				( attribute "CDS_PHYS_NET_NAME" "ISENSE_PVCCIO_CPU1_PH1_IMON"
					( Origin gPackager )
				)
				( objectStatus "ISENSE_PVCCIO_CPU1_PH1_IMON" )
			)
			( signal "@baseboard_fab2_lib.baseboard_fab2(sch_1):nc_pvccio_cpu1_dnc0"
				( attribute "CDS_PHYS_NET_NAME" "NC_PVCCIO_CPU1_DNC0"
					( Origin gPackager )
				)
				( objectStatus "NC_PVCCIO_CPU1_DNC0" )
			)
			( signal "@baseboard_fab2_lib.baseboard_fab2(sch_1):nc_pvccio_cpu1_dnc1"
				( attribute "CDS_PHYS_NET_NAME" "NC_PVCCIO_CPU1_DNC1"
					( Origin gPackager )
				)
				( objectStatus "NC_PVCCIO_CPU1_DNC1" )
			)
			( signal "@baseboard_fab2_lib.baseboard_fab2(sch_1):nc_pvccio_cpu1_dnc2"
				( attribute "CDS_PHYS_NET_NAME" "NC_PVCCIO_CPU1_DNC2"
					( Origin gPackager )
				)
				( objectStatus "NC_PVCCIO_CPU1_DNC2" )
			)
			( signal "@baseboard_fab2_lib.baseboard_fab2(sch_1):nc_pvccio_cpu1_dnc3"
				( attribute "CDS_PHYS_NET_NAME" "NC_PVCCIO_CPU1_DNC3"
					( Origin gPackager )
				)
				( objectStatus "NC_PVCCIO_CPU1_DNC3" )
			)
			( signal "@baseboard_fab2_lib.baseboard_fab2(sch_1):nc_pvccio_cpu1_dnc4"
				( attribute "CDS_PHYS_NET_NAME" "NC_PVCCIO_CPU1_DNC4"
					( Origin gPackager )
				)
				( objectStatus "NC_PVCCIO_CPU1_DNC4" )
			)
			( signal "@baseboard_fab2_lib.baseboard_fab2(sch_1):pu_vr_pvccio_cpu1_fault1"
				( attribute "CDS_PHYS_NET_NAME" "PU_VR_PVCCIO_CPU1_FAULT1"
					( Origin gPackager )
				)
				( objectStatus "PU_VR_PVCCIO_CPU1_FAULT1" )
			)
			( signal "@baseboard_fab2_lib.baseboard_fab2(sch_1):pwrgd_pvccio_cpu1_r"
				( attribute "CDS_PHYS_NET_NAME" "PWRGD_PVCCIO_CPU1_R"
					( Origin gPackager )
				)
				( objectStatus "PWRGD_PVCCIO_CPU1_R" )
			)
			( signal "@baseboard_fab2_lib.baseboard_fab2(sch_1):smb_vr_scl_pvccio_cpu1"
				( attribute "CDS_PHYS_NET_NAME" "SMB_VR_SCL_PVCCIO_CPU1"
					( Origin gPackager )
				)
				( objectStatus "SMB_VR_SCL_PVCCIO_CPU1" )
			)
			( signal "@baseboard_fab2_lib.baseboard_fab2(sch_1):smb_vr_sda_pvccio_cpu1"
				( attribute "CDS_PHYS_NET_NAME" "SMB_VR_SDA_PVCCIO_CPU1"
					( Origin gPackager )
				)
				( objectStatus "SMB_VR_SDA_PVCCIO_CPU1" )
			)
			( signal "@baseboard_fab2_lib.baseboard_fab2(sch_1):svid_alert_pvccio_cpu1"
				( attribute "CDS_PHYS_NET_NAME" "SVID_ALERT_PVCCIO_CPU1"
					( Origin gPackager )
				)
				( objectStatus "SVID_ALERT_PVCCIO_CPU1" )
			)
			( signal "@baseboard_fab2_lib.baseboard_fab2(sch_1):svid_clk_pvccio_cpu1"
				( attribute "CDS_PHYS_NET_NAME" "SVID_CLK_PVCCIO_CPU1"
					( Origin gPackager )
				)
				( objectStatus "SVID_CLK_PVCCIO_CPU1" )
			)
			( signal "@baseboard_fab2_lib.baseboard_fab2(sch_1):svid_vdio_pvccio_cpu1"
				( attribute "CDS_PHYS_NET_NAME" "SVID_VDIO_PVCCIO_CPU1"
					( Origin gPackager )
				)
				( objectStatus "SVID_VDIO_PVCCIO_CPU1" )
			)
			( signal "@baseboard_fab2_lib.baseboard_fab2(sch_1):tp_pvccio_cpu1_biref1"
				( attribute "CDS_PHYS_NET_NAME" "TP_PVCCIO_CPU1_BIREF1"
					( Origin gPackager )
				)
				( objectStatus "TP_PVCCIO_CPU1_BIREF1" )
			)
			( signal "@baseboard_fab2_lib.baseboard_fab2(sch_1):tp_pvccio_cpu1_bpwm1"
				( attribute "CDS_PHYS_NET_NAME" "TP_PVCCIO_CPU1_BPWM1"
					( Origin gPackager )
				)
				( objectStatus "TP_PVCCIO_CPU1_BPWM1" )
			)
			( signal "@baseboard_fab2_lib.baseboard_fab2(sch_1):tp_pvccio_cpu1_btsen"
				( attribute "CDS_PHYS_NET_NAME" "TP_PVCCIO_CPU1_BTSEN"
					( Origin gPackager )
				)
				( objectStatus "TP_PVCCIO_CPU1_BTSEN" )
			)
			( signal "@baseboard_fab2_lib.baseboard_fab2(sch_1):tp_pvccio_cpu1_bvref"
				( attribute "CDS_PHYS_NET_NAME" "TP_PVCCIO_CPU1_BVREF"
					( Origin gPackager )
				)
				( objectStatus "TP_PVCCIO_CPU1_BVREF" )
			)
			( signal "@baseboard_fab2_lib.baseboard_fab2(sch_1):tp_pvccio_cpu1_bvsen"
				( attribute "CDS_PHYS_NET_NAME" "TP_PVCCIO_CPU1_BVSEN"
					( Origin gPackager )
				)
				( objectStatus "TP_PVCCIO_CPU1_BVSEN" )
			)
			( signal "@baseboard_fab2_lib.baseboard_fab2(sch_1):tp_pvccio_cpu1_pinalrt_n"
				( attribute "CDS_PHYS_NET_NAME" "TP_PVCCIO_CPU1_PINALRT_N"
					( Origin gPackager )
				)
				( objectStatus "TP_PVCCIO_CPU1_PINALRT_N" )
			)
			( signal "@baseboard_fab2_lib.baseboard_fab2(sch_1):tp_pvccio_cpu1_reset_n"
				( attribute "CDS_PHYS_NET_NAME" "TP_PVCCIO_CPU1_RESET_N"
					( Origin gPackager )
				)
				( objectStatus "TP_PVCCIO_CPU1_RESET_N" )
			)
			( signal "@baseboard_fab2_lib.baseboard_fab2(sch_1):tp_vr_pvccio_cpu1_aiinsen"
				( attribute "CDS_PHYS_NET_NAME" "TP_VR_PVCCIO_CPU1_AIINSEN"
					( Origin gPackager )
				)
				( objectStatus "TP_VR_PVCCIO_CPU1_AIINSEN" )
			)
			( signal "@baseboard_fab2_lib.baseboard_fab2(sch_1):tp_vr_pvccio_cpu1_mp0"
				( attribute "CDS_PHYS_NET_NAME" "TP_VR_PVCCIO_CPU1_MP0"
					( Origin gPackager )
				)
				( objectStatus "TP_VR_PVCCIO_CPU1_MP0" )
			)
			( signal "@baseboard_fab2_lib.baseboard_fab2(sch_1):tp_vr_pvccio_cpu1_mp1"
				( attribute "CDS_PHYS_NET_NAME" "TP_VR_PVCCIO_CPU1_MP1"
					( Origin gPackager )
				)
				( objectStatus "TP_VR_PVCCIO_CPU1_MP1" )
			)
			( signal "@baseboard_fab2_lib.baseboard_fab2(sch_1):tp_vr_pvccio_cpu1_mp2"
				( attribute "CDS_PHYS_NET_NAME" "TP_VR_PVCCIO_CPU1_MP2"
					( Origin gPackager )
				)
				( objectStatus "TP_VR_PVCCIO_CPU1_MP2" )
			)
			( signal "@baseboard_fab2_lib.baseboard_fab2(sch_1):tp_vr_pvccio_cpu1_mp3"
				( attribute "CDS_PHYS_NET_NAME" "TP_VR_PVCCIO_CPU1_MP3"
					( Origin gPackager )
				)
				( objectStatus "TP_VR_PVCCIO_CPU1_MP3" )
			)
			( signal "@baseboard_fab2_lib.baseboard_fab2(sch_1):vr_pvccio_cpu1_airef1"
				( attribute "CDS_PHYS_NET_NAME" "VR_PVCCIO_CPU1_AIREF1"
					( Origin gPackager )
				)
				( objectStatus "VR_PVCCIO_CPU1_AIREF1" )
			)
			( signal "@baseboard_fab2_lib.baseboard_fab2(sch_1):vr_pvccio_cpu1_avsp"
				( alias ( signalRef "@baseboard_fab2_lib.baseboard_fab2(sch_1):page213_vr_pvccio_cpu1_avsp") )
				( attribute "VOLTAGE" "1.05"
					( Units "uVoltage" "V" 1.000000)
					( Status sAliasFlattened )
					( Origin gFrontEnd )
				)
				( attribute "CDS_PHYS_NET_NAME" "VR_PVCCIO_CPU1_AVSP"
					( Origin gPackager )
				)
				( objectStatus "VR_PVCCIO_CPU1_AVSP" )
			)
			( signal "@baseboard_fab2_lib.baseboard_fab2(sch_1):page213_vr_pvccio_cpu1_avsp"
				( attribute "VOLTAGE" "1.05"
					( Units "uVoltage" "V" 1.000000)
					( Origin gFrontEnd )
				)
				( objectFlag fObjectAlias )
				( objectStatus "page213_vr_pvccio_cpu1_avsp" )
			)
			( signal "@baseboard_fab2_lib.baseboard_fab2(sch_1):vr_pvccio_cpu1_en"
				( alias ( signalRef "@baseboard_fab2_lib.baseboard_fab2(sch_1):page213_vr_pvccio_cpu1_en") )
				( attribute "VOLTAGE" "3.3"
					( Units "uVoltage" "V" 1.000000)
					( Status sAliasFlattened )
					( Origin gFrontEnd )
				)
				( attribute "CDS_PHYS_NET_NAME" "VR_PVCCIO_CPU1_EN"
					( Origin gPackager )
				)
				( objectStatus "VR_PVCCIO_CPU1_EN" )
			)
			( signal "@baseboard_fab2_lib.baseboard_fab2(sch_1):page213_vr_pvccio_cpu1_en"
				( attribute "VOLTAGE" "3.3"
					( Units "uVoltage" "V" 1.000000)
					( Origin gFrontEnd )
				)
				( objectFlag fObjectAlias )
				( objectStatus "page213_vr_pvccio_cpu1_en" )
			)
			( signal "@baseboard_fab2_lib.baseboard_fab2(sch_1):vr_pvccio_cpu1_pwm1"
				( alias ( signalRef "@baseboard_fab2_lib.baseboard_fab2(sch_1):page213_vr_pvccio_cpu1_pwm1") )
				( attribute "VOLTAGE" "3.6"
					( Units "uVoltage" "V" 1.000000)
					( Status sAliasFlattened )
					( Origin gFrontEnd )
				)
				( attribute "CDS_PHYS_NET_NAME" "VR_PVCCIO_CPU1_PWM1"
					( Origin gPackager )
				)
				( objectStatus "VR_PVCCIO_CPU1_PWM1" )
			)
			( signal "@baseboard_fab2_lib.baseboard_fab2(sch_1):page213_vr_pvccio_cpu1_pwm1"
				( attribute "VOLTAGE" "3.6"
					( Units "uVoltage" "V" 1.000000)
					( Origin gFrontEnd )
				)
				( objectFlag fObjectAlias )
				( objectStatus "page213_vr_pvccio_cpu1_pwm1" )
			)
			( signal "@baseboard_fab2_lib.baseboard_fab2(sch_1):vr_pvccio_cpu1_vd12"
				( attribute "CDS_PHYS_NET_NAME" "VR_PVCCIO_CPU1_VD12"
					( Origin gPackager )
				)
				( objectStatus "VR_PVCCIO_CPU1_VD12" )
			)
			( signal "@baseboard_fab2_lib.baseboard_fab2(sch_1):vr_pvccio_cpu1_vdd"
				( alias ( signalRef "@baseboard_fab2_lib.baseboard_fab2(sch_1):page213_vr_pvccio_cpu1_vdd") )
				( attribute "VOLTAGE" "3.3"
					( Units "uVoltage" "V" 1.000000)
					( Status sAliasFlattened )
					( Origin gFrontEnd )
				)
				( attribute "CDS_PHYS_NET_NAME" "VR_PVCCIO_CPU1_VDD"
					( Origin gPackager )
				)
				( objectStatus "VR_PVCCIO_CPU1_VDD" )
			)
			( signal "@baseboard_fab2_lib.baseboard_fab2(sch_1):page213_vr_pvccio_cpu1_vdd"
				( attribute "VOLTAGE" "3.3"
					( Units "uVoltage" "V" 1.000000)
					( Origin gFrontEnd )
				)
				( objectFlag fObjectAlias )
				( objectStatus "page213_vr_pvccio_cpu1_vdd" )
			)
			( signal "@baseboard_fab2_lib.baseboard_fab2(sch_1):vr_pvccio_cpu1_vinsen"
				( attribute "CDS_PHYS_NET_NAME" "VR_PVCCIO_CPU1_VINSEN"
					( Origin gPackager )
				)
				( objectStatus "VR_PVCCIO_CPU1_VINSEN" )
			)
			( signal "@baseboard_fab2_lib.baseboard_fab2(sch_1):vr_pvccio_cpu1_xaddr1"
				( alias ( signalRef "@baseboard_fab2_lib.baseboard_fab2(sch_1):page213_vr_pvccio_cpu1_xaddr1") )
				( attribute "VOLTAGE" "3.3"
					( Units "uVoltage" "V" 1.000000)
					( Status sAliasFlattened )
					( Origin gFrontEnd )
				)
				( attribute "CDS_PHYS_NET_NAME" "VR_PVCCIO_CPU1_XADDR1"
					( Origin gPackager )
				)
				( objectStatus "VR_PVCCIO_CPU1_XADDR1" )
			)
			( signal "@baseboard_fab2_lib.baseboard_fab2(sch_1):page213_vr_pvccio_cpu1_xaddr1"
				( attribute "VOLTAGE" "3.3"
					( Units "uVoltage" "V" 1.000000)
					( Origin gFrontEnd )
				)
				( objectFlag fObjectAlias )
				( objectStatus "page213_vr_pvccio_cpu1_xaddr1" )
			)
			( signal "@baseboard_fab2_lib.baseboard_fab2(sch_1):vr_pvccio_cpu1_xaddr2"
				( alias ( signalRef "@baseboard_fab2_lib.baseboard_fab2(sch_1):page213_vr_pvccio_cpu1_xaddr2") )
				( attribute "VOLTAGE" "3.3"
					( Units "uVoltage" "V" 1.000000)
					( Status sAliasFlattened )
					( Origin gFrontEnd )
				)
				( attribute "CDS_PHYS_NET_NAME" "VR_PVCCIO_CPU1_XADDR2"
					( Origin gPackager )
				)
				( objectStatus "VR_PVCCIO_CPU1_XADDR2" )
			)
			( signal "@baseboard_fab2_lib.baseboard_fab2(sch_1):page213_vr_pvccio_cpu1_xaddr2"
				( attribute "VOLTAGE" "3.3"
					( Units "uVoltage" "V" 1.000000)
					( Origin gFrontEnd )
				)
				( objectFlag fObjectAlias )
				( objectStatus "page213_vr_pvccio_cpu1_xaddr2" )
			)
			( signal "@baseboard_fab2_lib.baseboard_fab2(sch_1):vsense_pvccio_cpu1_avsn"
				( attribute "CDS_PHYS_NET_NAME" "VSENSE_PVCCIO_CPU1_AVSN"
					( Origin gPackager )
				)
				( objectStatus "VSENSE_PVCCIO_CPU1_AVSN" )
			)
			( signal "@baseboard_fab2_lib.baseboard_fab2(sch_1):vsense_pvccio_cpu1_avsp"
				( attribute "CDS_PHYS_NET_NAME" "VSENSE_PVCCIO_CPU1_AVSP"
					( Origin gPackager )
				)
				( objectStatus "VSENSE_PVCCIO_CPU1_AVSP" )
			)
			( signal "@baseboard_fab2_lib.baseboard_fab2(sch_1):nc_pvccio_cpu1_ph1_p31"
				( attribute "CDS_PHYS_NET_NAME" "NC_PVCCIO_CPU1_PH1_P31"
					( Origin gPackager )
				)
				( objectStatus "NC_PVCCIO_CPU1_PH1_P31" )
			)
			( signal "@baseboard_fab2_lib.baseboard_fab2(sch_1):tp_pvccio_cpu1_gl_0"
				( attribute "CDS_PHYS_NET_NAME" "TP_PVCCIO_CPU1_GL_0"
					( Origin gPackager )
				)
				( objectStatus "TP_PVCCIO_CPU1_GL_0" )
			)
			( signal "@baseboard_fab2_lib.baseboard_fab2(sch_1):tp_pvccio_cpu1_gl_1"
				( attribute "CDS_PHYS_NET_NAME" "TP_PVCCIO_CPU1_GL_1"
					( Origin gPackager )
				)
				( objectStatus "TP_PVCCIO_CPU1_GL_1" )
			)
			( signal "@baseboard_fab2_lib.baseboard_fab2(sch_1):vr_pvccio_cpu1_ocset"
				( attribute "CDS_PHYS_NET_NAME" "VR_PVCCIO_CPU1_OCSET"
					( Origin gPackager )
				)
				( objectStatus "VR_PVCCIO_CPU1_OCSET" )
			)
			( signal "@baseboard_fab2_lib.baseboard_fab2(sch_1):vr_pvccio_cpu1_ph1_boot"
				( attribute "CDS_PHYS_NET_NAME" "VR_PVCCIO_CPU1_PH1_BOOT"
					( Origin gPackager )
				)
				( objectStatus "VR_PVCCIO_CPU1_PH1_BOOT" )
			)
			( signal "@baseboard_fab2_lib.baseboard_fab2(sch_1):vr_pvccio_cpu1_ph1_phase"
				( attribute "CDS_PHYS_NET_NAME" "VR_PVCCIO_CPU1_PH1_PHASE"
					( Origin gPackager )
				)
				( objectStatus "VR_PVCCIO_CPU1_PH1_PHASE" )
			)
			( signal "@baseboard_fab2_lib.baseboard_fab2(sch_1):vr_pvccio_cpu1_ph1_sw"
				( attribute "CDS_PHYS_NET_NAME" "VR_PVCCIO_CPU1_PH1_SW"
					( Origin gPackager )
				)
				( objectStatus "VR_PVCCIO_CPU1_PH1_SW" )
			)
			( signal "@baseboard_fab2_lib.baseboard_fab2(sch_1):vr_pvccio_cpu1_ph1_vcin"
				( attribute "CDS_PHYS_NET_NAME" "VR_PVCCIO_CPU1_PH1_VCIN"
					( Origin gPackager )
				)
				( objectStatus "VR_PVCCIO_CPU1_PH1_VCIN" )
			)
			( signal "@baseboard_fab2_lib.baseboard_fab2(sch_1):a_tsense_pvddq_abc"
				( attribute "CDS_PHYS_NET_NAME" "A_TSENSE_PVDDQ_ABC"
					( Origin gPackager )
				)
				( objectStatus "A_TSENSE_PVDDQ_ABC" )
			)
			( signal "@baseboard_fab2_lib.baseboard_fab2(sch_1):irq_pvddq_abc_vrhot_lvt3_r_n"
				( attribute "CDS_PHYS_NET_NAME" "IRQ_PVDDQ_ABC_VRHOT_LVT3_R_N"
					( Origin gPackager )
				)
				( objectStatus "IRQ_PVDDQ_ABC_VRHOT_LVT3_R_N" )
			)
			( signal "@baseboard_fab2_lib.baseboard_fab2(sch_1):isense_pvddq_abc_ph1_imon"
				( attribute "CDS_PHYS_NET_NAME" "ISENSE_PVDDQ_ABC_PH1_IMON"
					( Origin gPackager )
				)
				( objectStatus "ISENSE_PVDDQ_ABC_PH1_IMON" )
			)
			( signal "@baseboard_fab2_lib.baseboard_fab2(sch_1):isense_pvddq_abc_ph2_imon"
				( attribute "CDS_PHYS_NET_NAME" "ISENSE_PVDDQ_ABC_PH2_IMON"
					( Origin gPackager )
				)
				( objectStatus "ISENSE_PVDDQ_ABC_PH2_IMON" )
			)
			( signal "@baseboard_fab2_lib.baseboard_fab2(sch_1):nc_pvddq_abc_dnc0"
				( attribute "CDS_PHYS_NET_NAME" "NC_PVDDQ_ABC_DNC0"
					( Origin gPackager )
				)
				( objectStatus "NC_PVDDQ_ABC_DNC0" )
			)
			( signal "@baseboard_fab2_lib.baseboard_fab2(sch_1):nc_pvddq_abc_dnc1"
				( attribute "CDS_PHYS_NET_NAME" "NC_PVDDQ_ABC_DNC1"
					( Origin gPackager )
				)
				( objectStatus "NC_PVDDQ_ABC_DNC1" )
			)
			( signal "@baseboard_fab2_lib.baseboard_fab2(sch_1):pu_vr_pvddq_abc_fault1"
				( attribute "CDS_PHYS_NET_NAME" "PU_VR_PVDDQ_ABC_FAULT1"
					( Origin gPackager )
				)
				( objectStatus "PU_VR_PVDDQ_ABC_FAULT1" )
			)
			( signal "@baseboard_fab2_lib.baseboard_fab2(sch_1):pwrgd_pvddq_abc"
				( attribute "CDS_PHYS_NET_NAME" "PWRGD_PVDDQ_ABC"
					( Origin gPackager )
				)
				( objectStatus "PWRGD_PVDDQ_ABC" )
			)
			( signal "@baseboard_fab2_lib.baseboard_fab2(sch_1):pwrgd_pvddq_abc_r"
				( attribute "CDS_PHYS_NET_NAME" "PWRGD_PVDDQ_ABC_R"
					( Origin gPackager )
				)
				( objectStatus "PWRGD_PVDDQ_ABC_R" )
			)
			( signal "@baseboard_fab2_lib.baseboard_fab2(sch_1):smb_vr_scl_vddq_abc"
				( attribute "CDS_PHYS_NET_NAME" "SMB_VR_SCL_VDDQ_ABC"
					( Origin gPackager )
				)
				( objectStatus "SMB_VR_SCL_VDDQ_ABC" )
			)
			( signal "@baseboard_fab2_lib.baseboard_fab2(sch_1):smb_vr_sda_vddq_abc"
				( attribute "CDS_PHYS_NET_NAME" "SMB_VR_SDA_VDDQ_ABC"
					( Origin gPackager )
				)
				( objectStatus "SMB_VR_SDA_VDDQ_ABC" )
			)
			( signal "@baseboard_fab2_lib.baseboard_fab2(sch_1):svid_alert_pvddq_abc"
				( attribute "CDS_PHYS_NET_NAME" "SVID_ALERT_PVDDQ_ABC"
					( Origin gPackager )
				)
				( objectStatus "SVID_ALERT_PVDDQ_ABC" )
			)
			( signal "@baseboard_fab2_lib.baseboard_fab2(sch_1):svid_clk_pvddq_abc"
				( attribute "CDS_PHYS_NET_NAME" "SVID_CLK_PVDDQ_ABC"
					( Origin gPackager )
				)
				( objectStatus "SVID_CLK_PVDDQ_ABC" )
			)
			( signal "@baseboard_fab2_lib.baseboard_fab2(sch_1):svid_vdio_pvddq_abc"
				( attribute "CDS_PHYS_NET_NAME" "SVID_VDIO_PVDDQ_ABC"
					( Origin gPackager )
				)
				( objectStatus "SVID_VDIO_PVDDQ_ABC" )
			)
			( signal "@baseboard_fab2_lib.baseboard_fab2(sch_1):tp_pvddq_abc_bpwm1"
				( attribute "CDS_PHYS_NET_NAME" "TP_PVDDQ_ABC_BPWM1"
					( Origin gPackager )
				)
				( objectStatus "TP_PVDDQ_ABC_BPWM1" )
			)
			( signal "@baseboard_fab2_lib.baseboard_fab2(sch_1):tp_pvddq_abc_bref1"
				( attribute "CDS_PHYS_NET_NAME" "TP_PVDDQ_ABC_BREF1"
					( Origin gPackager )
				)
				( objectStatus "TP_PVDDQ_ABC_BREF1" )
			)
			( signal "@baseboard_fab2_lib.baseboard_fab2(sch_1):tp_pvddq_abc_btsen"
				( attribute "CDS_PHYS_NET_NAME" "TP_PVDDQ_ABC_BTSEN"
					( Origin gPackager )
				)
				( objectStatus "TP_PVDDQ_ABC_BTSEN" )
			)
			( signal "@baseboard_fab2_lib.baseboard_fab2(sch_1):tp_pvddq_abc_bvref"
				( attribute "CDS_PHYS_NET_NAME" "TP_PVDDQ_ABC_BVREF"
					( Origin gPackager )
				)
				( objectStatus "TP_PVDDQ_ABC_BVREF" )
			)
			( signal "@baseboard_fab2_lib.baseboard_fab2(sch_1):tp_pvddq_abc_bvsen"
				( attribute "CDS_PHYS_NET_NAME" "TP_PVDDQ_ABC_BVSEN"
					( Origin gPackager )
				)
				( objectStatus "TP_PVDDQ_ABC_BVSEN" )
			)
			( signal "@baseboard_fab2_lib.baseboard_fab2(sch_1):tp_pvddq_abc_mp1"
				( attribute "CDS_PHYS_NET_NAME" "TP_PVDDQ_ABC_MP1"
					( Origin gPackager )
				)
				( objectStatus "TP_PVDDQ_ABC_MP1" )
			)
			( signal "@baseboard_fab2_lib.baseboard_fab2(sch_1):tp_pvddq_abc_mp2"
				( attribute "CDS_PHYS_NET_NAME" "TP_PVDDQ_ABC_MP2"
					( Origin gPackager )
				)
				( objectStatus "TP_PVDDQ_ABC_MP2" )
			)
			( signal "@baseboard_fab2_lib.baseboard_fab2(sch_1):tp_pvddq_abc_ph3_imon"
				( attribute "CDS_PHYS_NET_NAME" "TP_PVDDQ_ABC_PH3_IMON"
					( Origin gPackager )
				)
				( objectStatus "TP_PVDDQ_ABC_PH3_IMON" )
			)
			( signal "@baseboard_fab2_lib.baseboard_fab2(sch_1):tp_pvddq_abc_ph3_imon_ref"
				( attribute "CDS_PHYS_NET_NAME" "TP_PVDDQ_ABC_PH3_IMON_REF"
					( Origin gPackager )
				)
				( objectStatus "TP_PVDDQ_ABC_PH3_IMON_REF" )
			)
			( signal "@baseboard_fab2_lib.baseboard_fab2(sch_1):tp_pvddq_abc_pinalrt_n"
				( attribute "CDS_PHYS_NET_NAME" "TP_PVDDQ_ABC_PINALRT_N"
					( Origin gPackager )
				)
				( objectStatus "TP_PVDDQ_ABC_PINALRT_N" )
			)
			( signal "@baseboard_fab2_lib.baseboard_fab2(sch_1):tp_pvddq_abc_pwm3"
				( attribute "CDS_PHYS_NET_NAME" "TP_PVDDQ_ABC_PWM3"
					( Origin gPackager )
				)
				( objectStatus "TP_PVDDQ_ABC_PWM3" )
			)
			( signal "@baseboard_fab2_lib.baseboard_fab2(sch_1):tp_pvddq_abc_reset_n"
				( attribute "CDS_PHYS_NET_NAME" "TP_PVDDQ_ABC_RESET_N"
					( Origin gPackager )
				)
				( objectStatus "TP_PVDDQ_ABC_RESET_N" )
			)
			( signal "@baseboard_fab2_lib.baseboard_fab2(sch_1):vr_fet_sw_p12v_stby_pvddq_abc"
				( alias ( signalRef "@baseboard_fab2_lib.baseboard_fab2(sch_1):page215_vr_fet_sw_p12v_stby_pvddq_abc") )
				( alias ( signalRef "@baseboard_fab2_lib.baseboard_fab2(sch_1):page216_vr_fet_sw_p12v_stby_pvddq_abc") )
				( alias ( signalRef "@baseboard_fab2_lib.baseboard_fab2(sch_1):page217_vr_fet_sw_p12v_stby_pvddq_abc") )
				( attribute "CDS_PHYS_NET_NAME" "VR_FET_SW_P12V_STBY_PVDDQ_ABC"
					( Origin gPackager )
				)
				( objectStatus "VR_FET_SW_P12V_STBY_PVDDQ_ABC" )
			)
			( signal "@baseboard_fab2_lib.baseboard_fab2(sch_1):page215_vr_fet_sw_p12v_stby_pvddq_abc"
				( objectFlag fObjectAlias )
				( objectStatus "page215_vr_fet_sw_p12v_stby_pvddq_abc" )
			)
			( signal "@baseboard_fab2_lib.baseboard_fab2(sch_1):page216_vr_fet_sw_p12v_stby_pvddq_abc"
				( objectFlag fObjectAlias )
				( objectStatus "page216_vr_fet_sw_p12v_stby_pvddq_abc" )
			)
			( signal "@baseboard_fab2_lib.baseboard_fab2(sch_1):page217_vr_fet_sw_p12v_stby_pvddq_abc"
				( objectFlag fObjectAlias )
				( objectStatus "page217_vr_fet_sw_p12v_stby_pvddq_abc" )
			)
			( signal "@baseboard_fab2_lib.baseboard_fab2(sch_1):vr_pvddq_abc_airef1"
				( attribute "CDS_PHYS_NET_NAME" "VR_PVDDQ_ABC_AIREF1"
					( Origin gPackager )
				)
				( objectStatus "VR_PVDDQ_ABC_AIREF1" )
			)
			( signal "@baseboard_fab2_lib.baseboard_fab2(sch_1):vr_pvddq_abc_airef2"
				( attribute "CDS_PHYS_NET_NAME" "VR_PVDDQ_ABC_AIREF2"
					( Origin gPackager )
				)
				( objectStatus "VR_PVDDQ_ABC_AIREF2" )
			)
			( signal "@baseboard_fab2_lib.baseboard_fab2(sch_1):vr_pvddq_abc_avsp"
				( attribute "CDS_PHYS_NET_NAME" "VR_PVDDQ_ABC_AVSP"
					( Origin gPackager )
				)
				( objectStatus "VR_PVDDQ_ABC_AVSP" )
			)
			( signal "@baseboard_fab2_lib.baseboard_fab2(sch_1):vr_pvddq_abc_pwm1"
				( attribute "CDS_PHYS_NET_NAME" "VR_PVDDQ_ABC_PWM1"
					( Origin gPackager )
				)
				( objectStatus "VR_PVDDQ_ABC_PWM1" )
			)
			( signal "@baseboard_fab2_lib.baseboard_fab2(sch_1):vr_pvddq_abc_pwm2"
				( attribute "CDS_PHYS_NET_NAME" "VR_PVDDQ_ABC_PWM2"
					( Origin gPackager )
				)
				( objectStatus "VR_PVDDQ_ABC_PWM2" )
			)
			( signal "@baseboard_fab2_lib.baseboard_fab2(sch_1):vr_pvddq_abc_vd12"
				( attribute "CDS_PHYS_NET_NAME" "VR_PVDDQ_ABC_VD12"
					( Origin gPackager )
				)
				( objectStatus "VR_PVDDQ_ABC_VD12" )
			)
			( signal "@baseboard_fab2_lib.baseboard_fab2(sch_1):vr_pvddq_abc_vdd"
				( attribute "CDS_PHYS_NET_NAME" "VR_PVDDQ_ABC_VDD"
					( Origin gPackager )
				)
				( objectStatus "VR_PVDDQ_ABC_VDD" )
			)
			( signal "@baseboard_fab2_lib.baseboard_fab2(sch_1):vr_pvddq_abc_vinsen"
				( attribute "CDS_PHYS_NET_NAME" "VR_PVDDQ_ABC_VINSEN"
					( Origin gPackager )
				)
				( objectStatus "VR_PVDDQ_ABC_VINSEN" )
			)
			( signal "@baseboard_fab2_lib.baseboard_fab2(sch_1):vr_pvddq_abc_vren"
				( attribute "CDS_PHYS_NET_NAME" "VR_PVDDQ_ABC_VREN"
					( Origin gPackager )
				)
				( objectStatus "VR_PVDDQ_ABC_VREN" )
			)
			( signal "@baseboard_fab2_lib.baseboard_fab2(sch_1):vr_pvddq_abc_xaddr1"
				( attribute "CDS_PHYS_NET_NAME" "VR_PVDDQ_ABC_XADDR1"
					( Origin gPackager )
				)
				( objectStatus "VR_PVDDQ_ABC_XADDR1" )
			)
			( signal "@baseboard_fab2_lib.baseboard_fab2(sch_1):vr_pvddq_abc_xaddr2"
				( attribute "CDS_PHYS_NET_NAME" "VR_PVDDQ_ABC_XADDR2"
					( Origin gPackager )
				)
				( objectStatus "VR_PVDDQ_ABC_XADDR2" )
			)
			( signal "@baseboard_fab2_lib.baseboard_fab2(sch_1):vsense_pvddq_abc_n"
				( attribute "CDS_PHYS_NET_NAME" "VSENSE_PVDDQ_ABC_N"
					( Origin gPackager )
				)
				( objectStatus "VSENSE_PVDDQ_ABC_N" )
			)
			( signal "@baseboard_fab2_lib.baseboard_fab2(sch_1):vsense_pvddq_abc_p"
				( attribute "CDS_PHYS_NET_NAME" "VSENSE_PVDDQ_ABC_P"
					( Origin gPackager )
				)
				( objectStatus "VSENSE_PVDDQ_ABC_P" )
			)
			( signal "@baseboard_fab2_lib.baseboard_fab2(sch_1):nc_pvddq_abc_ph1_p31"
				( attribute "CDS_PHYS_NET_NAME" "NC_PVDDQ_ABC_PH1_P31"
					( Origin gPackager )
				)
				( objectStatus "NC_PVDDQ_ABC_PH1_P31" )
			)
			( signal "@baseboard_fab2_lib.baseboard_fab2(sch_1):nc_pvddq_abc_ph2_p31"
				( attribute "CDS_PHYS_NET_NAME" "NC_PVDDQ_ABC_PH2_P31"
					( Origin gPackager )
				)
				( objectStatus "NC_PVDDQ_ABC_PH2_P31" )
			)
			( signal "@baseboard_fab2_lib.baseboard_fab2(sch_1):tp_pvddq_abc_ph1_gl_0"
				( attribute "CDS_PHYS_NET_NAME" "TP_PVDDQ_ABC_PH1_GL_0"
					( Origin gPackager )
				)
				( objectStatus "TP_PVDDQ_ABC_PH1_GL_0" )
			)
			( signal "@baseboard_fab2_lib.baseboard_fab2(sch_1):tp_pvddq_abc_ph1_gl_1"
				( attribute "CDS_PHYS_NET_NAME" "TP_PVDDQ_ABC_PH1_GL_1"
					( Origin gPackager )
				)
				( objectStatus "TP_PVDDQ_ABC_PH1_GL_1" )
			)
			( signal "@baseboard_fab2_lib.baseboard_fab2(sch_1):tp_pvddq_abc_ph2_gl_0"
				( attribute "CDS_PHYS_NET_NAME" "TP_PVDDQ_ABC_PH2_GL_0"
					( Origin gPackager )
				)
				( objectStatus "TP_PVDDQ_ABC_PH2_GL_0" )
			)
			( signal "@baseboard_fab2_lib.baseboard_fab2(sch_1):tp_pvddq_abc_ph2_gl_1"
				( attribute "CDS_PHYS_NET_NAME" "TP_PVDDQ_ABC_PH2_GL_1"
					( Origin gPackager )
				)
				( objectStatus "TP_PVDDQ_ABC_PH2_GL_1" )
			)
			( signal "@baseboard_fab2_lib.baseboard_fab2(sch_1):vr_pvddq_abc_ph1_boot"
				( attribute "CDS_PHYS_NET_NAME" "VR_PVDDQ_ABC_PH1_BOOT"
					( Origin gPackager )
				)
				( objectStatus "VR_PVDDQ_ABC_PH1_BOOT" )
			)
			( signal "@baseboard_fab2_lib.baseboard_fab2(sch_1):vr_pvddq_abc_ph1_ocset"
				( alias ( signalRef "@baseboard_fab2_lib.baseboard_fab2(sch_1):page216_vr_pvddq_abc_ph1_ocset") )
				( attribute "VOLTAGE" "3.6"
					( Units "uVoltage" "V" 1.000000)
					( Status sAliasFlattened )
					( Origin gFrontEnd )
				)
				( attribute "CDS_PHYS_NET_NAME" "VR_PVDDQ_ABC_PH1_OCSET"
					( Origin gPackager )
				)
				( objectStatus "VR_PVDDQ_ABC_PH1_OCSET" )
			)
			( signal "@baseboard_fab2_lib.baseboard_fab2(sch_1):page216_vr_pvddq_abc_ph1_ocset"
				( attribute "VOLTAGE" "3.6"
					( Units "uVoltage" "V" 1.000000)
					( Origin gFrontEnd )
				)
				( objectFlag fObjectAlias )
				( objectStatus "page216_vr_pvddq_abc_ph1_ocset" )
			)
			( signal "@baseboard_fab2_lib.baseboard_fab2(sch_1):vr_pvddq_abc_ph1_phase"
				( attribute "CDS_PHYS_NET_NAME" "VR_PVDDQ_ABC_PH1_PHASE"
					( Origin gPackager )
				)
				( objectStatus "VR_PVDDQ_ABC_PH1_PHASE" )
			)
			( signal "@baseboard_fab2_lib.baseboard_fab2(sch_1):vr_pvddq_abc_ph1_sw"
				( attribute "CDS_PHYS_NET_NAME" "VR_PVDDQ_ABC_PH1_SW"
					( Origin gPackager )
				)
				( objectStatus "VR_PVDDQ_ABC_PH1_SW" )
			)
			( signal "@baseboard_fab2_lib.baseboard_fab2(sch_1):vr_pvddq_abc_ph1_vcin"
				( attribute "CDS_PHYS_NET_NAME" "VR_PVDDQ_ABC_PH1_VCIN"
					( Origin gPackager )
				)
				( objectStatus "VR_PVDDQ_ABC_PH1_VCIN" )
			)
			( signal "@baseboard_fab2_lib.baseboard_fab2(sch_1):vr_pvddq_abc_ph2_boot"
				( attribute "CDS_PHYS_NET_NAME" "VR_PVDDQ_ABC_PH2_BOOT"
					( Origin gPackager )
				)
				( objectStatus "VR_PVDDQ_ABC_PH2_BOOT" )
			)
			( signal "@baseboard_fab2_lib.baseboard_fab2(sch_1):vr_pvddq_abc_ph2_ocset"
				( alias ( signalRef "@baseboard_fab2_lib.baseboard_fab2(sch_1):page216_vr_pvddq_abc_ph2_ocset") )
				( attribute "VOLTAGE" "3.6"
					( Units "uVoltage" "V" 1.000000)
					( Status sAliasFlattened )
					( Origin gFrontEnd )
				)
				( attribute "CDS_PHYS_NET_NAME" "VR_PVDDQ_ABC_PH2_OCSET"
					( Origin gPackager )
				)
				( objectStatus "VR_PVDDQ_ABC_PH2_OCSET" )
			)
			( signal "@baseboard_fab2_lib.baseboard_fab2(sch_1):page216_vr_pvddq_abc_ph2_ocset"
				( attribute "VOLTAGE" "3.6"
					( Units "uVoltage" "V" 1.000000)
					( Origin gFrontEnd )
				)
				( objectFlag fObjectAlias )
				( objectStatus "page216_vr_pvddq_abc_ph2_ocset" )
			)
			( signal "@baseboard_fab2_lib.baseboard_fab2(sch_1):vr_pvddq_abc_ph2_phase"
				( attribute "CDS_PHYS_NET_NAME" "VR_PVDDQ_ABC_PH2_PHASE"
					( Origin gPackager )
				)
				( objectStatus "VR_PVDDQ_ABC_PH2_PHASE" )
			)
			( signal "@baseboard_fab2_lib.baseboard_fab2(sch_1):vr_pvddq_abc_ph2_sw"
				( attribute "CDS_PHYS_NET_NAME" "VR_PVDDQ_ABC_PH2_SW"
					( Origin gPackager )
				)
				( objectStatus "VR_PVDDQ_ABC_PH2_SW" )
			)
			( signal "@baseboard_fab2_lib.baseboard_fab2(sch_1):vr_pvddq_abc_ph2_vcin"
				( attribute "CDS_PHYS_NET_NAME" "VR_PVDDQ_ABC_PH2_VCIN"
					( Origin gPackager )
				)
				( objectStatus "VR_PVDDQ_ABC_PH2_VCIN" )
			)
			( signal "@baseboard_fab2_lib.baseboard_fab2(sch_1):a_tsense_pvddq_def"
				( attribute "CDS_PHYS_NET_NAME" "A_TSENSE_PVDDQ_DEF"
					( Origin gPackager )
				)
				( objectStatus "A_TSENSE_PVDDQ_DEF" )
			)
			( signal "@baseboard_fab2_lib.baseboard_fab2(sch_1):irq_pvddq_def_vrhot_lvt3_r_n"
				( attribute "CDS_PHYS_NET_NAME" "IRQ_PVDDQ_DEF_VRHOT_LVT3_R_N"
					( Origin gPackager )
				)
				( objectStatus "IRQ_PVDDQ_DEF_VRHOT_LVT3_R_N" )
			)
			( signal "@baseboard_fab2_lib.baseboard_fab2(sch_1):isense_pvddq_def_ph1_imon"
				( attribute "CDS_PHYS_NET_NAME" "ISENSE_PVDDQ_DEF_PH1_IMON"
					( Origin gPackager )
				)
				( objectStatus "ISENSE_PVDDQ_DEF_PH1_IMON" )
			)
			( signal "@baseboard_fab2_lib.baseboard_fab2(sch_1):isense_pvddq_def_ph2_imon"
				( attribute "CDS_PHYS_NET_NAME" "ISENSE_PVDDQ_DEF_PH2_IMON"
					( Origin gPackager )
				)
				( objectStatus "ISENSE_PVDDQ_DEF_PH2_IMON" )
			)
			( signal "@baseboard_fab2_lib.baseboard_fab2(sch_1):nc_pvddq_def_dnc0"
				( attribute "CDS_PHYS_NET_NAME" "NC_PVDDQ_DEF_DNC0"
					( Origin gPackager )
				)
				( objectStatus "NC_PVDDQ_DEF_DNC0" )
			)
			( signal "@baseboard_fab2_lib.baseboard_fab2(sch_1):nc_pvddq_def_dnc1"
				( attribute "CDS_PHYS_NET_NAME" "NC_PVDDQ_DEF_DNC1"
					( Origin gPackager )
				)
				( objectStatus "NC_PVDDQ_DEF_DNC1" )
			)
			( signal "@baseboard_fab2_lib.baseboard_fab2(sch_1):pu_vr_pvddq_def_fault1"
				( attribute "CDS_PHYS_NET_NAME" "PU_VR_PVDDQ_DEF_FAULT1"
					( Origin gPackager )
				)
				( objectStatus "PU_VR_PVDDQ_DEF_FAULT1" )
			)
			( signal "@baseboard_fab2_lib.baseboard_fab2(sch_1):pwrgd_pvddq_def"
				( attribute "CDS_PHYS_NET_NAME" "PWRGD_PVDDQ_DEF"
					( Origin gPackager )
				)
				( objectStatus "PWRGD_PVDDQ_DEF" )
			)
			( signal "@baseboard_fab2_lib.baseboard_fab2(sch_1):pwrgd_pvddq_def_r"
				( attribute "CDS_PHYS_NET_NAME" "PWRGD_PVDDQ_DEF_R"
					( Origin gPackager )
				)
				( objectStatus "PWRGD_PVDDQ_DEF_R" )
			)
			( signal "@baseboard_fab2_lib.baseboard_fab2(sch_1):smb_vr_scl_vddq_def"
				( attribute "CDS_PHYS_NET_NAME" "SMB_VR_SCL_VDDQ_DEF"
					( Origin gPackager )
				)
				( objectStatus "SMB_VR_SCL_VDDQ_DEF" )
			)
			( signal "@baseboard_fab2_lib.baseboard_fab2(sch_1):smb_vr_sda_vddq_def"
				( attribute "CDS_PHYS_NET_NAME" "SMB_VR_SDA_VDDQ_DEF"
					( Origin gPackager )
				)
				( objectStatus "SMB_VR_SDA_VDDQ_DEF" )
			)
			( signal "@baseboard_fab2_lib.baseboard_fab2(sch_1):svid_alert_pvddq_def"
				( attribute "CDS_PHYS_NET_NAME" "SVID_ALERT_PVDDQ_DEF"
					( Origin gPackager )
				)
				( objectStatus "SVID_ALERT_PVDDQ_DEF" )
			)
			( signal "@baseboard_fab2_lib.baseboard_fab2(sch_1):svid_clk_pvddq_def"
				( attribute "CDS_PHYS_NET_NAME" "SVID_CLK_PVDDQ_DEF"
					( Origin gPackager )
				)
				( objectStatus "SVID_CLK_PVDDQ_DEF" )
			)
			( signal "@baseboard_fab2_lib.baseboard_fab2(sch_1):svid_vdio_pvddq_def"
				( attribute "CDS_PHYS_NET_NAME" "SVID_VDIO_PVDDQ_DEF"
					( Origin gPackager )
				)
				( objectStatus "SVID_VDIO_PVDDQ_DEF" )
			)
			( signal "@baseboard_fab2_lib.baseboard_fab2(sch_1):tp_pvddq_def_bpwm1"
				( attribute "CDS_PHYS_NET_NAME" "TP_PVDDQ_DEF_BPWM1"
					( Origin gPackager )
				)
				( objectStatus "TP_PVDDQ_DEF_BPWM1" )
			)
			( signal "@baseboard_fab2_lib.baseboard_fab2(sch_1):tp_pvddq_def_bref1"
				( attribute "CDS_PHYS_NET_NAME" "TP_PVDDQ_DEF_BREF1"
					( Origin gPackager )
				)
				( objectStatus "TP_PVDDQ_DEF_BREF1" )
			)
			( signal "@baseboard_fab2_lib.baseboard_fab2(sch_1):tp_pvddq_def_btsen"
				( attribute "CDS_PHYS_NET_NAME" "TP_PVDDQ_DEF_BTSEN"
					( Origin gPackager )
				)
				( objectStatus "TP_PVDDQ_DEF_BTSEN" )
			)
			( signal "@baseboard_fab2_lib.baseboard_fab2(sch_1):tp_pvddq_def_bvref"
				( attribute "CDS_PHYS_NET_NAME" "TP_PVDDQ_DEF_BVREF"
					( Origin gPackager )
				)
				( objectStatus "TP_PVDDQ_DEF_BVREF" )
			)
			( signal "@baseboard_fab2_lib.baseboard_fab2(sch_1):tp_pvddq_def_bvsen"
				( attribute "CDS_PHYS_NET_NAME" "TP_PVDDQ_DEF_BVSEN"
					( Origin gPackager )
				)
				( objectStatus "TP_PVDDQ_DEF_BVSEN" )
			)
			( signal "@baseboard_fab2_lib.baseboard_fab2(sch_1):tp_pvddq_def_mp1"
				( attribute "CDS_PHYS_NET_NAME" "TP_PVDDQ_DEF_MP1"
					( Origin gPackager )
				)
				( objectStatus "TP_PVDDQ_DEF_MP1" )
			)
			( signal "@baseboard_fab2_lib.baseboard_fab2(sch_1):tp_pvddq_def_mp2"
				( attribute "CDS_PHYS_NET_NAME" "TP_PVDDQ_DEF_MP2"
					( Origin gPackager )
				)
				( objectStatus "TP_PVDDQ_DEF_MP2" )
			)
			( signal "@baseboard_fab2_lib.baseboard_fab2(sch_1):tp_pvddq_def_ph3_imon"
				( attribute "CDS_PHYS_NET_NAME" "TP_PVDDQ_DEF_PH3_IMON"
					( Origin gPackager )
				)
				( objectStatus "TP_PVDDQ_DEF_PH3_IMON" )
			)
			( signal "@baseboard_fab2_lib.baseboard_fab2(sch_1):tp_pvddq_def_ph3_imon_ref"
				( attribute "CDS_PHYS_NET_NAME" "TP_PVDDQ_DEF_PH3_IMON_REF"
					( Origin gPackager )
				)
				( objectStatus "TP_PVDDQ_DEF_PH3_IMON_REF" )
			)
			( signal "@baseboard_fab2_lib.baseboard_fab2(sch_1):tp_pvddq_def_pinalrt_n"
				( attribute "CDS_PHYS_NET_NAME" "TP_PVDDQ_DEF_PINALRT_N"
					( Origin gPackager )
				)
				( objectStatus "TP_PVDDQ_DEF_PINALRT_N" )
			)
			( signal "@baseboard_fab2_lib.baseboard_fab2(sch_1):tp_pvddq_def_pwm3"
				( attribute "CDS_PHYS_NET_NAME" "TP_PVDDQ_DEF_PWM3"
					( Origin gPackager )
				)
				( objectStatus "TP_PVDDQ_DEF_PWM3" )
			)
			( signal "@baseboard_fab2_lib.baseboard_fab2(sch_1):tp_pvddq_def_reset_n"
				( attribute "CDS_PHYS_NET_NAME" "TP_PVDDQ_DEF_RESET_N"
					( Origin gPackager )
				)
				( objectStatus "TP_PVDDQ_DEF_RESET_N" )
			)
			( signal "@baseboard_fab2_lib.baseboard_fab2(sch_1):vr_fet_sw_p12v_stby_pvddq_def"
				( alias ( signalRef "@baseboard_fab2_lib.baseboard_fab2(sch_1):page218_vr_fet_sw_p12v_stby_pvddq_def") )
				( alias ( signalRef "@baseboard_fab2_lib.baseboard_fab2(sch_1):page219_vr_fet_sw_p12v_stby_pvddq_def") )
				( alias ( signalRef "@baseboard_fab2_lib.baseboard_fab2(sch_1):page220_vr_fet_sw_p12v_stby_pvddq_def") )
				( alias ( signalRef "@baseboard_fab2_lib.baseboard_fab2(sch_1):page235_vr_fet_sw_p12v_stby_pvddq_def") )
				( alias ( signalRef "@baseboard_fab2_lib.baseboard_fab2(sch_1):page236_vr_fet_sw_p12v_stby_pvddq_def") )
				( attribute "CDS_PHYS_NET_NAME" "VR_FET_SW_P12V_STBY_PVDDQ_DEF"
					( Origin gPackager )
				)
				( objectStatus "VR_FET_SW_P12V_STBY_PVDDQ_DEF" )
			)
			( signal "@baseboard_fab2_lib.baseboard_fab2(sch_1):page218_vr_fet_sw_p12v_stby_pvddq_def"
				( objectFlag fObjectAlias )
				( objectStatus "page218_vr_fet_sw_p12v_stby_pvddq_def" )
			)
			( signal "@baseboard_fab2_lib.baseboard_fab2(sch_1):page219_vr_fet_sw_p12v_stby_pvddq_def"
				( objectFlag fObjectAlias )
				( objectStatus "page219_vr_fet_sw_p12v_stby_pvddq_def" )
			)
			( signal "@baseboard_fab2_lib.baseboard_fab2(sch_1):page220_vr_fet_sw_p12v_stby_pvddq_def"
				( objectFlag fObjectAlias )
				( objectStatus "page220_vr_fet_sw_p12v_stby_pvddq_def" )
			)
			( signal "@baseboard_fab2_lib.baseboard_fab2(sch_1):page235_vr_fet_sw_p12v_stby_pvddq_def"
				( objectFlag fObjectAlias )
				( objectStatus "page235_vr_fet_sw_p12v_stby_pvddq_def" )
			)
			( signal "@baseboard_fab2_lib.baseboard_fab2(sch_1):page236_vr_fet_sw_p12v_stby_pvddq_def"
				( objectFlag fObjectAlias )
				( objectStatus "page236_vr_fet_sw_p12v_stby_pvddq_def" )
			)
			( signal "@baseboard_fab2_lib.baseboard_fab2(sch_1):vr_pvddq_def_airef1"
				( attribute "CDS_PHYS_NET_NAME" "VR_PVDDQ_DEF_AIREF1"
					( Origin gPackager )
				)
				( objectStatus "VR_PVDDQ_DEF_AIREF1" )
			)
			( signal "@baseboard_fab2_lib.baseboard_fab2(sch_1):vr_pvddq_def_airef2"
				( attribute "CDS_PHYS_NET_NAME" "VR_PVDDQ_DEF_AIREF2"
					( Origin gPackager )
				)
				( objectStatus "VR_PVDDQ_DEF_AIREF2" )
			)
			( signal "@baseboard_fab2_lib.baseboard_fab2(sch_1):vr_pvddq_def_avsp"
				( attribute "CDS_PHYS_NET_NAME" "VR_PVDDQ_DEF_AVSP"
					( Origin gPackager )
				)
				( objectStatus "VR_PVDDQ_DEF_AVSP" )
			)
			( signal "@baseboard_fab2_lib.baseboard_fab2(sch_1):vr_pvddq_def_pwm1"
				( attribute "CDS_PHYS_NET_NAME" "VR_PVDDQ_DEF_PWM1"
					( Origin gPackager )
				)
				( objectStatus "VR_PVDDQ_DEF_PWM1" )
			)
			( signal "@baseboard_fab2_lib.baseboard_fab2(sch_1):vr_pvddq_def_pwm2"
				( attribute "CDS_PHYS_NET_NAME" "VR_PVDDQ_DEF_PWM2"
					( Origin gPackager )
				)
				( objectStatus "VR_PVDDQ_DEF_PWM2" )
			)
			( signal "@baseboard_fab2_lib.baseboard_fab2(sch_1):vr_pvddq_def_vd12"
				( attribute "CDS_PHYS_NET_NAME" "VR_PVDDQ_DEF_VD12"
					( Origin gPackager )
				)
				( objectStatus "VR_PVDDQ_DEF_VD12" )
			)
			( signal "@baseboard_fab2_lib.baseboard_fab2(sch_1):vr_pvddq_def_vdd"
				( attribute "CDS_PHYS_NET_NAME" "VR_PVDDQ_DEF_VDD"
					( Origin gPackager )
				)
				( objectStatus "VR_PVDDQ_DEF_VDD" )
			)
			( signal "@baseboard_fab2_lib.baseboard_fab2(sch_1):vr_pvddq_def_vinsen"
				( attribute "CDS_PHYS_NET_NAME" "VR_PVDDQ_DEF_VINSEN"
					( Origin gPackager )
				)
				( objectStatus "VR_PVDDQ_DEF_VINSEN" )
			)
			( signal "@baseboard_fab2_lib.baseboard_fab2(sch_1):vr_pvddq_def_vren"
				( attribute "CDS_PHYS_NET_NAME" "VR_PVDDQ_DEF_VREN"
					( Origin gPackager )
				)
				( objectStatus "VR_PVDDQ_DEF_VREN" )
			)
			( signal "@baseboard_fab2_lib.baseboard_fab2(sch_1):vr_pvddq_def_xaddr1"
				( attribute "CDS_PHYS_NET_NAME" "VR_PVDDQ_DEF_XADDR1"
					( Origin gPackager )
				)
				( objectStatus "VR_PVDDQ_DEF_XADDR1" )
			)
			( signal "@baseboard_fab2_lib.baseboard_fab2(sch_1):vr_pvddq_def_xaddr2"
				( attribute "CDS_PHYS_NET_NAME" "VR_PVDDQ_DEF_XADDR2"
					( Origin gPackager )
				)
				( objectStatus "VR_PVDDQ_DEF_XADDR2" )
			)
			( signal "@baseboard_fab2_lib.baseboard_fab2(sch_1):vsense_pvddq_def_n"
				( attribute "CDS_PHYS_NET_NAME" "VSENSE_PVDDQ_DEF_N"
					( Origin gPackager )
				)
				( objectStatus "VSENSE_PVDDQ_DEF_N" )
			)
			( signal "@baseboard_fab2_lib.baseboard_fab2(sch_1):vsense_pvddq_def_p"
				( attribute "CDS_PHYS_NET_NAME" "VSENSE_PVDDQ_DEF_P"
					( Origin gPackager )
				)
				( objectStatus "VSENSE_PVDDQ_DEF_P" )
			)
			( signal "@baseboard_fab2_lib.baseboard_fab2(sch_1):nc_pvddq_def_ph1_p31"
				( attribute "CDS_PHYS_NET_NAME" "NC_PVDDQ_DEF_PH1_P31"
					( Origin gPackager )
				)
				( objectStatus "NC_PVDDQ_DEF_PH1_P31" )
			)
			( signal "@baseboard_fab2_lib.baseboard_fab2(sch_1):nc_pvddq_def_ph2_p31"
				( attribute "CDS_PHYS_NET_NAME" "NC_PVDDQ_DEF_PH2_P31"
					( Origin gPackager )
				)
				( objectStatus "NC_PVDDQ_DEF_PH2_P31" )
			)
			( signal "@baseboard_fab2_lib.baseboard_fab2(sch_1):tp_pvddq_def_ph1_gl_0"
				( attribute "CDS_PHYS_NET_NAME" "TP_PVDDQ_DEF_PH1_GL_0"
					( Origin gPackager )
				)
				( objectStatus "TP_PVDDQ_DEF_PH1_GL_0" )
			)
			( signal "@baseboard_fab2_lib.baseboard_fab2(sch_1):tp_pvddq_def_ph1_gl_1"
				( attribute "CDS_PHYS_NET_NAME" "TP_PVDDQ_DEF_PH1_GL_1"
					( Origin gPackager )
				)
				( objectStatus "TP_PVDDQ_DEF_PH1_GL_1" )
			)
			( signal "@baseboard_fab2_lib.baseboard_fab2(sch_1):tp_pvddq_def_ph2_gl_0"
				( attribute "CDS_PHYS_NET_NAME" "TP_PVDDQ_DEF_PH2_GL_0"
					( Origin gPackager )
				)
				( objectStatus "TP_PVDDQ_DEF_PH2_GL_0" )
			)
			( signal "@baseboard_fab2_lib.baseboard_fab2(sch_1):tp_pvddq_def_ph2_gl_1"
				( attribute "CDS_PHYS_NET_NAME" "TP_PVDDQ_DEF_PH2_GL_1"
					( Origin gPackager )
				)
				( objectStatus "TP_PVDDQ_DEF_PH2_GL_1" )
			)
			( signal "@baseboard_fab2_lib.baseboard_fab2(sch_1):vr_pvddq_def_ph1_boot"
				( attribute "CDS_PHYS_NET_NAME" "VR_PVDDQ_DEF_PH1_BOOT"
					( Origin gPackager )
				)
				( objectStatus "VR_PVDDQ_DEF_PH1_BOOT" )
			)
			( signal "@baseboard_fab2_lib.baseboard_fab2(sch_1):vr_pvddq_def_ph1_ocset"
				( alias ( signalRef "@baseboard_fab2_lib.baseboard_fab2(sch_1):page219_vr_pvddq_def_ph1_ocset") )
				( attribute "VOLTAGE" "3.6"
					( Units "uVoltage" "V" 1.000000)
					( Status sAliasFlattened )
					( Origin gFrontEnd )
				)
				( attribute "CDS_PHYS_NET_NAME" "VR_PVDDQ_DEF_PH1_OCSET"
					( Origin gPackager )
				)
				( objectStatus "VR_PVDDQ_DEF_PH1_OCSET" )
			)
			( signal "@baseboard_fab2_lib.baseboard_fab2(sch_1):page219_vr_pvddq_def_ph1_ocset"
				( attribute "VOLTAGE" "3.6"
					( Units "uVoltage" "V" 1.000000)
					( Origin gFrontEnd )
				)
				( objectFlag fObjectAlias )
				( objectStatus "page219_vr_pvddq_def_ph1_ocset" )
			)
			( signal "@baseboard_fab2_lib.baseboard_fab2(sch_1):vr_pvddq_def_ph1_phase"
				( attribute "CDS_PHYS_NET_NAME" "VR_PVDDQ_DEF_PH1_PHASE"
					( Origin gPackager )
				)
				( objectStatus "VR_PVDDQ_DEF_PH1_PHASE" )
			)
			( signal "@baseboard_fab2_lib.baseboard_fab2(sch_1):vr_pvddq_def_ph1_sw"
				( attribute "CDS_PHYS_NET_NAME" "VR_PVDDQ_DEF_PH1_SW"
					( Origin gPackager )
				)
				( objectStatus "VR_PVDDQ_DEF_PH1_SW" )
			)
			( signal "@baseboard_fab2_lib.baseboard_fab2(sch_1):vr_pvddq_def_ph1_vcin"
				( attribute "CDS_PHYS_NET_NAME" "VR_PVDDQ_DEF_PH1_VCIN"
					( Origin gPackager )
				)
				( objectStatus "VR_PVDDQ_DEF_PH1_VCIN" )
			)
			( signal "@baseboard_fab2_lib.baseboard_fab2(sch_1):vr_pvddq_def_ph2_boot"
				( attribute "CDS_PHYS_NET_NAME" "VR_PVDDQ_DEF_PH2_BOOT"
					( Origin gPackager )
				)
				( objectStatus "VR_PVDDQ_DEF_PH2_BOOT" )
			)
			( signal "@baseboard_fab2_lib.baseboard_fab2(sch_1):vr_pvddq_def_ph2_ocset"
				( alias ( signalRef "@baseboard_fab2_lib.baseboard_fab2(sch_1):page219_vr_pvddq_def_ph2_ocset") )
				( attribute "VOLTAGE" "3.6"
					( Units "uVoltage" "V" 1.000000)
					( Status sAliasFlattened )
					( Origin gFrontEnd )
				)
				( attribute "CDS_PHYS_NET_NAME" "VR_PVDDQ_DEF_PH2_OCSET"
					( Origin gPackager )
				)
				( objectStatus "VR_PVDDQ_DEF_PH2_OCSET" )
			)
			( signal "@baseboard_fab2_lib.baseboard_fab2(sch_1):page219_vr_pvddq_def_ph2_ocset"
				( attribute "VOLTAGE" "3.6"
					( Units "uVoltage" "V" 1.000000)
					( Origin gFrontEnd )
				)
				( objectFlag fObjectAlias )
				( objectStatus "page219_vr_pvddq_def_ph2_ocset" )
			)
			( signal "@baseboard_fab2_lib.baseboard_fab2(sch_1):vr_pvddq_def_ph2_phase"
				( attribute "CDS_PHYS_NET_NAME" "VR_PVDDQ_DEF_PH2_PHASE"
					( Origin gPackager )
				)
				( objectStatus "VR_PVDDQ_DEF_PH2_PHASE" )
			)
			( signal "@baseboard_fab2_lib.baseboard_fab2(sch_1):vr_pvddq_def_ph2_sw"
				( attribute "CDS_PHYS_NET_NAME" "VR_PVDDQ_DEF_PH2_SW"
					( Origin gPackager )
				)
				( objectStatus "VR_PVDDQ_DEF_PH2_SW" )
			)
			( signal "@baseboard_fab2_lib.baseboard_fab2(sch_1):vr_pvddq_def_ph2_vcin"
				( attribute "CDS_PHYS_NET_NAME" "VR_PVDDQ_DEF_PH2_VCIN"
					( Origin gPackager )
				)
				( objectStatus "VR_PVDDQ_DEF_PH2_VCIN" )
			)
			( signal "@baseboard_fab2_lib.baseboard_fab2(sch_1):fm_pvtt_abc_en_r"
				( attribute "CDS_PHYS_NET_NAME" "FM_PVTT_ABC_EN_R"
					( Origin gPackager )
				)
				( objectStatus "FM_PVTT_ABC_EN_R" )
			)
			( signal "@baseboard_fab2_lib.baseboard_fab2(sch_1):pwrgd_pvtt_abc_cpu0_r"
				( attribute "CDS_PHYS_NET_NAME" "PWRGD_PVTT_ABC_CPU0_R"
					( Origin gPackager )
				)
				( objectStatus "PWRGD_PVTT_ABC_CPU0_R" )
			)
			( signal "@baseboard_fab2_lib.baseboard_fab2(sch_1):vr_pvtt_abc_bias"
				( attribute "CDS_PHYS_NET_NAME" "VR_PVTT_ABC_BIAS"
					( Origin gPackager )
				)
				( objectStatus "VR_PVTT_ABC_BIAS" )
			)
			( signal "@baseboard_fab2_lib.baseboard_fab2(sch_1):vr_pvtt_abc_sns"
				( attribute "CDS_PHYS_NET_NAME" "VR_PVTT_ABC_SNS"
					( Origin gPackager )
				)
				( objectStatus "VR_PVTT_ABC_SNS" )
			)
			( signal "@baseboard_fab2_lib.baseboard_fab2(sch_1):vr_pvtt_abc_vref"
				( attribute "CDS_PHYS_NET_NAME" "VR_PVTT_ABC_VREF"
					( Origin gPackager )
				)
				( objectStatus "VR_PVTT_ABC_VREF" )
			)
			( signal "@baseboard_fab2_lib.baseboard_fab2(sch_1):vsense_pvddq_abc_vtt"
				( attribute "CDS_PHYS_NET_NAME" "VSENSE_PVDDQ_ABC_VTT"
					( Origin gPackager )
				)
				( objectStatus "VSENSE_PVDDQ_ABC_VTT" )
			)
			( signal "@baseboard_fab2_lib.baseboard_fab2(sch_1):fm_pvtt_def_en_r"
				( attribute "CDS_PHYS_NET_NAME" "FM_PVTT_DEF_EN_R"
					( Origin gPackager )
				)
				( objectStatus "FM_PVTT_DEF_EN_R" )
			)
			( signal "@baseboard_fab2_lib.baseboard_fab2(sch_1):pwrgd_pvtt_def_cpu0_r"
				( attribute "CDS_PHYS_NET_NAME" "PWRGD_PVTT_DEF_CPU0_R"
					( Origin gPackager )
				)
				( objectStatus "PWRGD_PVTT_DEF_CPU0_R" )
			)
			( signal "@baseboard_fab2_lib.baseboard_fab2(sch_1):vr_pvtt_def_bias"
				( attribute "CDS_PHYS_NET_NAME" "VR_PVTT_DEF_BIAS"
					( Origin gPackager )
				)
				( objectStatus "VR_PVTT_DEF_BIAS" )
			)
			( signal "@baseboard_fab2_lib.baseboard_fab2(sch_1):vr_pvtt_def_sns"
				( attribute "CDS_PHYS_NET_NAME" "VR_PVTT_DEF_SNS"
					( Origin gPackager )
				)
				( objectStatus "VR_PVTT_DEF_SNS" )
			)
			( signal "@baseboard_fab2_lib.baseboard_fab2(sch_1):vr_pvtt_def_vref"
				( attribute "CDS_PHYS_NET_NAME" "VR_PVTT_DEF_VREF"
					( Origin gPackager )
				)
				( objectStatus "VR_PVTT_DEF_VREF" )
			)
			( signal "@baseboard_fab2_lib.baseboard_fab2(sch_1):vsense_pvddq_def_vtt"
				( attribute "CDS_PHYS_NET_NAME" "VSENSE_PVDDQ_DEF_VTT"
					( Origin gPackager )
				)
				( objectStatus "VSENSE_PVDDQ_DEF_VTT" )
			)
			( signal "@baseboard_fab2_lib.baseboard_fab2(sch_1):a_tsense_pvddq_ghj"
				( attribute "CDS_PHYS_NET_NAME" "A_TSENSE_PVDDQ_GHJ"
					( Origin gPackager )
				)
				( objectStatus "A_TSENSE_PVDDQ_GHJ" )
			)
			( signal "@baseboard_fab2_lib.baseboard_fab2(sch_1):irq_pvddq_ghj_vrhot_lvt3_r_n"
				( attribute "CDS_PHYS_NET_NAME" "IRQ_PVDDQ_GHJ_VRHOT_LVT3_R_N"
					( Origin gPackager )
				)
				( objectStatus "IRQ_PVDDQ_GHJ_VRHOT_LVT3_R_N" )
			)
			( signal "@baseboard_fab2_lib.baseboard_fab2(sch_1):isense_pvddq_ghj_ph1_imon"
				( attribute "CDS_PHYS_NET_NAME" "ISENSE_PVDDQ_GHJ_PH1_IMON"
					( Origin gPackager )
				)
				( objectStatus "ISENSE_PVDDQ_GHJ_PH1_IMON" )
			)
			( signal "@baseboard_fab2_lib.baseboard_fab2(sch_1):isense_pvddq_ghj_ph2_imon"
				( attribute "CDS_PHYS_NET_NAME" "ISENSE_PVDDQ_GHJ_PH2_IMON"
					( Origin gPackager )
				)
				( objectStatus "ISENSE_PVDDQ_GHJ_PH2_IMON" )
			)
			( signal "@baseboard_fab2_lib.baseboard_fab2(sch_1):nc_pvddq_ghj_dnc0"
				( attribute "CDS_PHYS_NET_NAME" "NC_PVDDQ_GHJ_DNC0"
					( Origin gPackager )
				)
				( objectStatus "NC_PVDDQ_GHJ_DNC0" )
			)
			( signal "@baseboard_fab2_lib.baseboard_fab2(sch_1):nc_pvddq_ghj_dnc1"
				( attribute "CDS_PHYS_NET_NAME" "NC_PVDDQ_GHJ_DNC1"
					( Origin gPackager )
				)
				( objectStatus "NC_PVDDQ_GHJ_DNC1" )
			)
			( signal "@baseboard_fab2_lib.baseboard_fab2(sch_1):nc_pvddq_ghj_pinalrt_n"
				( attribute "CDS_PHYS_NET_NAME" "NC_PVDDQ_GHJ_PINALRT_N"
					( Origin gPackager )
				)
				( objectStatus "NC_PVDDQ_GHJ_PINALRT_N" )
			)
			( signal "@baseboard_fab2_lib.baseboard_fab2(sch_1):pu_vr_pvddq_ghj_fault1"
				( attribute "CDS_PHYS_NET_NAME" "PU_VR_PVDDQ_GHJ_FAULT1"
					( Origin gPackager )
				)
				( objectStatus "PU_VR_PVDDQ_GHJ_FAULT1" )
			)
			( signal "@baseboard_fab2_lib.baseboard_fab2(sch_1):pwrgd_pvddq_ghj"
				( attribute "CDS_PHYS_NET_NAME" "PWRGD_PVDDQ_GHJ"
					( Origin gPackager )
				)
				( objectStatus "PWRGD_PVDDQ_GHJ" )
			)
			( signal "@baseboard_fab2_lib.baseboard_fab2(sch_1):pwrgd_pvddq_ghj_r"
				( attribute "CDS_PHYS_NET_NAME" "PWRGD_PVDDQ_GHJ_R"
					( Origin gPackager )
				)
				( objectStatus "PWRGD_PVDDQ_GHJ_R" )
			)
			( signal "@baseboard_fab2_lib.baseboard_fab2(sch_1):smb_vr_scl_vddq_ghj"
				( attribute "CDS_PHYS_NET_NAME" "SMB_VR_SCL_VDDQ_GHJ"
					( Origin gPackager )
				)
				( objectStatus "SMB_VR_SCL_VDDQ_GHJ" )
			)
			( signal "@baseboard_fab2_lib.baseboard_fab2(sch_1):smb_vr_sda_vddq_ghj"
				( attribute "CDS_PHYS_NET_NAME" "SMB_VR_SDA_VDDQ_GHJ"
					( Origin gPackager )
				)
				( objectStatus "SMB_VR_SDA_VDDQ_GHJ" )
			)
			( signal "@baseboard_fab2_lib.baseboard_fab2(sch_1):svid_alert_pvddq_ghj"
				( attribute "CDS_PHYS_NET_NAME" "SVID_ALERT_PVDDQ_GHJ"
					( Origin gPackager )
				)
				( objectStatus "SVID_ALERT_PVDDQ_GHJ" )
			)
			( signal "@baseboard_fab2_lib.baseboard_fab2(sch_1):svid_clk_pvddq_ghj"
				( attribute "CDS_PHYS_NET_NAME" "SVID_CLK_PVDDQ_GHJ"
					( Origin gPackager )
				)
				( objectStatus "SVID_CLK_PVDDQ_GHJ" )
			)
			( signal "@baseboard_fab2_lib.baseboard_fab2(sch_1):svid_vdio_pvddq_ghj"
				( attribute "CDS_PHYS_NET_NAME" "SVID_VDIO_PVDDQ_GHJ"
					( Origin gPackager )
				)
				( objectStatus "SVID_VDIO_PVDDQ_GHJ" )
			)
			( signal "@baseboard_fab2_lib.baseboard_fab2(sch_1):tp_pvddq_ghj_bpwm1"
				( attribute "CDS_PHYS_NET_NAME" "TP_PVDDQ_GHJ_BPWM1"
					( Origin gPackager )
				)
				( objectStatus "TP_PVDDQ_GHJ_BPWM1" )
			)
			( signal "@baseboard_fab2_lib.baseboard_fab2(sch_1):tp_pvddq_ghj_bref1"
				( attribute "CDS_PHYS_NET_NAME" "TP_PVDDQ_GHJ_BREF1"
					( Origin gPackager )
				)
				( objectStatus "TP_PVDDQ_GHJ_BREF1" )
			)
			( signal "@baseboard_fab2_lib.baseboard_fab2(sch_1):tp_pvddq_ghj_btsen"
				( attribute "CDS_PHYS_NET_NAME" "TP_PVDDQ_GHJ_BTSEN"
					( Origin gPackager )
				)
				( objectStatus "TP_PVDDQ_GHJ_BTSEN" )
			)
			( signal "@baseboard_fab2_lib.baseboard_fab2(sch_1):tp_pvddq_ghj_bvref"
				( attribute "CDS_PHYS_NET_NAME" "TP_PVDDQ_GHJ_BVREF"
					( Origin gPackager )
				)
				( objectStatus "TP_PVDDQ_GHJ_BVREF" )
			)
			( signal "@baseboard_fab2_lib.baseboard_fab2(sch_1):tp_pvddq_ghj_bvsen"
				( attribute "CDS_PHYS_NET_NAME" "TP_PVDDQ_GHJ_BVSEN"
					( Origin gPackager )
				)
				( objectStatus "TP_PVDDQ_GHJ_BVSEN" )
			)
			( signal "@baseboard_fab2_lib.baseboard_fab2(sch_1):tp_pvddq_ghj_mp1"
				( attribute "CDS_PHYS_NET_NAME" "TP_PVDDQ_GHJ_MP1"
					( Origin gPackager )
				)
				( objectStatus "TP_PVDDQ_GHJ_MP1" )
			)
			( signal "@baseboard_fab2_lib.baseboard_fab2(sch_1):tp_pvddq_ghj_mp2"
				( attribute "CDS_PHYS_NET_NAME" "TP_PVDDQ_GHJ_MP2"
					( Origin gPackager )
				)
				( objectStatus "TP_PVDDQ_GHJ_MP2" )
			)
			( signal "@baseboard_fab2_lib.baseboard_fab2(sch_1):tp_pvddq_ghj_ph3_imon"
				( attribute "CDS_PHYS_NET_NAME" "TP_PVDDQ_GHJ_PH3_IMON"
					( Origin gPackager )
				)
				( objectStatus "TP_PVDDQ_GHJ_PH3_IMON" )
			)
			( signal "@baseboard_fab2_lib.baseboard_fab2(sch_1):tp_pvddq_ghj_ph3_imon_ref"
				( attribute "CDS_PHYS_NET_NAME" "TP_PVDDQ_GHJ_PH3_IMON_REF"
					( Origin gPackager )
				)
				( objectStatus "TP_PVDDQ_GHJ_PH3_IMON_REF" )
			)
			( signal "@baseboard_fab2_lib.baseboard_fab2(sch_1):tp_pvddq_ghj_pwm3"
				( attribute "CDS_PHYS_NET_NAME" "TP_PVDDQ_GHJ_PWM3"
					( Origin gPackager )
				)
				( objectStatus "TP_PVDDQ_GHJ_PWM3" )
			)
			( signal "@baseboard_fab2_lib.baseboard_fab2(sch_1):tp_pvddq_ghj_reset_n"
				( attribute "CDS_PHYS_NET_NAME" "TP_PVDDQ_GHJ_RESET_N"
					( Origin gPackager )
				)
				( objectStatus "TP_PVDDQ_GHJ_RESET_N" )
			)
			( signal "@baseboard_fab2_lib.baseboard_fab2(sch_1):vr_fet_sw_p12v_stby_pvddq_ghj"
				( alias ( signalRef "@baseboard_fab2_lib.baseboard_fab2(sch_1):page223_vr_fet_sw_p12v_stby_pvddq_ghj") )
				( alias ( signalRef "@baseboard_fab2_lib.baseboard_fab2(sch_1):page224_vr_fet_sw_p12v_stby_pvddq_ghj") )
				( alias ( signalRef "@baseboard_fab2_lib.baseboard_fab2(sch_1):page225_vr_fet_sw_p12v_stby_pvddq_ghj") )
				( attribute "CDS_PHYS_NET_NAME" "VR_FET_SW_P12V_STBY_PVDDQ_GHJ"
					( Origin gPackager )
				)
				( objectStatus "VR_FET_SW_P12V_STBY_PVDDQ_GHJ" )
			)
			( signal "@baseboard_fab2_lib.baseboard_fab2(sch_1):page223_vr_fet_sw_p12v_stby_pvddq_ghj"
				( objectFlag fObjectAlias )
				( objectStatus "page223_vr_fet_sw_p12v_stby_pvddq_ghj" )
			)
			( signal "@baseboard_fab2_lib.baseboard_fab2(sch_1):page224_vr_fet_sw_p12v_stby_pvddq_ghj"
				( objectFlag fObjectAlias )
				( objectStatus "page224_vr_fet_sw_p12v_stby_pvddq_ghj" )
			)
			( signal "@baseboard_fab2_lib.baseboard_fab2(sch_1):page225_vr_fet_sw_p12v_stby_pvddq_ghj"
				( objectFlag fObjectAlias )
				( objectStatus "page225_vr_fet_sw_p12v_stby_pvddq_ghj" )
			)
			( signal "@baseboard_fab2_lib.baseboard_fab2(sch_1):vr_pvddq_ghj_airef1"
				( attribute "CDS_PHYS_NET_NAME" "VR_PVDDQ_GHJ_AIREF1"
					( Origin gPackager )
				)
				( objectStatus "VR_PVDDQ_GHJ_AIREF1" )
			)
			( signal "@baseboard_fab2_lib.baseboard_fab2(sch_1):vr_pvddq_ghj_airef2"
				( attribute "CDS_PHYS_NET_NAME" "VR_PVDDQ_GHJ_AIREF2"
					( Origin gPackager )
				)
				( objectStatus "VR_PVDDQ_GHJ_AIREF2" )
			)
			( signal "@baseboard_fab2_lib.baseboard_fab2(sch_1):vr_pvddq_ghj_avsp"
				( attribute "CDS_PHYS_NET_NAME" "VR_PVDDQ_GHJ_AVSP"
					( Origin gPackager )
				)
				( objectStatus "VR_PVDDQ_GHJ_AVSP" )
			)
			( signal "@baseboard_fab2_lib.baseboard_fab2(sch_1):vr_pvddq_ghj_pwm1"
				( attribute "CDS_PHYS_NET_NAME" "VR_PVDDQ_GHJ_PWM1"
					( Origin gPackager )
				)
				( objectStatus "VR_PVDDQ_GHJ_PWM1" )
			)
			( signal "@baseboard_fab2_lib.baseboard_fab2(sch_1):vr_pvddq_ghj_pwm2"
				( attribute "CDS_PHYS_NET_NAME" "VR_PVDDQ_GHJ_PWM2"
					( Origin gPackager )
				)
				( objectStatus "VR_PVDDQ_GHJ_PWM2" )
			)
			( signal "@baseboard_fab2_lib.baseboard_fab2(sch_1):vr_pvddq_ghj_vd12"
				( attribute "CDS_PHYS_NET_NAME" "VR_PVDDQ_GHJ_VD12"
					( Origin gPackager )
				)
				( objectStatus "VR_PVDDQ_GHJ_VD12" )
			)
			( signal "@baseboard_fab2_lib.baseboard_fab2(sch_1):vr_pvddq_ghj_vdd"
				( attribute "CDS_PHYS_NET_NAME" "VR_PVDDQ_GHJ_VDD"
					( Origin gPackager )
				)
				( objectStatus "VR_PVDDQ_GHJ_VDD" )
			)
			( signal "@baseboard_fab2_lib.baseboard_fab2(sch_1):vr_pvddq_ghj_vinsen"
				( attribute "CDS_PHYS_NET_NAME" "VR_PVDDQ_GHJ_VINSEN"
					( Origin gPackager )
				)
				( objectStatus "VR_PVDDQ_GHJ_VINSEN" )
			)
			( signal "@baseboard_fab2_lib.baseboard_fab2(sch_1):vr_pvddq_ghj_vren"
				( attribute "CDS_PHYS_NET_NAME" "VR_PVDDQ_GHJ_VREN"
					( Origin gPackager )
				)
				( objectStatus "VR_PVDDQ_GHJ_VREN" )
			)
			( signal "@baseboard_fab2_lib.baseboard_fab2(sch_1):vr_pvddq_ghj_xaddr1"
				( attribute "CDS_PHYS_NET_NAME" "VR_PVDDQ_GHJ_XADDR1"
					( Origin gPackager )
				)
				( objectStatus "VR_PVDDQ_GHJ_XADDR1" )
			)
			( signal "@baseboard_fab2_lib.baseboard_fab2(sch_1):vr_pvddq_ghj_xaddr2"
				( attribute "CDS_PHYS_NET_NAME" "VR_PVDDQ_GHJ_XADDR2"
					( Origin gPackager )
				)
				( objectStatus "VR_PVDDQ_GHJ_XADDR2" )
			)
			( signal "@baseboard_fab2_lib.baseboard_fab2(sch_1):vsense_pvddq_ghj_n"
				( attribute "CDS_PHYS_NET_NAME" "VSENSE_PVDDQ_GHJ_N"
					( Origin gPackager )
				)
				( objectStatus "VSENSE_PVDDQ_GHJ_N" )
			)
			( signal "@baseboard_fab2_lib.baseboard_fab2(sch_1):vsense_pvddq_ghj_p"
				( attribute "CDS_PHYS_NET_NAME" "VSENSE_PVDDQ_GHJ_P"
					( Origin gPackager )
				)
				( objectStatus "VSENSE_PVDDQ_GHJ_P" )
			)
			( signal "@baseboard_fab2_lib.baseboard_fab2(sch_1):nc_pvddq_ghj_ph1_p31"
				( attribute "CDS_PHYS_NET_NAME" "NC_PVDDQ_GHJ_PH1_P31"
					( Origin gPackager )
				)
				( objectStatus "NC_PVDDQ_GHJ_PH1_P31" )
			)
			( signal "@baseboard_fab2_lib.baseboard_fab2(sch_1):nc_pvddq_ghj_ph2_p31"
				( attribute "CDS_PHYS_NET_NAME" "NC_PVDDQ_GHJ_PH2_P31"
					( Origin gPackager )
				)
				( objectStatus "NC_PVDDQ_GHJ_PH2_P31" )
			)
			( signal "@baseboard_fab2_lib.baseboard_fab2(sch_1):tp_pvddq_ghj_ph1_gl_0"
				( attribute "CDS_PHYS_NET_NAME" "TP_PVDDQ_GHJ_PH1_GL_0"
					( Origin gPackager )
				)
				( objectStatus "TP_PVDDQ_GHJ_PH1_GL_0" )
			)
			( signal "@baseboard_fab2_lib.baseboard_fab2(sch_1):tp_pvddq_ghj_ph1_gl_1"
				( attribute "CDS_PHYS_NET_NAME" "TP_PVDDQ_GHJ_PH1_GL_1"
					( Origin gPackager )
				)
				( objectStatus "TP_PVDDQ_GHJ_PH1_GL_1" )
			)
			( signal "@baseboard_fab2_lib.baseboard_fab2(sch_1):tp_pvddq_ghj_ph2_gl_0"
				( attribute "CDS_PHYS_NET_NAME" "TP_PVDDQ_GHJ_PH2_GL_0"
					( Origin gPackager )
				)
				( objectStatus "TP_PVDDQ_GHJ_PH2_GL_0" )
			)
			( signal "@baseboard_fab2_lib.baseboard_fab2(sch_1):tp_pvddq_ghj_ph2_gl_1"
				( attribute "CDS_PHYS_NET_NAME" "TP_PVDDQ_GHJ_PH2_GL_1"
					( Origin gPackager )
				)
				( objectStatus "TP_PVDDQ_GHJ_PH2_GL_1" )
			)
			( signal "@baseboard_fab2_lib.baseboard_fab2(sch_1):vr_pvddq_ghj_ph1_boot"
				( attribute "CDS_PHYS_NET_NAME" "VR_PVDDQ_GHJ_PH1_BOOT"
					( Origin gPackager )
				)
				( objectStatus "VR_PVDDQ_GHJ_PH1_BOOT" )
			)
			( signal "@baseboard_fab2_lib.baseboard_fab2(sch_1):vr_pvddq_ghj_ph1_ocset"
				( alias ( signalRef "@baseboard_fab2_lib.baseboard_fab2(sch_1):page224_vr_pvddq_ghj_ph1_ocset") )
				( attribute "VOLTAGE" "3.6"
					( Units "uVoltage" "V" 1.000000)
					( Status sAliasFlattened )
					( Origin gFrontEnd )
				)
				( attribute "CDS_PHYS_NET_NAME" "VR_PVDDQ_GHJ_PH1_OCSET"
					( Origin gPackager )
				)
				( objectStatus "VR_PVDDQ_GHJ_PH1_OCSET" )
			)
			( signal "@baseboard_fab2_lib.baseboard_fab2(sch_1):page224_vr_pvddq_ghj_ph1_ocset"
				( attribute "VOLTAGE" "3.6"
					( Units "uVoltage" "V" 1.000000)
					( Origin gFrontEnd )
				)
				( objectFlag fObjectAlias )
				( objectStatus "page224_vr_pvddq_ghj_ph1_ocset" )
			)
			( signal "@baseboard_fab2_lib.baseboard_fab2(sch_1):vr_pvddq_ghj_ph1_phase"
				( attribute "CDS_PHYS_NET_NAME" "VR_PVDDQ_GHJ_PH1_PHASE"
					( Origin gPackager )
				)
				( objectStatus "VR_PVDDQ_GHJ_PH1_PHASE" )
			)
			( signal "@baseboard_fab2_lib.baseboard_fab2(sch_1):vr_pvddq_ghj_ph1_sw"
				( attribute "CDS_PHYS_NET_NAME" "VR_PVDDQ_GHJ_PH1_SW"
					( Origin gPackager )
				)
				( objectStatus "VR_PVDDQ_GHJ_PH1_SW" )
			)
			( signal "@baseboard_fab2_lib.baseboard_fab2(sch_1):vr_pvddq_ghj_ph1_vcin"
				( attribute "CDS_PHYS_NET_NAME" "VR_PVDDQ_GHJ_PH1_VCIN"
					( Origin gPackager )
				)
				( objectStatus "VR_PVDDQ_GHJ_PH1_VCIN" )
			)
			( signal "@baseboard_fab2_lib.baseboard_fab2(sch_1):vr_pvddq_ghj_ph2_boot"
				( attribute "CDS_PHYS_NET_NAME" "VR_PVDDQ_GHJ_PH2_BOOT"
					( Origin gPackager )
				)
				( objectStatus "VR_PVDDQ_GHJ_PH2_BOOT" )
			)
			( signal "@baseboard_fab2_lib.baseboard_fab2(sch_1):vr_pvddq_ghj_ph2_ocset"
				( alias ( signalRef "@baseboard_fab2_lib.baseboard_fab2(sch_1):page224_vr_pvddq_ghj_ph2_ocset") )
				( attribute "VOLTAGE" "3.6"
					( Units "uVoltage" "V" 1.000000)
					( Status sAliasFlattened )
					( Origin gFrontEnd )
				)
				( attribute "CDS_PHYS_NET_NAME" "VR_PVDDQ_GHJ_PH2_OCSET"
					( Origin gPackager )
				)
				( objectStatus "VR_PVDDQ_GHJ_PH2_OCSET" )
			)
			( signal "@baseboard_fab2_lib.baseboard_fab2(sch_1):page224_vr_pvddq_ghj_ph2_ocset"
				( attribute "VOLTAGE" "3.6"
					( Units "uVoltage" "V" 1.000000)
					( Origin gFrontEnd )
				)
				( objectFlag fObjectAlias )
				( objectStatus "page224_vr_pvddq_ghj_ph2_ocset" )
			)
			( signal "@baseboard_fab2_lib.baseboard_fab2(sch_1):vr_pvddq_ghj_ph2_phase"
				( attribute "CDS_PHYS_NET_NAME" "VR_PVDDQ_GHJ_PH2_PHASE"
					( Origin gPackager )
				)
				( objectStatus "VR_PVDDQ_GHJ_PH2_PHASE" )
			)
			( signal "@baseboard_fab2_lib.baseboard_fab2(sch_1):vr_pvddq_ghj_ph2_sw"
				( attribute "CDS_PHYS_NET_NAME" "VR_PVDDQ_GHJ_PH2_SW"
					( Origin gPackager )
				)
				( objectStatus "VR_PVDDQ_GHJ_PH2_SW" )
			)
			( signal "@baseboard_fab2_lib.baseboard_fab2(sch_1):vr_pvddq_ghj_ph2_vcin"
				( attribute "CDS_PHYS_NET_NAME" "VR_PVDDQ_GHJ_PH2_VCIN"
					( Origin gPackager )
				)
				( objectStatus "VR_PVDDQ_GHJ_PH2_VCIN" )
			)
			( signal "@baseboard_fab2_lib.baseboard_fab2(sch_1):a_tsense_pvddq_klm"
				( attribute "CDS_PHYS_NET_NAME" "A_TSENSE_PVDDQ_KLM"
					( Origin gPackager )
				)
				( objectStatus "A_TSENSE_PVDDQ_KLM" )
			)
			( signal "@baseboard_fab2_lib.baseboard_fab2(sch_1):irq_pvddq_klm_vrhot_lvt3_r_n"
				( attribute "CDS_PHYS_NET_NAME" "IRQ_PVDDQ_KLM_VRHOT_LVT3_R_N"
					( Origin gPackager )
				)
				( objectStatus "IRQ_PVDDQ_KLM_VRHOT_LVT3_R_N" )
			)
			( signal "@baseboard_fab2_lib.baseboard_fab2(sch_1):isense_pvddq_klm_ph1_imon"
				( attribute "CDS_PHYS_NET_NAME" "ISENSE_PVDDQ_KLM_PH1_IMON"
					( Origin gPackager )
				)
				( objectStatus "ISENSE_PVDDQ_KLM_PH1_IMON" )
			)
			( signal "@baseboard_fab2_lib.baseboard_fab2(sch_1):isense_pvddq_klm_ph2_imon"
				( attribute "CDS_PHYS_NET_NAME" "ISENSE_PVDDQ_KLM_PH2_IMON"
					( Origin gPackager )
				)
				( objectStatus "ISENSE_PVDDQ_KLM_PH2_IMON" )
			)
			( signal "@baseboard_fab2_lib.baseboard_fab2(sch_1):nc_pvddq_klm_dnc0"
				( attribute "CDS_PHYS_NET_NAME" "NC_PVDDQ_KLM_DNC0"
					( Origin gPackager )
				)
				( objectStatus "NC_PVDDQ_KLM_DNC0" )
			)
			( signal "@baseboard_fab2_lib.baseboard_fab2(sch_1):nc_pvddq_klm_dnc1"
				( attribute "CDS_PHYS_NET_NAME" "NC_PVDDQ_KLM_DNC1"
					( Origin gPackager )
				)
				( objectStatus "NC_PVDDQ_KLM_DNC1" )
			)
			( signal "@baseboard_fab2_lib.baseboard_fab2(sch_1):nc_pvddq_klm_gp0"
				( attribute "CDS_PHYS_NET_NAME" "NC_PVDDQ_KLM_GP0"
					( Origin gPackager )
				)
				( objectStatus "NC_PVDDQ_KLM_GP0" )
			)
			( signal "@baseboard_fab2_lib.baseboard_fab2(sch_1):nc_pvddq_klm_gp1"
				( attribute "CDS_PHYS_NET_NAME" "NC_PVDDQ_KLM_GP1"
					( Origin gPackager )
				)
				( objectStatus "NC_PVDDQ_KLM_GP1" )
			)
			( signal "@baseboard_fab2_lib.baseboard_fab2(sch_1):nc_pvddq_klm_pinalrt_n"
				( attribute "CDS_PHYS_NET_NAME" "NC_PVDDQ_KLM_PINALRT_N"
					( Origin gPackager )
				)
				( objectStatus "NC_PVDDQ_KLM_PINALRT_N" )
			)
			( signal "@baseboard_fab2_lib.baseboard_fab2(sch_1):nc_pvddq_klm_pwm3"
				( attribute "CDS_PHYS_NET_NAME" "NC_PVDDQ_KLM_PWM3"
					( Origin gPackager )
				)
				( objectStatus "NC_PVDDQ_KLM_PWM3" )
			)
			( signal "@baseboard_fab2_lib.baseboard_fab2(sch_1):pu_vr_pvddq_klm_fault1"
				( attribute "CDS_PHYS_NET_NAME" "PU_VR_PVDDQ_KLM_FAULT1"
					( Origin gPackager )
				)
				( objectStatus "PU_VR_PVDDQ_KLM_FAULT1" )
			)
			( signal "@baseboard_fab2_lib.baseboard_fab2(sch_1):pwrgd_pvddq_klm"
				( attribute "CDS_PHYS_NET_NAME" "PWRGD_PVDDQ_KLM"
					( Origin gPackager )
				)
				( objectStatus "PWRGD_PVDDQ_KLM" )
			)
			( signal "@baseboard_fab2_lib.baseboard_fab2(sch_1):pwrgd_pvddq_klm_r"
				( attribute "CDS_PHYS_NET_NAME" "PWRGD_PVDDQ_KLM_R"
					( Origin gPackager )
				)
				( objectStatus "PWRGD_PVDDQ_KLM_R" )
			)
			( signal "@baseboard_fab2_lib.baseboard_fab2(sch_1):smb_vr_scl_vddq_klm"
				( attribute "CDS_PHYS_NET_NAME" "SMB_VR_SCL_VDDQ_KLM"
					( Origin gPackager )
				)
				( objectStatus "SMB_VR_SCL_VDDQ_KLM" )
			)
			( signal "@baseboard_fab2_lib.baseboard_fab2(sch_1):smb_vr_sda_vddq_klm"
				( attribute "CDS_PHYS_NET_NAME" "SMB_VR_SDA_VDDQ_KLM"
					( Origin gPackager )
				)
				( objectStatus "SMB_VR_SDA_VDDQ_KLM" )
			)
			( signal "@baseboard_fab2_lib.baseboard_fab2(sch_1):svid_alert_pvddq_klm"
				( attribute "CDS_PHYS_NET_NAME" "SVID_ALERT_PVDDQ_KLM"
					( Origin gPackager )
				)
				( objectStatus "SVID_ALERT_PVDDQ_KLM" )
			)
			( signal "@baseboard_fab2_lib.baseboard_fab2(sch_1):svid_clk_pvddq_klm"
				( attribute "CDS_PHYS_NET_NAME" "SVID_CLK_PVDDQ_KLM"
					( Origin gPackager )
				)
				( objectStatus "SVID_CLK_PVDDQ_KLM" )
			)
			( signal "@baseboard_fab2_lib.baseboard_fab2(sch_1):svid_vdio_pvddq_klm"
				( attribute "CDS_PHYS_NET_NAME" "SVID_VDIO_PVDDQ_KLM"
					( Origin gPackager )
				)
				( objectStatus "SVID_VDIO_PVDDQ_KLM" )
			)
			( signal "@baseboard_fab2_lib.baseboard_fab2(sch_1):tp_pvddq_klm_bpwm1"
				( attribute "CDS_PHYS_NET_NAME" "TP_PVDDQ_KLM_BPWM1"
					( Origin gPackager )
				)
				( objectStatus "TP_PVDDQ_KLM_BPWM1" )
			)
			( signal "@baseboard_fab2_lib.baseboard_fab2(sch_1):tp_pvddq_klm_bref1"
				( attribute "CDS_PHYS_NET_NAME" "TP_PVDDQ_KLM_BREF1"
					( Origin gPackager )
				)
				( objectStatus "TP_PVDDQ_KLM_BREF1" )
			)
			( signal "@baseboard_fab2_lib.baseboard_fab2(sch_1):tp_pvddq_klm_btsen"
				( attribute "CDS_PHYS_NET_NAME" "TP_PVDDQ_KLM_BTSEN"
					( Origin gPackager )
				)
				( objectStatus "TP_PVDDQ_KLM_BTSEN" )
			)
			( signal "@baseboard_fab2_lib.baseboard_fab2(sch_1):tp_pvddq_klm_bvref"
				( attribute "CDS_PHYS_NET_NAME" "TP_PVDDQ_KLM_BVREF"
					( Origin gPackager )
				)
				( objectStatus "TP_PVDDQ_KLM_BVREF" )
			)
			( signal "@baseboard_fab2_lib.baseboard_fab2(sch_1):tp_pvddq_klm_bvsen"
				( attribute "CDS_PHYS_NET_NAME" "TP_PVDDQ_KLM_BVSEN"
					( Origin gPackager )
				)
				( objectStatus "TP_PVDDQ_KLM_BVSEN" )
			)
			( signal "@baseboard_fab2_lib.baseboard_fab2(sch_1):tp_pvddq_klm_ph3_imon"
				( attribute "CDS_PHYS_NET_NAME" "TP_PVDDQ_KLM_PH3_IMON"
					( Origin gPackager )
				)
				( objectStatus "TP_PVDDQ_KLM_PH3_IMON" )
			)
			( signal "@baseboard_fab2_lib.baseboard_fab2(sch_1):tp_pvddq_klm_ph3_imon_ref"
				( attribute "CDS_PHYS_NET_NAME" "TP_PVDDQ_KLM_PH3_IMON_REF"
					( Origin gPackager )
				)
				( objectStatus "TP_PVDDQ_KLM_PH3_IMON_REF" )
			)
			( signal "@baseboard_fab2_lib.baseboard_fab2(sch_1):tp_pvddq_klm_reset_n"
				( attribute "CDS_PHYS_NET_NAME" "TP_PVDDQ_KLM_RESET_N"
					( Origin gPackager )
				)
				( objectStatus "TP_PVDDQ_KLM_RESET_N" )
			)
			( signal "@baseboard_fab2_lib.baseboard_fab2(sch_1):vr_fet_sw_p12v_stby_pvddq_klm"
				( alias ( signalRef "@baseboard_fab2_lib.baseboard_fab2(sch_1):page226_vr_fet_sw_p12v_stby_pvddq_klm") )
				( alias ( signalRef "@baseboard_fab2_lib.baseboard_fab2(sch_1):page227_vr_fet_sw_p12v_stby_pvddq_klm") )
				( alias ( signalRef "@baseboard_fab2_lib.baseboard_fab2(sch_1):page228_vr_fet_sw_p12v_stby_pvddq_klm") )
				( attribute "CDS_PHYS_NET_NAME" "VR_FET_SW_P12V_STBY_PVDDQ_KLM"
					( Origin gPackager )
				)
				( objectStatus "VR_FET_SW_P12V_STBY_PVDDQ_KLM" )
			)
			( signal "@baseboard_fab2_lib.baseboard_fab2(sch_1):page226_vr_fet_sw_p12v_stby_pvddq_klm"
				( objectFlag fObjectAlias )
				( objectStatus "page226_vr_fet_sw_p12v_stby_pvddq_klm" )
			)
			( signal "@baseboard_fab2_lib.baseboard_fab2(sch_1):page227_vr_fet_sw_p12v_stby_pvddq_klm"
				( objectFlag fObjectAlias )
				( objectStatus "page227_vr_fet_sw_p12v_stby_pvddq_klm" )
			)
			( signal "@baseboard_fab2_lib.baseboard_fab2(sch_1):page228_vr_fet_sw_p12v_stby_pvddq_klm"
				( objectFlag fObjectAlias )
				( objectStatus "page228_vr_fet_sw_p12v_stby_pvddq_klm" )
			)
			( signal "@baseboard_fab2_lib.baseboard_fab2(sch_1):vr_pvddq_klm_airef1"
				( attribute "CDS_PHYS_NET_NAME" "VR_PVDDQ_KLM_AIREF1"
					( Origin gPackager )
				)
				( objectStatus "VR_PVDDQ_KLM_AIREF1" )
			)
			( signal "@baseboard_fab2_lib.baseboard_fab2(sch_1):vr_pvddq_klm_airef2"
				( attribute "CDS_PHYS_NET_NAME" "VR_PVDDQ_KLM_AIREF2"
					( Origin gPackager )
				)
				( objectStatus "VR_PVDDQ_KLM_AIREF2" )
			)
			( signal "@baseboard_fab2_lib.baseboard_fab2(sch_1):vr_pvddq_klm_avsp"
				( attribute "CDS_PHYS_NET_NAME" "VR_PVDDQ_KLM_AVSP"
					( Origin gPackager )
				)
				( objectStatus "VR_PVDDQ_KLM_AVSP" )
			)
			( signal "@baseboard_fab2_lib.baseboard_fab2(sch_1):vr_pvddq_klm_pwm1"
				( attribute "CDS_PHYS_NET_NAME" "VR_PVDDQ_KLM_PWM1"
					( Origin gPackager )
				)
				( objectStatus "VR_PVDDQ_KLM_PWM1" )
			)
			( signal "@baseboard_fab2_lib.baseboard_fab2(sch_1):vr_pvddq_klm_pwm2"
				( attribute "CDS_PHYS_NET_NAME" "VR_PVDDQ_KLM_PWM2"
					( Origin gPackager )
				)
				( objectStatus "VR_PVDDQ_KLM_PWM2" )
			)
			( signal "@baseboard_fab2_lib.baseboard_fab2(sch_1):vr_pvddq_klm_vd12"
				( attribute "CDS_PHYS_NET_NAME" "VR_PVDDQ_KLM_VD12"
					( Origin gPackager )
				)
				( objectStatus "VR_PVDDQ_KLM_VD12" )
			)
			( signal "@baseboard_fab2_lib.baseboard_fab2(sch_1):vr_pvddq_klm_vdd"
				( attribute "CDS_PHYS_NET_NAME" "VR_PVDDQ_KLM_VDD"
					( Origin gPackager )
				)
				( objectStatus "VR_PVDDQ_KLM_VDD" )
			)
			( signal "@baseboard_fab2_lib.baseboard_fab2(sch_1):vr_pvddq_klm_vinsen"
				( attribute "CDS_PHYS_NET_NAME" "VR_PVDDQ_KLM_VINSEN"
					( Origin gPackager )
				)
				( objectStatus "VR_PVDDQ_KLM_VINSEN" )
			)
			( signal "@baseboard_fab2_lib.baseboard_fab2(sch_1):vr_pvddq_klm_vren"
				( attribute "CDS_PHYS_NET_NAME" "VR_PVDDQ_KLM_VREN"
					( Origin gPackager )
				)
				( objectStatus "VR_PVDDQ_KLM_VREN" )
			)
			( signal "@baseboard_fab2_lib.baseboard_fab2(sch_1):vr_pvddq_klm_xaddr1"
				( attribute "CDS_PHYS_NET_NAME" "VR_PVDDQ_KLM_XADDR1"
					( Origin gPackager )
				)
				( objectStatus "VR_PVDDQ_KLM_XADDR1" )
			)
			( signal "@baseboard_fab2_lib.baseboard_fab2(sch_1):vr_pvddq_klm_xaddr2"
				( attribute "CDS_PHYS_NET_NAME" "VR_PVDDQ_KLM_XADDR2"
					( Origin gPackager )
				)
				( objectStatus "VR_PVDDQ_KLM_XADDR2" )
			)
			( signal "@baseboard_fab2_lib.baseboard_fab2(sch_1):vsense_pvddq_klm_n"
				( attribute "CDS_PHYS_NET_NAME" "VSENSE_PVDDQ_KLM_N"
					( Origin gPackager )
				)
				( objectStatus "VSENSE_PVDDQ_KLM_N" )
			)
			( signal "@baseboard_fab2_lib.baseboard_fab2(sch_1):vsense_pvddq_klm_p"
				( attribute "CDS_PHYS_NET_NAME" "VSENSE_PVDDQ_KLM_P"
					( Origin gPackager )
				)
				( objectStatus "VSENSE_PVDDQ_KLM_P" )
			)
			( signal "@baseboard_fab2_lib.baseboard_fab2(sch_1):nc_pvddq_klm_ph1_p31"
				( attribute "CDS_PHYS_NET_NAME" "NC_PVDDQ_KLM_PH1_P31"
					( Origin gPackager )
				)
				( objectStatus "NC_PVDDQ_KLM_PH1_P31" )
			)
			( signal "@baseboard_fab2_lib.baseboard_fab2(sch_1):nc_pvddq_klm_ph2_p31"
				( attribute "CDS_PHYS_NET_NAME" "NC_PVDDQ_KLM_PH2_P31"
					( Origin gPackager )
				)
				( objectStatus "NC_PVDDQ_KLM_PH2_P31" )
			)
			( signal "@baseboard_fab2_lib.baseboard_fab2(sch_1):tp_pvddq_klm_ph1_gl_0"
				( attribute "CDS_PHYS_NET_NAME" "TP_PVDDQ_KLM_PH1_GL_0"
					( Origin gPackager )
				)
				( objectStatus "TP_PVDDQ_KLM_PH1_GL_0" )
			)
			( signal "@baseboard_fab2_lib.baseboard_fab2(sch_1):tp_pvddq_klm_ph1_gl_1"
				( attribute "CDS_PHYS_NET_NAME" "TP_PVDDQ_KLM_PH1_GL_1"
					( Origin gPackager )
				)
				( objectStatus "TP_PVDDQ_KLM_PH1_GL_1" )
			)
			( signal "@baseboard_fab2_lib.baseboard_fab2(sch_1):tp_pvddq_klm_ph2_gl_0"
				( attribute "CDS_PHYS_NET_NAME" "TP_PVDDQ_KLM_PH2_GL_0"
					( Origin gPackager )
				)
				( objectStatus "TP_PVDDQ_KLM_PH2_GL_0" )
			)
			( signal "@baseboard_fab2_lib.baseboard_fab2(sch_1):tp_pvddq_klm_ph2_gl_1"
				( attribute "CDS_PHYS_NET_NAME" "TP_PVDDQ_KLM_PH2_GL_1"
					( Origin gPackager )
				)
				( objectStatus "TP_PVDDQ_KLM_PH2_GL_1" )
			)
			( signal "@baseboard_fab2_lib.baseboard_fab2(sch_1):vr_pvddq_klm_ph1_boot"
				( attribute "CDS_PHYS_NET_NAME" "VR_PVDDQ_KLM_PH1_BOOT"
					( Origin gPackager )
				)
				( objectStatus "VR_PVDDQ_KLM_PH1_BOOT" )
			)
			( signal "@baseboard_fab2_lib.baseboard_fab2(sch_1):vr_pvddq_klm_ph1_ocset"
				( alias ( signalRef "@baseboard_fab2_lib.baseboard_fab2(sch_1):page227_vr_pvddq_klm_ph1_ocset") )
				( attribute "VOLTAGE" "3.6"
					( Units "uVoltage" "V" 1.000000)
					( Status sAliasFlattened )
					( Origin gFrontEnd )
				)
				( attribute "CDS_PHYS_NET_NAME" "VR_PVDDQ_KLM_PH1_OCSET"
					( Origin gPackager )
				)
				( objectStatus "VR_PVDDQ_KLM_PH1_OCSET" )
			)
			( signal "@baseboard_fab2_lib.baseboard_fab2(sch_1):page227_vr_pvddq_klm_ph1_ocset"
				( attribute "VOLTAGE" "3.6"
					( Units "uVoltage" "V" 1.000000)
					( Origin gFrontEnd )
				)
				( objectFlag fObjectAlias )
				( objectStatus "page227_vr_pvddq_klm_ph1_ocset" )
			)
			( signal "@baseboard_fab2_lib.baseboard_fab2(sch_1):vr_pvddq_klm_ph1_phase"
				( attribute "CDS_PHYS_NET_NAME" "VR_PVDDQ_KLM_PH1_PHASE"
					( Origin gPackager )
				)
				( objectStatus "VR_PVDDQ_KLM_PH1_PHASE" )
			)
			( signal "@baseboard_fab2_lib.baseboard_fab2(sch_1):vr_pvddq_klm_ph1_sw"
				( attribute "CDS_PHYS_NET_NAME" "VR_PVDDQ_KLM_PH1_SW"
					( Origin gPackager )
				)
				( objectStatus "VR_PVDDQ_KLM_PH1_SW" )
			)
			( signal "@baseboard_fab2_lib.baseboard_fab2(sch_1):vr_pvddq_klm_ph1_vcin"
				( attribute "CDS_PHYS_NET_NAME" "VR_PVDDQ_KLM_PH1_VCIN"
					( Origin gPackager )
				)
				( objectStatus "VR_PVDDQ_KLM_PH1_VCIN" )
			)
			( signal "@baseboard_fab2_lib.baseboard_fab2(sch_1):vr_pvddq_klm_ph2_boot"
				( attribute "CDS_PHYS_NET_NAME" "VR_PVDDQ_KLM_PH2_BOOT"
					( Origin gPackager )
				)
				( objectStatus "VR_PVDDQ_KLM_PH2_BOOT" )
			)
			( signal "@baseboard_fab2_lib.baseboard_fab2(sch_1):vr_pvddq_klm_ph2_ocset"
				( alias ( signalRef "@baseboard_fab2_lib.baseboard_fab2(sch_1):page227_vr_pvddq_klm_ph2_ocset") )
				( attribute "VOLTAGE" "3.6"
					( Units "uVoltage" "V" 1.000000)
					( Status sAliasFlattened )
					( Origin gFrontEnd )
				)
				( attribute "CDS_PHYS_NET_NAME" "VR_PVDDQ_KLM_PH2_OCSET"
					( Origin gPackager )
				)
				( objectStatus "VR_PVDDQ_KLM_PH2_OCSET" )
			)
			( signal "@baseboard_fab2_lib.baseboard_fab2(sch_1):page227_vr_pvddq_klm_ph2_ocset"
				( attribute "VOLTAGE" "3.6"
					( Units "uVoltage" "V" 1.000000)
					( Origin gFrontEnd )
				)
				( objectFlag fObjectAlias )
				( objectStatus "page227_vr_pvddq_klm_ph2_ocset" )
			)
			( signal "@baseboard_fab2_lib.baseboard_fab2(sch_1):vr_pvddq_klm_ph2_phase"
				( attribute "CDS_PHYS_NET_NAME" "VR_PVDDQ_KLM_PH2_PHASE"
					( Origin gPackager )
				)
				( objectStatus "VR_PVDDQ_KLM_PH2_PHASE" )
			)
			( signal "@baseboard_fab2_lib.baseboard_fab2(sch_1):vr_pvddq_klm_ph2_sw"
				( attribute "CDS_PHYS_NET_NAME" "VR_PVDDQ_KLM_PH2_SW"
					( Origin gPackager )
				)
				( objectStatus "VR_PVDDQ_KLM_PH2_SW" )
			)
			( signal "@baseboard_fab2_lib.baseboard_fab2(sch_1):vr_pvddq_klm_ph2_vcin"
				( attribute "CDS_PHYS_NET_NAME" "VR_PVDDQ_KLM_PH2_VCIN"
					( Origin gPackager )
				)
				( objectStatus "VR_PVDDQ_KLM_PH2_VCIN" )
			)
			( signal "@baseboard_fab2_lib.baseboard_fab2(sch_1):fm_pvtt_ghj_en_r"
				( attribute "CDS_PHYS_NET_NAME" "FM_PVTT_GHJ_EN_R"
					( Origin gPackager )
				)
				( objectStatus "FM_PVTT_GHJ_EN_R" )
			)
			( signal "@baseboard_fab2_lib.baseboard_fab2(sch_1):pwrgd_pvtt_ghj_cpu1_r"
				( attribute "CDS_PHYS_NET_NAME" "PWRGD_PVTT_GHJ_CPU1_R"
					( Origin gPackager )
				)
				( objectStatus "PWRGD_PVTT_GHJ_CPU1_R" )
			)
			( signal "@baseboard_fab2_lib.baseboard_fab2(sch_1):vr_pvtt_ghj_bias"
				( attribute "CDS_PHYS_NET_NAME" "VR_PVTT_GHJ_BIAS"
					( Origin gPackager )
				)
				( objectStatus "VR_PVTT_GHJ_BIAS" )
			)
			( signal "@baseboard_fab2_lib.baseboard_fab2(sch_1):vr_pvtt_ghj_sns"
				( attribute "CDS_PHYS_NET_NAME" "VR_PVTT_GHJ_SNS"
					( Origin gPackager )
				)
				( objectStatus "VR_PVTT_GHJ_SNS" )
			)
			( signal "@baseboard_fab2_lib.baseboard_fab2(sch_1):vr_pvtt_ghj_vref"
				( attribute "CDS_PHYS_NET_NAME" "VR_PVTT_GHJ_VREF"
					( Origin gPackager )
				)
				( objectStatus "VR_PVTT_GHJ_VREF" )
			)
			( signal "@baseboard_fab2_lib.baseboard_fab2(sch_1):vsense_pvddq_ghj_vtt"
				( attribute "CDS_PHYS_NET_NAME" "VSENSE_PVDDQ_GHJ_VTT"
					( Origin gPackager )
				)
				( objectStatus "VSENSE_PVDDQ_GHJ_VTT" )
			)
			( signal "@baseboard_fab2_lib.baseboard_fab2(sch_1):fm_pvtt_klm_en_r"
				( attribute "CDS_PHYS_NET_NAME" "FM_PVTT_KLM_EN_R"
					( Origin gPackager )
				)
				( objectStatus "FM_PVTT_KLM_EN_R" )
			)
			( signal "@baseboard_fab2_lib.baseboard_fab2(sch_1):pwrgd_pvtt_klm_cpu1_r"
				( attribute "CDS_PHYS_NET_NAME" "PWRGD_PVTT_KLM_CPU1_R"
					( Origin gPackager )
				)
				( objectStatus "PWRGD_PVTT_KLM_CPU1_R" )
			)
			( signal "@baseboard_fab2_lib.baseboard_fab2(sch_1):vr_pvtt_klm_bias"
				( attribute "CDS_PHYS_NET_NAME" "VR_PVTT_KLM_BIAS"
					( Origin gPackager )
				)
				( objectStatus "VR_PVTT_KLM_BIAS" )
			)
			( signal "@baseboard_fab2_lib.baseboard_fab2(sch_1):vr_pvtt_klm_sns"
				( attribute "CDS_PHYS_NET_NAME" "VR_PVTT_KLM_SNS"
					( Origin gPackager )
				)
				( objectStatus "VR_PVTT_KLM_SNS" )
			)
			( signal "@baseboard_fab2_lib.baseboard_fab2(sch_1):vr_pvtt_klm_vref"
				( attribute "CDS_PHYS_NET_NAME" "VR_PVTT_KLM_VREF"
					( Origin gPackager )
				)
				( objectStatus "VR_PVTT_KLM_VREF" )
			)
			( signal "@baseboard_fab2_lib.baseboard_fab2(sch_1):vsense_pvddq_klm_vtt"
				( attribute "CDS_PHYS_NET_NAME" "VSENSE_PVDDQ_KLM_VTT"
					( Origin gPackager )
				)
				( objectStatus "VSENSE_PVDDQ_KLM_VTT" )
			)
			( signal "@baseboard_fab2_lib.baseboard_fab2(sch_1):agnd_pvpp_abc"
				( alias ( signalRef "@baseboard_fab2_lib.baseboard_fab2(sch_1):page231_agnd_pvpp_abc") )
				( attribute "VOLTAGE" "0.0V"
					( Units "uVoltage" "V" 1.000000)
					( Status sAliasFlattened )
					( Origin gFrontEnd )
				)
				( attribute "CDS_PHYS_NET_NAME" "AGND_PVPP_ABC"
					( Origin gPackager )
				)
				( objectStatus "AGND_PVPP_ABC" )
			)
			( signal "@baseboard_fab2_lib.baseboard_fab2(sch_1):page231_agnd_pvpp_abc"
				( attribute "VOLTAGE" "0.0V"
					( Units "uVoltage" "V" 1.000000)
					( Origin gFrontEnd )
				)
				( objectFlag fObjectAlias )
				( objectStatus "page231_agnd_pvpp_abc" )
			)
			( signal "@baseboard_fab2_lib.baseboard_fab2(sch_1):fm_pvpp_pvddq_cpu0_en_abc"
				( attribute "CDS_PHYS_NET_NAME" "FM_PVPP_PVDDQ_CPU0_EN_ABC"
					( Origin gPackager )
				)
				( objectStatus "FM_PVPP_PVDDQ_CPU0_EN_ABC" )
			)
			( signal "@baseboard_fab2_lib.baseboard_fab2(sch_1):pwrgd_pvpp_abc_r"
				( attribute "CDS_PHYS_NET_NAME" "PWRGD_PVPP_ABC_R"
					( Origin gPackager )
				)
				( objectStatus "PWRGD_PVPP_ABC_R" )
			)
			( signal "@baseboard_fab2_lib.baseboard_fab2(sch_1):vr_comp_pvpp_abc"
				( attribute "CDS_PHYS_NET_NAME" "VR_COMP_PVPP_ABC"
					( Origin gPackager )
				)
				( objectStatus "VR_COMP_PVPP_ABC" )
			)
			( signal "@baseboard_fab2_lib.baseboard_fab2(sch_1):vr_comp_pvpp_abc_3"
				( attribute "CDS_PHYS_NET_NAME" "VR_COMP_PVPP_ABC_3"
					( Origin gPackager )
				)
				( objectStatus "VR_COMP_PVPP_ABC_3" )
			)
			( signal "@baseboard_fab2_lib.baseboard_fab2(sch_1):vr_comp_rc_pvpp_abc"
				( attribute "CDS_PHYS_NET_NAME" "VR_COMP_RC_PVPP_ABC"
					( Origin gPackager )
				)
				( objectStatus "VR_COMP_RC_PVPP_ABC" )
			)
			( signal "@baseboard_fab2_lib.baseboard_fab2(sch_1):vr_fb_pvpp_abc"
				( attribute "CDS_PHYS_NET_NAME" "VR_FB_PVPP_ABC"
					( Origin gPackager )
				)
				( objectStatus "VR_FB_PVPP_ABC" )
			)
			( signal "@baseboard_fab2_lib.baseboard_fab2(sch_1):vr_fet_sw_p12v_stby_pvpp_abc"
				( attribute "CDS_PHYS_NET_NAME" "VR_FET_SW_P12V_STBY_PVPP_ABC"
					( Origin gPackager )
				)
				( objectStatus "VR_FET_SW_P12V_STBY_PVPP_ABC" )
			)
			( signal "@baseboard_fab2_lib.baseboard_fab2(sch_1):vr_pvpp_abc_boot"
				( attribute "CDS_PHYS_NET_NAME" "VR_PVPP_ABC_BOOT"
					( Origin gPackager )
				)
				( objectStatus "VR_PVPP_ABC_BOOT" )
			)
			( signal "@baseboard_fab2_lib.baseboard_fab2(sch_1):vr_pvpp_abc_boot_r"
				( attribute "CDS_PHYS_NET_NAME" "VR_PVPP_ABC_BOOT_R"
					( Origin gPackager )
				)
				( objectStatus "VR_PVPP_ABC_BOOT_R" )
			)
			( signal "@baseboard_fab2_lib.baseboard_fab2(sch_1):vr_pvpp_abc_iset"
				( attribute "CDS_PHYS_NET_NAME" "VR_PVPP_ABC_ISET"
					( Origin gPackager )
				)
				( objectStatus "VR_PVPP_ABC_ISET" )
			)
			( signal "@baseboard_fab2_lib.baseboard_fab2(sch_1):vr_pvpp_abc_phase"
				( attribute "CDS_PHYS_NET_NAME" "VR_PVPP_ABC_PHASE"
					( Origin gPackager )
				)
				( objectStatus "VR_PVPP_ABC_PHASE" )
			)
			( signal "@baseboard_fab2_lib.baseboard_fab2(sch_1):vr_pvpp_abc_snub"
				( attribute "CDS_PHYS_NET_NAME" "VR_PVPP_ABC_SNUB"
					( Origin gPackager )
				)
				( objectStatus "VR_PVPP_ABC_SNUB" )
			)
			( signal "@baseboard_fab2_lib.baseboard_fab2(sch_1):vr_pvpp_abc_ss"
				( attribute "CDS_PHYS_NET_NAME" "VR_PVPP_ABC_SS"
					( Origin gPackager )
				)
				( objectStatus "VR_PVPP_ABC_SS" )
			)
			( signal "@baseboard_fab2_lib.baseboard_fab2(sch_1):vr_vb_pvpp_abc"
				( attribute "CDS_PHYS_NET_NAME" "VR_VB_PVPP_ABC"
					( Origin gPackager )
				)
				( objectStatus "VR_VB_PVPP_ABC" )
			)
			( signal "@baseboard_fab2_lib.baseboard_fab2(sch_1):vsense_pvpp_abc"
				( attribute "CDS_PHYS_NET_NAME" "VSENSE_PVPP_ABC"
					( Origin gPackager )
				)
				( objectStatus "VSENSE_PVPP_ABC" )
			)
			( signal "@baseboard_fab2_lib.baseboard_fab2(sch_1):agnd_pvpp_def"
				( alias ( signalRef "@baseboard_fab2_lib.baseboard_fab2(sch_1):page232_agnd_pvpp_def") )
				( attribute "VOLTAGE" "0.0V"
					( Units "uVoltage" "V" 1.000000)
					( Status sAliasFlattened )
					( Origin gFrontEnd )
				)
				( attribute "CDS_PHYS_NET_NAME" "AGND_PVPP_DEF"
					( Origin gPackager )
				)
				( objectStatus "AGND_PVPP_DEF" )
			)
			( signal "@baseboard_fab2_lib.baseboard_fab2(sch_1):page232_agnd_pvpp_def"
				( attribute "VOLTAGE" "0.0V"
					( Units "uVoltage" "V" 1.000000)
					( Origin gFrontEnd )
				)
				( objectFlag fObjectAlias )
				( objectStatus "page232_agnd_pvpp_def" )
			)
			( signal "@baseboard_fab2_lib.baseboard_fab2(sch_1):fm_pvpp_pvddq_cpu0_en_def"
				( attribute "CDS_PHYS_NET_NAME" "FM_PVPP_PVDDQ_CPU0_EN_DEF"
					( Origin gPackager )
				)
				( objectStatus "FM_PVPP_PVDDQ_CPU0_EN_DEF" )
			)
			( signal "@baseboard_fab2_lib.baseboard_fab2(sch_1):pwrgd_pvpp_def_r"
				( attribute "CDS_PHYS_NET_NAME" "PWRGD_PVPP_DEF_R"
					( Origin gPackager )
				)
				( objectStatus "PWRGD_PVPP_DEF_R" )
			)
			( signal "@baseboard_fab2_lib.baseboard_fab2(sch_1):vr_comp_pvpp_def"
				( attribute "CDS_PHYS_NET_NAME" "VR_COMP_PVPP_DEF"
					( Origin gPackager )
				)
				( objectStatus "VR_COMP_PVPP_DEF" )
			)
			( signal "@baseboard_fab2_lib.baseboard_fab2(sch_1):vr_comp_pvpp_def_3"
				( attribute "CDS_PHYS_NET_NAME" "VR_COMP_PVPP_DEF_3"
					( Origin gPackager )
				)
				( objectStatus "VR_COMP_PVPP_DEF_3" )
			)
			( signal "@baseboard_fab2_lib.baseboard_fab2(sch_1):vr_comp_rc_pvpp_def"
				( attribute "CDS_PHYS_NET_NAME" "VR_COMP_RC_PVPP_DEF"
					( Origin gPackager )
				)
				( objectStatus "VR_COMP_RC_PVPP_DEF" )
			)
			( signal "@baseboard_fab2_lib.baseboard_fab2(sch_1):vr_fb_pvpp_def"
				( attribute "CDS_PHYS_NET_NAME" "VR_FB_PVPP_DEF"
					( Origin gPackager )
				)
				( objectStatus "VR_FB_PVPP_DEF" )
			)
			( signal "@baseboard_fab2_lib.baseboard_fab2(sch_1):vr_fet_sw_p12v_stby_pvpp_def"
				( attribute "CDS_PHYS_NET_NAME" "VR_FET_SW_P12V_STBY_PVPP_DEF"
					( Origin gPackager )
				)
				( objectStatus "VR_FET_SW_P12V_STBY_PVPP_DEF" )
			)
			( signal "@baseboard_fab2_lib.baseboard_fab2(sch_1):vr_pvpp_def_boot"
				( attribute "CDS_PHYS_NET_NAME" "VR_PVPP_DEF_BOOT"
					( Origin gPackager )
				)
				( objectStatus "VR_PVPP_DEF_BOOT" )
			)
			( signal "@baseboard_fab2_lib.baseboard_fab2(sch_1):vr_pvpp_def_boot_r"
				( attribute "CDS_PHYS_NET_NAME" "VR_PVPP_DEF_BOOT_R"
					( Origin gPackager )
				)
				( objectStatus "VR_PVPP_DEF_BOOT_R" )
			)
			( signal "@baseboard_fab2_lib.baseboard_fab2(sch_1):vr_pvpp_def_iset"
				( attribute "CDS_PHYS_NET_NAME" "VR_PVPP_DEF_ISET"
					( Origin gPackager )
				)
				( objectStatus "VR_PVPP_DEF_ISET" )
			)
			( signal "@baseboard_fab2_lib.baseboard_fab2(sch_1):vr_pvpp_def_phase"
				( attribute "CDS_PHYS_NET_NAME" "VR_PVPP_DEF_PHASE"
					( Origin gPackager )
				)
				( objectStatus "VR_PVPP_DEF_PHASE" )
			)
			( signal "@baseboard_fab2_lib.baseboard_fab2(sch_1):vr_pvpp_def_snub"
				( attribute "CDS_PHYS_NET_NAME" "VR_PVPP_DEF_SNUB"
					( Origin gPackager )
				)
				( objectStatus "VR_PVPP_DEF_SNUB" )
			)
			( signal "@baseboard_fab2_lib.baseboard_fab2(sch_1):vr_pvpp_def_ss"
				( attribute "CDS_PHYS_NET_NAME" "VR_PVPP_DEF_SS"
					( Origin gPackager )
				)
				( objectStatus "VR_PVPP_DEF_SS" )
			)
			( signal "@baseboard_fab2_lib.baseboard_fab2(sch_1):vr_vb_pvpp_def"
				( attribute "CDS_PHYS_NET_NAME" "VR_VB_PVPP_DEF"
					( Origin gPackager )
				)
				( objectStatus "VR_VB_PVPP_DEF" )
			)
			( signal "@baseboard_fab2_lib.baseboard_fab2(sch_1):vsense_pvpp_def"
				( attribute "CDS_PHYS_NET_NAME" "VSENSE_PVPP_DEF"
					( Origin gPackager )
				)
				( objectStatus "VSENSE_PVPP_DEF" )
			)
			( signal "@baseboard_fab2_lib.baseboard_fab2(sch_1):agnd_pvpp_ghj"
				( alias ( signalRef "@baseboard_fab2_lib.baseboard_fab2(sch_1):page233_agnd_pvpp_ghj") )
				( attribute "VOLTAGE" "0.0V"
					( Units "uVoltage" "V" 1.000000)
					( Status sAliasFlattened )
					( Origin gFrontEnd )
				)
				( attribute "CDS_PHYS_NET_NAME" "AGND_PVPP_GHJ"
					( Origin gPackager )
				)
				( objectStatus "AGND_PVPP_GHJ" )
			)
			( signal "@baseboard_fab2_lib.baseboard_fab2(sch_1):page233_agnd_pvpp_ghj"
				( attribute "VOLTAGE" "0.0V"
					( Units "uVoltage" "V" 1.000000)
					( Origin gFrontEnd )
				)
				( objectFlag fObjectAlias )
				( objectStatus "page233_agnd_pvpp_ghj" )
			)
			( signal "@baseboard_fab2_lib.baseboard_fab2(sch_1):fm_pvpp_pvddq_cpu1_en_ghj"
				( attribute "CDS_PHYS_NET_NAME" "FM_PVPP_PVDDQ_CPU1_EN_GHJ"
					( Origin gPackager )
				)
				( objectStatus "FM_PVPP_PVDDQ_CPU1_EN_GHJ" )
			)
			( signal "@baseboard_fab2_lib.baseboard_fab2(sch_1):pwrgd_pvpp_ghj_r"
				( attribute "CDS_PHYS_NET_NAME" "PWRGD_PVPP_GHJ_R"
					( Origin gPackager )
				)
				( objectStatus "PWRGD_PVPP_GHJ_R" )
			)
			( signal "@baseboard_fab2_lib.baseboard_fab2(sch_1):vr_comp_pvpp_ghj"
				( attribute "CDS_PHYS_NET_NAME" "VR_COMP_PVPP_GHJ"
					( Origin gPackager )
				)
				( objectStatus "VR_COMP_PVPP_GHJ" )
			)
			( signal "@baseboard_fab2_lib.baseboard_fab2(sch_1):vr_comp_pvpp_ghj_3"
				( attribute "CDS_PHYS_NET_NAME" "VR_COMP_PVPP_GHJ_3"
					( Origin gPackager )
				)
				( objectStatus "VR_COMP_PVPP_GHJ_3" )
			)
			( signal "@baseboard_fab2_lib.baseboard_fab2(sch_1):vr_comp_rc_pvpp_ghj"
				( attribute "CDS_PHYS_NET_NAME" "VR_COMP_RC_PVPP_GHJ"
					( Origin gPackager )
				)
				( objectStatus "VR_COMP_RC_PVPP_GHJ" )
			)
			( signal "@baseboard_fab2_lib.baseboard_fab2(sch_1):vr_fb_pvpp_ghj"
				( attribute "CDS_PHYS_NET_NAME" "VR_FB_PVPP_GHJ"
					( Origin gPackager )
				)
				( objectStatus "VR_FB_PVPP_GHJ" )
			)
			( signal "@baseboard_fab2_lib.baseboard_fab2(sch_1):vr_fet_sw_p12v_stby_pvpp_ghj"
				( attribute "CDS_PHYS_NET_NAME" "VR_FET_SW_P12V_STBY_PVPP_GHJ"
					( Origin gPackager )
				)
				( objectStatus "VR_FET_SW_P12V_STBY_PVPP_GHJ" )
			)
			( signal "@baseboard_fab2_lib.baseboard_fab2(sch_1):vr_pvpp_ghj_boot"
				( attribute "CDS_PHYS_NET_NAME" "VR_PVPP_GHJ_BOOT"
					( Origin gPackager )
				)
				( objectStatus "VR_PVPP_GHJ_BOOT" )
			)
			( signal "@baseboard_fab2_lib.baseboard_fab2(sch_1):vr_pvpp_ghj_boot_r"
				( attribute "CDS_PHYS_NET_NAME" "VR_PVPP_GHJ_BOOT_R"
					( Origin gPackager )
				)
				( objectStatus "VR_PVPP_GHJ_BOOT_R" )
			)
			( signal "@baseboard_fab2_lib.baseboard_fab2(sch_1):vr_pvpp_ghj_iset"
				( attribute "CDS_PHYS_NET_NAME" "VR_PVPP_GHJ_ISET"
					( Origin gPackager )
				)
				( objectStatus "VR_PVPP_GHJ_ISET" )
			)
			( signal "@baseboard_fab2_lib.baseboard_fab2(sch_1):vr_pvpp_ghj_phase"
				( attribute "CDS_PHYS_NET_NAME" "VR_PVPP_GHJ_PHASE"
					( Origin gPackager )
				)
				( objectStatus "VR_PVPP_GHJ_PHASE" )
			)
			( signal "@baseboard_fab2_lib.baseboard_fab2(sch_1):vr_pvpp_ghj_snub"
				( attribute "CDS_PHYS_NET_NAME" "VR_PVPP_GHJ_SNUB"
					( Origin gPackager )
				)
				( objectStatus "VR_PVPP_GHJ_SNUB" )
			)
			( signal "@baseboard_fab2_lib.baseboard_fab2(sch_1):vr_pvpp_ghj_ss"
				( attribute "CDS_PHYS_NET_NAME" "VR_PVPP_GHJ_SS"
					( Origin gPackager )
				)
				( objectStatus "VR_PVPP_GHJ_SS" )
			)
			( signal "@baseboard_fab2_lib.baseboard_fab2(sch_1):vr_vb_pvpp_ghj"
				( attribute "CDS_PHYS_NET_NAME" "VR_VB_PVPP_GHJ"
					( Origin gPackager )
				)
				( objectStatus "VR_VB_PVPP_GHJ" )
			)
			( signal "@baseboard_fab2_lib.baseboard_fab2(sch_1):vsense_pvpp_ghj"
				( attribute "CDS_PHYS_NET_NAME" "VSENSE_PVPP_GHJ"
					( Origin gPackager )
				)
				( objectStatus "VSENSE_PVPP_GHJ" )
			)
			( signal "@baseboard_fab2_lib.baseboard_fab2(sch_1):agnd_pvpp_klm"
				( alias ( signalRef "@baseboard_fab2_lib.baseboard_fab2(sch_1):page234_agnd_pvpp_klm") )
				( attribute "VOLTAGE" "0.0V"
					( Units "uVoltage" "V" 1.000000)
					( Status sAliasFlattened )
					( Origin gFrontEnd )
				)
				( attribute "CDS_PHYS_NET_NAME" "AGND_PVPP_KLM"
					( Origin gPackager )
				)
				( objectStatus "AGND_PVPP_KLM" )
			)
			( signal "@baseboard_fab2_lib.baseboard_fab2(sch_1):page234_agnd_pvpp_klm"
				( attribute "VOLTAGE" "0.0V"
					( Units "uVoltage" "V" 1.000000)
					( Origin gFrontEnd )
				)
				( objectFlag fObjectAlias )
				( objectStatus "page234_agnd_pvpp_klm" )
			)
			( signal "@baseboard_fab2_lib.baseboard_fab2(sch_1):fm_pvpp_pvddq_cpu1_en_klm"
				( attribute "CDS_PHYS_NET_NAME" "FM_PVPP_PVDDQ_CPU1_EN_KLM"
					( Origin gPackager )
				)
				( objectStatus "FM_PVPP_PVDDQ_CPU1_EN_KLM" )
			)
			( signal "@baseboard_fab2_lib.baseboard_fab2(sch_1):pwrgd_pvpp_klm_r"
				( attribute "CDS_PHYS_NET_NAME" "PWRGD_PVPP_KLM_R"
					( Origin gPackager )
				)
				( objectStatus "PWRGD_PVPP_KLM_R" )
			)
			( signal "@baseboard_fab2_lib.baseboard_fab2(sch_1):vr_comp_pvpp_klm"
				( attribute "CDS_PHYS_NET_NAME" "VR_COMP_PVPP_KLM"
					( Origin gPackager )
				)
				( objectStatus "VR_COMP_PVPP_KLM" )
			)
			( signal "@baseboard_fab2_lib.baseboard_fab2(sch_1):vr_comp_pvpp_klm_3"
				( attribute "CDS_PHYS_NET_NAME" "VR_COMP_PVPP_KLM_3"
					( Origin gPackager )
				)
				( objectStatus "VR_COMP_PVPP_KLM_3" )
			)
			( signal "@baseboard_fab2_lib.baseboard_fab2(sch_1):vr_comp_rc_pvpp_klm"
				( attribute "CDS_PHYS_NET_NAME" "VR_COMP_RC_PVPP_KLM"
					( Origin gPackager )
				)
				( objectStatus "VR_COMP_RC_PVPP_KLM" )
			)
			( signal "@baseboard_fab2_lib.baseboard_fab2(sch_1):vr_fb_pvpp_klm"
				( attribute "CDS_PHYS_NET_NAME" "VR_FB_PVPP_KLM"
					( Origin gPackager )
				)
				( objectStatus "VR_FB_PVPP_KLM" )
			)
			( signal "@baseboard_fab2_lib.baseboard_fab2(sch_1):vr_fet_sw_p12v_stby_pvpp_klm"
				( attribute "CDS_PHYS_NET_NAME" "VR_FET_SW_P12V_STBY_PVPP_KLM"
					( Origin gPackager )
				)
				( objectStatus "VR_FET_SW_P12V_STBY_PVPP_KLM" )
			)
			( signal "@baseboard_fab2_lib.baseboard_fab2(sch_1):vr_pvpp_klm_boot"
				( attribute "CDS_PHYS_NET_NAME" "VR_PVPP_KLM_BOOT"
					( Origin gPackager )
				)
				( objectStatus "VR_PVPP_KLM_BOOT" )
			)
			( signal "@baseboard_fab2_lib.baseboard_fab2(sch_1):vr_pvpp_klm_boot_r"
				( attribute "CDS_PHYS_NET_NAME" "VR_PVPP_KLM_BOOT_R"
					( Origin gPackager )
				)
				( objectStatus "VR_PVPP_KLM_BOOT_R" )
			)
			( signal "@baseboard_fab2_lib.baseboard_fab2(sch_1):vr_pvpp_klm_iset"
				( attribute "CDS_PHYS_NET_NAME" "VR_PVPP_KLM_ISET"
					( Origin gPackager )
				)
				( objectStatus "VR_PVPP_KLM_ISET" )
			)
			( signal "@baseboard_fab2_lib.baseboard_fab2(sch_1):vr_pvpp_klm_phase"
				( attribute "CDS_PHYS_NET_NAME" "VR_PVPP_KLM_PHASE"
					( Origin gPackager )
				)
				( objectStatus "VR_PVPP_KLM_PHASE" )
			)
			( signal "@baseboard_fab2_lib.baseboard_fab2(sch_1):vr_pvpp_klm_snub"
				( attribute "CDS_PHYS_NET_NAME" "VR_PVPP_KLM_SNUB"
					( Origin gPackager )
				)
				( objectStatus "VR_PVPP_KLM_SNUB" )
			)
			( signal "@baseboard_fab2_lib.baseboard_fab2(sch_1):vr_pvpp_klm_ss"
				( attribute "CDS_PHYS_NET_NAME" "VR_PVPP_KLM_SS"
					( Origin gPackager )
				)
				( objectStatus "VR_PVPP_KLM_SS" )
			)
			( signal "@baseboard_fab2_lib.baseboard_fab2(sch_1):vr_vb_pvpp_klm"
				( attribute "CDS_PHYS_NET_NAME" "VR_VB_PVPP_KLM"
					( Origin gPackager )
				)
				( objectStatus "VR_VB_PVPP_KLM" )
			)
			( signal "@baseboard_fab2_lib.baseboard_fab2(sch_1):vsense_pvpp_klm"
				( attribute "CDS_PHYS_NET_NAME" "VSENSE_PVPP_KLM"
					( Origin gPackager )
				)
				( objectStatus "VSENSE_PVPP_KLM" )
			)
			( signal "@baseboard_fab2_lib.baseboard_fab2(sch_1):a_tsense_p1v05_pch_stby_tmon"
				( attribute "CDS_PHYS_NET_NAME" "A_TSENSE_P1V05_PCH_STBY_TMON"
					( Origin gPackager )
				)
				( objectStatus "A_TSENSE_P1V05_PCH_STBY_TMON" )
			)
			( signal "@baseboard_fab2_lib.baseboard_fab2(sch_1):a_tsense_pvnn_pch_tmon"
				( attribute "CDS_PHYS_NET_NAME" "A_TSENSE_PVNN_PCH_TMON"
					( Origin gPackager )
				)
				( objectStatus "A_TSENSE_PVNN_PCH_TMON" )
			)
			( signal "@baseboard_fab2_lib.baseboard_fab2(sch_1):irq_pvnn_pch_vrhot_n"
				( attribute "CDS_PHYS_NET_NAME" "IRQ_PVNN_PCH_VRHOT_N"
					( Origin gPackager )
				)
				( objectStatus "IRQ_PVNN_PCH_VRHOT_N" )
			)
			( signal "@baseboard_fab2_lib.baseboard_fab2(sch_1):isense_p1v05_pch_stby_ph1_imon"
				( attribute "CDS_PHYS_NET_NAME" "ISENSE_P1V05_PCH_STBY_PH1_IMON"
					( Origin gPackager )
				)
				( objectStatus "ISENSE_P1V05_PCH_STBY_PH1_IMON" )
			)
			( signal "@baseboard_fab2_lib.baseboard_fab2(sch_1):isense_pvnn_pch_ph1_imon"
				( attribute "CDS_PHYS_NET_NAME" "ISENSE_PVNN_PCH_PH1_IMON"
					( Origin gPackager )
				)
				( objectStatus "ISENSE_PVNN_PCH_PH1_IMON" )
			)
			( signal "@baseboard_fab2_lib.baseboard_fab2(sch_1):nc_pvnn_pch_dnc0"
				( attribute "CDS_PHYS_NET_NAME" "NC_PVNN_PCH_DNC0"
					( Origin gPackager )
				)
				( objectStatus "NC_PVNN_PCH_DNC0" )
			)
			( signal "@baseboard_fab2_lib.baseboard_fab2(sch_1):nc_pvnn_pch_dnc1"
				( attribute "CDS_PHYS_NET_NAME" "NC_PVNN_PCH_DNC1"
					( Origin gPackager )
				)
				( objectStatus "NC_PVNN_PCH_DNC1" )
			)
			( signal "@baseboard_fab2_lib.baseboard_fab2(sch_1):nc_pvnn_pch_dnc2"
				( attribute "CDS_PHYS_NET_NAME" "NC_PVNN_PCH_DNC2"
					( Origin gPackager )
				)
				( objectStatus "NC_PVNN_PCH_DNC2" )
			)
			( signal "@baseboard_fab2_lib.baseboard_fab2(sch_1):nc_pvnn_pch_dnc3"
				( attribute "CDS_PHYS_NET_NAME" "NC_PVNN_PCH_DNC3"
					( Origin gPackager )
				)
				( objectStatus "NC_PVNN_PCH_DNC3" )
			)
			( signal "@baseboard_fab2_lib.baseboard_fab2(sch_1):nc_pvnn_pch_dnc4"
				( attribute "CDS_PHYS_NET_NAME" "NC_PVNN_PCH_DNC4"
					( Origin gPackager )
				)
				( objectStatus "NC_PVNN_PCH_DNC4" )
			)
			( signal "@baseboard_fab2_lib.baseboard_fab2(sch_1):pu_vr_pvnn_pch_fault1"
				( attribute "CDS_PHYS_NET_NAME" "PU_VR_PVNN_PCH_FAULT1"
					( Origin gPackager )
				)
				( objectStatus "PU_VR_PVNN_PCH_FAULT1" )
			)
			( signal "@baseboard_fab2_lib.baseboard_fab2(sch_1):pwrgd_p1v8_pch_stby"
				( attribute "CDS_PHYS_NET_NAME" "PWRGD_P1V8_PCH_STBY"
					( Origin gPackager )
				)
				( objectStatus "PWRGD_P1V8_PCH_STBY" )
			)
			( signal "@baseboard_fab2_lib.baseboard_fab2(sch_1):pwrgd_pvnn_pch_r"
				( attribute "CDS_PHYS_NET_NAME" "PWRGD_PVNN_PCH_R"
					( Origin gPackager )
				)
				( objectStatus "PWRGD_PVNN_PCH_R" )
			)
			( signal "@baseboard_fab2_lib.baseboard_fab2(sch_1):smb_vr_scl_pvnn_pch"
				( attribute "CDS_PHYS_NET_NAME" "SMB_VR_SCL_PVNN_PCH"
					( Origin gPackager )
				)
				( objectStatus "SMB_VR_SCL_PVNN_PCH" )
			)
			( signal "@baseboard_fab2_lib.baseboard_fab2(sch_1):smb_vr_sda_pvnn_pch"
				( attribute "CDS_PHYS_NET_NAME" "SMB_VR_SDA_PVNN_PCH"
					( Origin gPackager )
				)
				( objectStatus "SMB_VR_SDA_PVNN_PCH" )
			)
			( signal "@baseboard_fab2_lib.baseboard_fab2(sch_1):tp_pvnn_pch_mp2"
				( attribute "CDS_PHYS_NET_NAME" "TP_PVNN_PCH_MP2"
					( Origin gPackager )
				)
				( objectStatus "TP_PVNN_PCH_MP2" )
			)
			( signal "@baseboard_fab2_lib.baseboard_fab2(sch_1):tp_pvnn_pch_mp3"
				( attribute "CDS_PHYS_NET_NAME" "TP_PVNN_PCH_MP3"
					( Origin gPackager )
				)
				( objectStatus "TP_PVNN_PCH_MP3" )
			)
			( signal "@baseboard_fab2_lib.baseboard_fab2(sch_1):tp_pvnn_pch_pinalrt_n"
				( attribute "CDS_PHYS_NET_NAME" "TP_PVNN_PCH_PINALRT_N"
					( Origin gPackager )
				)
				( objectStatus "TP_PVNN_PCH_PINALRT_N" )
			)
			( signal "@baseboard_fab2_lib.baseboard_fab2(sch_1):tp_pvnn_pch_reset_n"
				( attribute "CDS_PHYS_NET_NAME" "TP_PVNN_PCH_RESET_N"
					( Origin gPackager )
				)
				( objectStatus "TP_PVNN_PCH_RESET_N" )
			)
			( signal "@baseboard_fab2_lib.baseboard_fab2(sch_1):tp_pvnn_pch_svid_alert"
				( attribute "CDS_PHYS_NET_NAME" "TP_PVNN_PCH_SVID_ALERT"
					( Origin gPackager )
				)
				( objectStatus "TP_PVNN_PCH_SVID_ALERT" )
			)
			( signal "@baseboard_fab2_lib.baseboard_fab2(sch_1):tp_pvnn_pch_vclk"
				( attribute "CDS_PHYS_NET_NAME" "TP_PVNN_PCH_VCLK"
					( Origin gPackager )
				)
				( objectStatus "TP_PVNN_PCH_VCLK" )
			)
			( signal "@baseboard_fab2_lib.baseboard_fab2(sch_1):tp_pvnn_pch_vdio"
				( attribute "CDS_PHYS_NET_NAME" "TP_PVNN_PCH_VDIO"
					( Origin gPackager )
				)
				( objectStatus "TP_PVNN_PCH_VDIO" )
			)
			( signal "@baseboard_fab2_lib.baseboard_fab2(sch_1):tp_vr_pvnn_pch_aiinsen"
				( attribute "CDS_PHYS_NET_NAME" "TP_VR_PVNN_PCH_AIINSEN"
					( Origin gPackager )
				)
				( objectStatus "TP_VR_PVNN_PCH_AIINSEN" )
			)
			( signal "@baseboard_fab2_lib.baseboard_fab2(sch_1):vr_p1v05_pch_biref1"
				( attribute "CDS_PHYS_NET_NAME" "VR_P1V05_PCH_BIREF1"
					( Origin gPackager )
				)
				( objectStatus "VR_P1V05_PCH_BIREF1" )
			)
			( signal "@baseboard_fab2_lib.baseboard_fab2(sch_1):vr_p1v05_pch_stby_avsp"
				( attribute "CDS_PHYS_NET_NAME" "VR_P1V05_PCH_STBY_AVSP"
					( Origin gPackager )
				)
				( objectStatus "VR_P1V05_PCH_STBY_AVSP" )
			)
			( signal "@baseboard_fab2_lib.baseboard_fab2(sch_1):vr_p1v05_pch_stby_pwm1"
				( attribute "CDS_PHYS_NET_NAME" "VR_P1V05_PCH_STBY_PWM1"
					( Origin gPackager )
				)
				( objectStatus "VR_P1V05_PCH_STBY_PWM1" )
			)
			( signal "@baseboard_fab2_lib.baseboard_fab2(sch_1):vr_pvnn_p1v05_pch_vd12"
				( attribute "CDS_PHYS_NET_NAME" "VR_PVNN_P1V05_PCH_VD12"
					( Origin gPackager )
				)
				( objectStatus "VR_PVNN_P1V05_PCH_VD12" )
			)
			( signal "@baseboard_fab2_lib.baseboard_fab2(sch_1):vr_pvnn_pch_airef1"
				( attribute "CDS_PHYS_NET_NAME" "VR_PVNN_PCH_AIREF1"
					( Origin gPackager )
				)
				( objectStatus "VR_PVNN_PCH_AIREF1" )
			)
			( signal "@baseboard_fab2_lib.baseboard_fab2(sch_1):vr_pvnn_pch_avsp"
				( attribute "CDS_PHYS_NET_NAME" "VR_PVNN_PCH_AVSP"
					( Origin gPackager )
				)
				( objectStatus "VR_PVNN_PCH_AVSP" )
			)
			( signal "@baseboard_fab2_lib.baseboard_fab2(sch_1):vr_pvnn_pch_pwm1"
				( attribute "CDS_PHYS_NET_NAME" "VR_PVNN_PCH_PWM1"
					( Origin gPackager )
				)
				( objectStatus "VR_PVNN_PCH_PWM1" )
			)
			( signal "@baseboard_fab2_lib.baseboard_fab2(sch_1):vr_pvnn_pch_vdd"
				( attribute "CDS_PHYS_NET_NAME" "VR_PVNN_PCH_VDD"
					( Origin gPackager )
				)
				( objectStatus "VR_PVNN_PCH_VDD" )
			)
			( signal "@baseboard_fab2_lib.baseboard_fab2(sch_1):vr_pvnn_pch_vinsen"
				( attribute "CDS_PHYS_NET_NAME" "VR_PVNN_PCH_VINSEN"
					( Origin gPackager )
				)
				( objectStatus "VR_PVNN_PCH_VINSEN" )
			)
			( signal "@baseboard_fab2_lib.baseboard_fab2(sch_1):vr_pvnn_pch_vren"
				( attribute "CDS_PHYS_NET_NAME" "VR_PVNN_PCH_VREN"
					( Origin gPackager )
				)
				( objectStatus "VR_PVNN_PCH_VREN" )
			)
			( signal "@baseboard_fab2_lib.baseboard_fab2(sch_1):vr_pvnn_pch_xaddr1"
				( attribute "CDS_PHYS_NET_NAME" "VR_PVNN_PCH_XADDR1"
					( Origin gPackager )
				)
				( objectStatus "VR_PVNN_PCH_XADDR1" )
			)
			( signal "@baseboard_fab2_lib.baseboard_fab2(sch_1):vr_pvnn_pch_xaddr2"
				( attribute "CDS_PHYS_NET_NAME" "VR_PVNN_PCH_XADDR2"
					( Origin gPackager )
				)
				( objectStatus "VR_PVNN_PCH_XADDR2" )
			)
			( signal "@baseboard_fab2_lib.baseboard_fab2(sch_1):vsense_p1v05_pch_stby_avsn"
				( attribute "CDS_PHYS_NET_NAME" "VSENSE_P1V05_PCH_STBY_AVSN"
					( Origin gPackager )
				)
				( objectStatus "VSENSE_P1V05_PCH_STBY_AVSN" )
			)
			( signal "@baseboard_fab2_lib.baseboard_fab2(sch_1):vsense_p1v05_pch_stby_avsp"
				( attribute "CDS_PHYS_NET_NAME" "VSENSE_P1V05_PCH_STBY_AVSP"
					( Origin gPackager )
				)
				( objectStatus "VSENSE_P1V05_PCH_STBY_AVSP" )
			)
			( signal "@baseboard_fab2_lib.baseboard_fab2(sch_1):vsense_pvnn_pch_stby_avsn"
				( attribute "CDS_PHYS_NET_NAME" "VSENSE_PVNN_PCH_STBY_AVSN"
					( Origin gPackager )
				)
				( objectStatus "VSENSE_PVNN_PCH_STBY_AVSN" )
			)
			( signal "@baseboard_fab2_lib.baseboard_fab2(sch_1):vsense_pvnn_pch_stby_avsp"
				( attribute "CDS_PHYS_NET_NAME" "VSENSE_PVNN_PCH_STBY_AVSP"
					( Origin gPackager )
				)
				( objectStatus "VSENSE_PVNN_PCH_STBY_AVSP" )
			)
			( signal "@baseboard_fab2_lib.baseboard_fab2(sch_1):nc_p1v05_pch_stby_ph1_p31"
				( attribute "CDS_PHYS_NET_NAME" "NC_P1V05_PCH_STBY_PH1_P31"
					( Origin gPackager )
				)
				( objectStatus "NC_P1V05_PCH_STBY_PH1_P31" )
			)
			( signal "@baseboard_fab2_lib.baseboard_fab2(sch_1):nc_pvnn_pch_ph1_p31"
				( attribute "CDS_PHYS_NET_NAME" "NC_PVNN_PCH_PH1_P31"
					( Origin gPackager )
				)
				( objectStatus "NC_PVNN_PCH_PH1_P31" )
			)
			( signal "@baseboard_fab2_lib.baseboard_fab2(sch_1):tp_p1v05_pch_gl_0"
				( attribute "CDS_PHYS_NET_NAME" "TP_P1V05_PCH_GL_0"
					( Origin gPackager )
				)
				( objectStatus "TP_P1V05_PCH_GL_0" )
			)
			( signal "@baseboard_fab2_lib.baseboard_fab2(sch_1):tp_p1v05_pch_gl_1"
				( attribute "CDS_PHYS_NET_NAME" "TP_P1V05_PCH_GL_1"
					( Origin gPackager )
				)
				( objectStatus "TP_P1V05_PCH_GL_1" )
			)
			( signal "@baseboard_fab2_lib.baseboard_fab2(sch_1):tp_pvnn_pch_gl_0"
				( attribute "CDS_PHYS_NET_NAME" "TP_PVNN_PCH_GL_0"
					( Origin gPackager )
				)
				( objectStatus "TP_PVNN_PCH_GL_0" )
			)
			( signal "@baseboard_fab2_lib.baseboard_fab2(sch_1):tp_pvnn_pch_gl_1"
				( attribute "CDS_PHYS_NET_NAME" "TP_PVNN_PCH_GL_1"
					( Origin gPackager )
				)
				( objectStatus "TP_PVNN_PCH_GL_1" )
			)
			( signal "@baseboard_fab2_lib.baseboard_fab2(sch_1):vr_p1v05_pch_stby_ocset"
				( attribute "CDS_PHYS_NET_NAME" "VR_P1V05_PCH_STBY_OCSET"
					( Origin gPackager )
				)
				( objectStatus "VR_P1V05_PCH_STBY_OCSET" )
			)
			( signal "@baseboard_fab2_lib.baseboard_fab2(sch_1):vr_p1v05_pch_stby_ph1_boot"
				( attribute "CDS_PHYS_NET_NAME" "VR_P1V05_PCH_STBY_PH1_BOOT"
					( Origin gPackager )
				)
				( objectStatus "VR_P1V05_PCH_STBY_PH1_BOOT" )
			)
			( signal "@baseboard_fab2_lib.baseboard_fab2(sch_1):vr_p1v05_pch_stby_ph1_phase"
				( attribute "CDS_PHYS_NET_NAME" "VR_P1V05_PCH_STBY_PH1_PHASE"
					( Origin gPackager )
				)
				( objectStatus "VR_P1V05_PCH_STBY_PH1_PHASE" )
			)
			( signal "@baseboard_fab2_lib.baseboard_fab2(sch_1):vr_p1v05_pch_stby_ph1_phase_sw"
				( attribute "CDS_PHYS_NET_NAME" "VR_P1V05_PCH_STBY_PH1_PHASE_SW"
					( Origin gPackager )
				)
				( objectStatus "VR_P1V05_PCH_STBY_PH1_PHASE_SW" )
			)
			( signal "@baseboard_fab2_lib.baseboard_fab2(sch_1):vr_p1v05_pch_stby_ph1_vcin"
				( attribute "CDS_PHYS_NET_NAME" "VR_P1V05_PCH_STBY_PH1_VCIN"
					( Origin gPackager )
				)
				( objectStatus "VR_P1V05_PCH_STBY_PH1_VCIN" )
			)
			( signal "@baseboard_fab2_lib.baseboard_fab2(sch_1):vr_pvnn_pch_ph1_boot"
				( attribute "CDS_PHYS_NET_NAME" "VR_PVNN_PCH_PH1_BOOT"
					( Origin gPackager )
				)
				( objectStatus "VR_PVNN_PCH_PH1_BOOT" )
			)
			( signal "@baseboard_fab2_lib.baseboard_fab2(sch_1):vr_pvnn_pch_ph1_phase"
				( attribute "CDS_PHYS_NET_NAME" "VR_PVNN_PCH_PH1_PHASE"
					( Origin gPackager )
				)
				( objectStatus "VR_PVNN_PCH_PH1_PHASE" )
			)
			( signal "@baseboard_fab2_lib.baseboard_fab2(sch_1):vr_pvnn_pch_ph1_phase_sw"
				( attribute "CDS_PHYS_NET_NAME" "VR_PVNN_PCH_PH1_PHASE_SW"
					( Origin gPackager )
				)
				( objectStatus "VR_PVNN_PCH_PH1_PHASE_SW" )
			)
			( signal "@baseboard_fab2_lib.baseboard_fab2(sch_1):vr_pvnn_pch_ph1_vcin"
				( attribute "CDS_PHYS_NET_NAME" "VR_PVNN_PCH_PH1_VCIN"
					( Origin gPackager )
				)
				( objectStatus "VR_PVNN_PCH_PH1_VCIN" )
			)
			( signal "@baseboard_fab2_lib.baseboard_fab2(sch_1):vr_pvnn_pch_stby_ocset"
				( attribute "CDS_PHYS_NET_NAME" "VR_PVNN_PCH_STBY_OCSET"
					( Origin gPackager )
				)
				( objectStatus "VR_PVNN_PCH_STBY_OCSET" )
			)
			( signal "@baseboard_fab2_lib.baseboard_fab2(sch_1):pwrgd_p1v8_pch_stby_r"
				( attribute "CDS_PHYS_NET_NAME" "PWRGD_P1V8_PCH_STBY_R"
					( Origin gPackager )
				)
				( objectStatus "PWRGD_P1V8_PCH_STBY_R" )
			)
			( signal "@baseboard_fab2_lib.baseboard_fab2(sch_1):vr_p1v8_pch_stby_fb"
				( attribute "CDS_PHYS_NET_NAME" "VR_P1V8_PCH_STBY_FB"
					( Origin gPackager )
				)
				( objectStatus "VR_P1V8_PCH_STBY_FB" )
			)
			( signal "@baseboard_fab2_lib.baseboard_fab2(sch_1):pwrgd_p1v26_bmc_stby_r"
				( attribute "CDS_PHYS_NET_NAME" "PWRGD_P1V26_BMC_STBY_R"
					( Origin gPackager )
				)
				( objectStatus "PWRGD_P1V26_BMC_STBY_R" )
			)
			( signal "@baseboard_fab2_lib.baseboard_fab2(sch_1):pwrgd_p1v538_bmc_stby"
				( attribute "CDS_PHYS_NET_NAME" "PWRGD_P1V538_BMC_STBY"
					( Origin gPackager )
				)
				( objectStatus "PWRGD_P1V538_BMC_STBY" )
			)
			( signal "@baseboard_fab2_lib.baseboard_fab2(sch_1):vr_p1v26_bmc_stby_fb"
				( attribute "CDS_PHYS_NET_NAME" "VR_P1V26_BMC_STBY_FB"
					( Origin gPackager )
				)
				( objectStatus "VR_P1V26_BMC_STBY_FB" )
			)
			( signal "@baseboard_fab2_lib.baseboard_fab2(sch_1):pwrgd_p1v538_bmc_stby_r"
				( attribute "CDS_PHYS_NET_NAME" "PWRGD_P1V538_BMC_STBY_R"
					( Origin gPackager )
				)
				( objectStatus "PWRGD_P1V538_BMC_STBY_R" )
			)
			( signal "@baseboard_fab2_lib.baseboard_fab2(sch_1):vr_p1v538_bmc_stby_fb"
				( attribute "CDS_PHYS_NET_NAME" "VR_P1V538_BMC_STBY_FB"
					( Origin gPackager )
				)
				( objectStatus "VR_P1V538_BMC_STBY_FB" )
			)
			( signal "@baseboard_fab2_lib.baseboard_fab2(sch_1):agnd_p3v3_stby"
				( alias ( signalRef "@baseboard_fab2_lib.baseboard_fab2(sch_1):page240_agnd_p3v3_stby") )
				( attribute "VOLTAGE" "0V"
					( Units "uVoltage" "V" 1.000000)
					( Status sAliasFlattened )
					( Origin gFrontEnd )
				)
				( attribute "CDS_PHYS_NET_NAME" "AGND_P3V3_STBY"
					( Origin gPackager )
				)
				( objectStatus "AGND_P3V3_STBY" )
			)
			( signal "@baseboard_fab2_lib.baseboard_fab2(sch_1):page240_agnd_p3v3_stby"
				( attribute "VOLTAGE" "0V"
					( Units "uVoltage" "V" 1.000000)
					( Origin gFrontEnd )
				)
				( objectFlag fObjectAlias )
				( objectStatus "page240_agnd_p3v3_stby" )
			)
			( signal "@baseboard_fab2_lib.baseboard_fab2(sch_1):pwrgd_p3v3_stby_r"
				( attribute "CDS_PHYS_NET_NAME" "PWRGD_P3V3_STBY_R"
					( Origin gPackager )
				)
				( objectStatus "PWRGD_P3V3_STBY_R" )
			)
			( signal "@baseboard_fab2_lib.baseboard_fab2(sch_1):pwrgd_p5v_stby"
				( attribute "CDS_PHYS_NET_NAME" "PWRGD_P5V_STBY"
					( Origin gPackager )
				)
				( objectStatus "PWRGD_P5V_STBY" )
			)
			( signal "@baseboard_fab2_lib.baseboard_fab2(sch_1):vr_fet_sw_p12v_stby_p3v3_stby"
				( attribute "CDS_PHYS_NET_NAME" "VR_FET_SW_P12V_STBY_P3V3_STBY"
					( Origin gPackager )
				)
				( objectStatus "VR_FET_SW_P12V_STBY_P3V3_STBY" )
			)
			( signal "@baseboard_fab2_lib.baseboard_fab2(sch_1):vr_p3v3_stby_boot"
				( attribute "CDS_PHYS_NET_NAME" "VR_P3V3_STBY_BOOT"
					( Origin gPackager )
				)
				( objectStatus "VR_P3V3_STBY_BOOT" )
			)
			( signal "@baseboard_fab2_lib.baseboard_fab2(sch_1):vr_p3v3_stby_boot_r"
				( attribute "CDS_PHYS_NET_NAME" "VR_P3V3_STBY_BOOT_R"
					( Origin gPackager )
				)
				( objectStatus "VR_P3V3_STBY_BOOT_R" )
			)
			( signal "@baseboard_fab2_lib.baseboard_fab2(sch_1):vr_p3v3_stby_en"
				( attribute "CDS_PHYS_NET_NAME" "VR_P3V3_STBY_EN"
					( Origin gPackager )
				)
				( objectStatus "VR_P3V3_STBY_EN" )
			)
			( signal "@baseboard_fab2_lib.baseboard_fab2(sch_1):vr_p3v3_stby_lgate"
				( attribute "CDS_PHYS_NET_NAME" "VR_P3V3_STBY_LGATE"
					( Origin gPackager )
				)
				( objectStatus "VR_P3V3_STBY_LGATE" )
			)
			( signal "@baseboard_fab2_lib.baseboard_fab2(sch_1):vr_p3v3_stby_ocselect"
				( attribute "CDS_PHYS_NET_NAME" "VR_P3V3_STBY_OCSELECT"
					( Origin gPackager )
				)
				( objectStatus "VR_P3V3_STBY_OCSELECT" )
			)
			( signal "@baseboard_fab2_lib.baseboard_fab2(sch_1):vr_p3v3_stby_phase"
				( attribute "CDS_PHYS_NET_NAME" "VR_P3V3_STBY_PHASE"
					( Origin gPackager )
				)
				( objectStatus "VR_P3V3_STBY_PHASE" )
			)
			( signal "@baseboard_fab2_lib.baseboard_fab2(sch_1):vr_p3v3_stby_snub"
				( attribute "CDS_PHYS_NET_NAME" "VR_P3V3_STBY_SNUB"
					( Origin gPackager )
				)
				( objectStatus "VR_P3V3_STBY_SNUB" )
			)
			( signal "@baseboard_fab2_lib.baseboard_fab2(sch_1):vr_p3v3_stby_ugate"
				( attribute "CDS_PHYS_NET_NAME" "VR_P3V3_STBY_UGATE"
					( Origin gPackager )
				)
				( objectStatus "VR_P3V3_STBY_UGATE" )
			)
			( signal "@baseboard_fab2_lib.baseboard_fab2(sch_1):vsense_p3v3_stby"
				( attribute "CDS_PHYS_NET_NAME" "VSENSE_P3V3_STBY"
					( Origin gPackager )
				)
				( objectStatus "VSENSE_P3V3_STBY" )
			)
			( signal "@baseboard_fab2_lib.baseboard_fab2(sch_1):vsense_rgnd_p3v3_stby"
				( attribute "CDS_PHYS_NET_NAME" "VSENSE_RGND_P3V3_STBY"
					( Origin gPackager )
				)
				( objectStatus "VSENSE_RGND_P3V3_STBY" )
			)
			( signal "@baseboard_fab2_lib.baseboard_fab2(sch_1):vsense_vout_p3v3_stby"
				( attribute "CDS_PHYS_NET_NAME" "VSENSE_VOUT_P3V3_STBY"
					( Origin gPackager )
				)
				( objectStatus "VSENSE_VOUT_P3V3_STBY" )
			)
			( signal "@baseboard_fab2_lib.baseboard_fab2(sch_1):agnd_p5v_stby"
				( alias ( signalRef "@baseboard_fab2_lib.baseboard_fab2(sch_1):page241_agnd_p5v_stby") )
				( attribute "VOLTAGE" "0"
					( Units "uVoltage" "V" 1.000000)
					( Status sAliasFlattened )
					( Origin gFrontEnd )
				)
				( attribute "CDS_PHYS_NET_NAME" "AGND_P5V_STBY"
					( Origin gPackager )
				)
				( objectStatus "AGND_P5V_STBY" )
			)
			( signal "@baseboard_fab2_lib.baseboard_fab2(sch_1):page241_agnd_p5v_stby"
				( attribute "VOLTAGE" "0"
					( Units "uVoltage" "V" 1.000000)
					( Origin gFrontEnd )
				)
				( objectFlag fObjectAlias )
				( objectStatus "page241_agnd_p5v_stby" )
			)
			( signal "@baseboard_fab2_lib.baseboard_fab2(sch_1):pwrgd_p5v_stby_r"
				( attribute "CDS_PHYS_NET_NAME" "PWRGD_P5V_STBY_R"
					( Origin gPackager )
				)
				( objectStatus "PWRGD_P5V_STBY_R" )
			)
			( signal "@baseboard_fab2_lib.baseboard_fab2(sch_1):vr_fet_sw_p5v_stby_pvin"
				( attribute "CDS_PHYS_NET_NAME" "VR_FET_SW_P5V_STBY_PVIN"
					( Origin gPackager )
				)
				( objectStatus "VR_FET_SW_P5V_STBY_PVIN" )
			)
			( signal "@baseboard_fab2_lib.baseboard_fab2(sch_1):vr_p5v_stby_boot"
				( attribute "CDS_PHYS_NET_NAME" "VR_P5V_STBY_BOOT"
					( Origin gPackager )
				)
				( objectStatus "VR_P5V_STBY_BOOT" )
			)
			( signal "@baseboard_fab2_lib.baseboard_fab2(sch_1):vr_p5v_stby_comp"
				( attribute "CDS_PHYS_NET_NAME" "VR_P5V_STBY_COMP"
					( Origin gPackager )
				)
				( objectStatus "VR_P5V_STBY_COMP" )
			)
			( signal "@baseboard_fab2_lib.baseboard_fab2(sch_1):vr_p5v_stby_en"
				( attribute "CDS_PHYS_NET_NAME" "VR_P5V_STBY_EN"
					( Origin gPackager )
				)
				( objectStatus "VR_P5V_STBY_EN" )
			)
			( signal "@baseboard_fab2_lib.baseboard_fab2(sch_1):vr_p5v_stby_phase"
				( attribute "CDS_PHYS_NET_NAME" "VR_P5V_STBY_PHASE"
					( Origin gPackager )
				)
				( objectStatus "VR_P5V_STBY_PHASE" )
			)
			( signal "@baseboard_fab2_lib.baseboard_fab2(sch_1):vr_p5v_stby_rc_comp"
				( attribute "CDS_PHYS_NET_NAME" "VR_P5V_STBY_RC_COMP"
					( Origin gPackager )
				)
				( objectStatus "VR_P5V_STBY_RC_COMP" )
			)
			( signal "@baseboard_fab2_lib.baseboard_fab2(sch_1):vr_p5v_stby_rt"
				( attribute "CDS_PHYS_NET_NAME" "VR_P5V_STBY_RT"
					( Origin gPackager )
				)
				( objectStatus "VR_P5V_STBY_RT" )
			)
			( signal "@baseboard_fab2_lib.baseboard_fab2(sch_1):vr_p5v_stby_ss"
				( attribute "CDS_PHYS_NET_NAME" "VR_P5V_STBY_SS"
					( Origin gPackager )
				)
				( objectStatus "VR_P5V_STBY_SS" )
			)
			( signal "@baseboard_fab2_lib.baseboard_fab2(sch_1):vr_p5v_stby_vin"
				( attribute "CDS_PHYS_NET_NAME" "VR_P5V_STBY_VIN"
					( Origin gPackager )
				)
				( objectStatus "VR_P5V_STBY_VIN" )
			)
			( signal "@baseboard_fab2_lib.baseboard_fab2(sch_1):vr_p5v_stby_vsense"
				( attribute "CDS_PHYS_NET_NAME" "VR_P5V_STBY_VSENSE"
					( Origin gPackager )
				)
				( objectStatus "VR_P5V_STBY_VSENSE" )
			)
			( signal "@baseboard_fab2_lib.baseboard_fab2(sch_1):vr_p5v_stby_vsense_r"
				( attribute "CDS_PHYS_NET_NAME" "VR_P5V_STBY_VSENSE_R"
					( Origin gPackager )
				)
				( objectStatus "VR_P5V_STBY_VSENSE_R" )
			)
			( signal "@baseboard_fab2_lib.baseboard_fab2(sch_1):\unnamed_219_3d01r5f-gp_i126_2\"
				( attribute "CDS_PHYS_NET_NAME" "UNNAMED_219_3D01R5F-GP_I126_2"
					( Origin gPackager )
				)
				( objectStatus "UNNAMED_219_3D01R5F-GP_I126_2" )
			)
			( signal "@baseboard_fab2_lib.baseboard_fab2(sch_1):vr_pvccin_cpu0_ph1_boot_r"
				( attribute "CDS_PHYS_NET_NAME" "VR_PVCCIN_CPU0_PH1_BOOT_R"
					( Origin gPackager )
				)
				( objectStatus "VR_PVCCIN_CPU0_PH1_BOOT_R" )
			)
			( signal "@baseboard_fab2_lib.baseboard_fab2(sch_1):vr_pvccin_cpu0_ph2_boot_r"
				( attribute "CDS_PHYS_NET_NAME" "VR_PVCCIN_CPU0_PH2_BOOT_R"
					( Origin gPackager )
				)
				( objectStatus "VR_PVCCIN_CPU0_PH2_BOOT_R" )
			)
			( signal "@baseboard_fab2_lib.baseboard_fab2(sch_1):\unnamed_208_3d01r5f-gp_i94_2\"
				( attribute "CDS_PHYS_NET_NAME" "UNNAMED_208_3D01R5F-GP_I94_2"
					( Origin gPackager )
				)
				( objectStatus "UNNAMED_208_3D01R5F-GP_I94_2" )
			)
			( signal "@baseboard_fab2_lib.baseboard_fab2(sch_1):vr_pvddq_klm_ph1_boot_r"
				( attribute "CDS_PHYS_NET_NAME" "VR_PVDDQ_KLM_PH1_BOOT_R"
					( Origin gPackager )
				)
				( objectStatus "VR_PVDDQ_KLM_PH1_BOOT_R" )
			)
			( signal "@baseboard_fab2_lib.baseboard_fab2(sch_1):vr_pvddq_klm_ph2_boot_r"
				( attribute "CDS_PHYS_NET_NAME" "VR_PVDDQ_KLM_PH2_BOOT_R"
					( Origin gPackager )
				)
				( objectStatus "VR_PVDDQ_KLM_PH2_BOOT_R" )
			)
			( signal "@baseboard_fab2_lib.baseboard_fab2(sch_1):\unnamed_227_3d01r5f-gp_i124_1\"
				( attribute "CDS_PHYS_NET_NAME" "UNNAMED_227_3D01R5F-GP_I124_1"
					( Origin gPackager )
				)
				( objectStatus "UNNAMED_227_3D01R5F-GP_I124_1" )
			)
			( signal "@baseboard_fab2_lib.baseboard_fab2(sch_1):vr_pvccin_cpu1_ph5_boot_r"
				( attribute "CDS_PHYS_NET_NAME" "VR_PVCCIN_CPU1_PH5_BOOT_R"
					( Origin gPackager )
				)
				( objectStatus "VR_PVCCIN_CPU1_PH5_BOOT_R" )
			)
			( signal "@baseboard_fab2_lib.baseboard_fab2(sch_1):\unnamed_208_3d01r5f-gp_i86_2\"
				( attribute "CDS_PHYS_NET_NAME" "UNNAMED_208_3D01R5F-GP_I86_2"
					( Origin gPackager )
				)
				( objectStatus "UNNAMED_208_3D01R5F-GP_I86_2" )
			)
			( signal "@baseboard_fab2_lib.baseboard_fab2(sch_1):vr_pvccin_cpu1_ph3_boot_r"
				( attribute "CDS_PHYS_NET_NAME" "VR_PVCCIN_CPU1_PH3_BOOT_R"
					( Origin gPackager )
				)
				( objectStatus "VR_PVCCIN_CPU1_PH3_BOOT_R" )
			)
			( signal "@baseboard_fab2_lib.baseboard_fab2(sch_1):vr_pvccin_cpu1_ph4_boot_r"
				( attribute "CDS_PHYS_NET_NAME" "VR_PVCCIN_CPU1_PH4_BOOT_R"
					( Origin gPackager )
				)
				( objectStatus "VR_PVCCIN_CPU1_PH4_BOOT_R" )
			)
			( signal "@baseboard_fab2_lib.baseboard_fab2(sch_1):\unnamed_224_3d01r5f-gp_i129_2\"
				( attribute "CDS_PHYS_NET_NAME" "UNNAMED_224_3D01R5F-GP_I129_2"
					( Origin gPackager )
				)
				( objectStatus "UNNAMED_224_3D01R5F-GP_I129_2" )
			)
			( signal "@baseboard_fab2_lib.baseboard_fab2(sch_1):vr_pvccin_cpu1_ph1_boot_r"
				( attribute "CDS_PHYS_NET_NAME" "VR_PVCCIN_CPU1_PH1_BOOT_R"
					( Origin gPackager )
				)
				( objectStatus "VR_PVCCIN_CPU1_PH1_BOOT_R" )
			)
			( signal "@baseboard_fab2_lib.baseboard_fab2(sch_1):vr_pvddq_ghj_ph1_boot_r"
				( attribute "CDS_PHYS_NET_NAME" "VR_PVDDQ_GHJ_PH1_BOOT_R"
					( Origin gPackager )
				)
				( objectStatus "VR_PVDDQ_GHJ_PH1_BOOT_R" )
			)
			( signal "@baseboard_fab2_lib.baseboard_fab2(sch_1):\unnamed_224_3d01r5f-gp_i119_2\"
				( attribute "CDS_PHYS_NET_NAME" "UNNAMED_224_3D01R5F-GP_I119_2"
					( Origin gPackager )
				)
				( objectStatus "UNNAMED_224_3D01R5F-GP_I119_2" )
			)
			( signal "@baseboard_fab2_lib.baseboard_fab2(sch_1):vr_pvddq_ghj_ph2_boot_r"
				( attribute "CDS_PHYS_NET_NAME" "VR_PVDDQ_GHJ_PH2_BOOT_R"
					( Origin gPackager )
				)
				( objectStatus "VR_PVDDQ_GHJ_PH2_BOOT_R" )
			)
			( signal "@baseboard_fab2_lib.baseboard_fab2(sch_1):\unnamed_203_3d01r5f-gp_i105_2\"
				( attribute "CDS_PHYS_NET_NAME" "UNNAMED_203_3D01R5F-GP_I105_2"
					( Origin gPackager )
				)
				( objectStatus "UNNAMED_203_3D01R5F-GP_I105_2" )
			)
			( signal "@baseboard_fab2_lib.baseboard_fab2(sch_1):vr_pvccin_cpu0_ph5_boot_r"
				( attribute "CDS_PHYS_NET_NAME" "VR_PVCCIN_CPU0_PH5_BOOT_R"
					( Origin gPackager )
				)
				( objectStatus "VR_PVCCIN_CPU0_PH5_BOOT_R" )
			)
			( signal "@baseboard_fab2_lib.baseboard_fab2(sch_1):\unnamed_203_3d01r5f-gp_i102_2\"
				( attribute "CDS_PHYS_NET_NAME" "UNNAMED_203_3D01R5F-GP_I102_2"
					( Origin gPackager )
				)
				( objectStatus "UNNAMED_203_3D01R5F-GP_I102_2" )
			)
			( signal "@baseboard_fab2_lib.baseboard_fab2(sch_1):vr_pvccin_cpu0_ph3_boot_r"
				( attribute "CDS_PHYS_NET_NAME" "VR_PVCCIN_CPU0_PH3_BOOT_R"
					( Origin gPackager )
				)
				( objectStatus "VR_PVCCIN_CPU0_PH3_BOOT_R" )
			)
			( signal "@baseboard_fab2_lib.baseboard_fab2(sch_1):vr_pvddq_def_ph1_boot_r"
				( attribute "CDS_PHYS_NET_NAME" "VR_PVDDQ_DEF_PH1_BOOT_R"
					( Origin gPackager )
				)
				( objectStatus "VR_PVDDQ_DEF_PH1_BOOT_R" )
			)
			( signal "@baseboard_fab2_lib.baseboard_fab2(sch_1):vr_pvddq_def_ph2_boot_r"
				( attribute "CDS_PHYS_NET_NAME" "VR_PVDDQ_DEF_PH2_BOOT_R"
					( Origin gPackager )
				)
				( objectStatus "VR_PVDDQ_DEF_PH2_BOOT_R" )
			)
			( signal "@baseboard_fab2_lib.baseboard_fab2(sch_1):\unnamed_216_3d01r5f-gp_i123_2\"
				( attribute "CDS_PHYS_NET_NAME" "UNNAMED_216_3D01R5F-GP_I123_2"
					( Origin gPackager )
				)
				( objectStatus "UNNAMED_216_3D01R5F-GP_I123_2" )
			)
			( signal "@baseboard_fab2_lib.baseboard_fab2(sch_1):\unnamed_210_3d01r5f-gp_i59_2\"
				( attribute "CDS_PHYS_NET_NAME" "UNNAMED_210_3D01R5F-GP_I59_2"
					( Origin gPackager )
				)
				( objectStatus "UNNAMED_210_3D01R5F-GP_I59_2" )
			)
			( signal "@baseboard_fab2_lib.baseboard_fab2(sch_1):vr_pvddq_abc_ph1_boot_r"
				( attribute "CDS_PHYS_NET_NAME" "VR_PVDDQ_ABC_PH1_BOOT_R"
					( Origin gPackager )
				)
				( objectStatus "VR_PVDDQ_ABC_PH1_BOOT_R" )
			)
			( signal "@baseboard_fab2_lib.baseboard_fab2(sch_1):vr_pvddq_abc_ph2_boot_r"
				( attribute "CDS_PHYS_NET_NAME" "VR_PVDDQ_ABC_PH2_BOOT_R"
					( Origin gPackager )
				)
				( objectStatus "VR_PVDDQ_ABC_PH2_BOOT_R" )
			)
			( signal "@baseboard_fab2_lib.baseboard_fab2(sch_1):\unnamed_205_3d01r5f-gp_i68_2\"
				( attribute "CDS_PHYS_NET_NAME" "UNNAMED_205_3D01R5F-GP_I68_2"
					( Origin gPackager )
				)
				( objectStatus "UNNAMED_205_3D01R5F-GP_I68_2" )
			)
			( signal "@baseboard_fab2_lib.baseboard_fab2(sch_1):vr_pvsa_cpu1_boot_r"
				( attribute "CDS_PHYS_NET_NAME" "VR_PVSA_CPU1_BOOT_R"
					( Origin gPackager )
				)
				( objectStatus "VR_PVSA_CPU1_BOOT_R" )
			)
			( signal "@baseboard_fab2_lib.baseboard_fab2(sch_1):vr_pvsa_cpu0_boot_r"
				( attribute "CDS_PHYS_NET_NAME" "VR_PVSA_CPU0_BOOT_R"
					( Origin gPackager )
				)
				( objectStatus "VR_PVSA_CPU0_BOOT_R" )
			)
			( signal "@baseboard_fab2_lib.baseboard_fab2(sch_1):vr_pvccio_cpu1_ph1_boot_r"
				( attribute "CDS_PHYS_NET_NAME" "VR_PVCCIO_CPU1_PH1_BOOT_R"
					( Origin gPackager )
				)
				( objectStatus "VR_PVCCIO_CPU1_PH1_BOOT_R" )
			)
			( signal "@baseboard_fab2_lib.baseboard_fab2(sch_1):vr_p1v05_pch_stby_ph1_boot_r"
				( attribute "CDS_PHYS_NET_NAME" "VR_P1V05_PCH_STBY_PH1_BOOT_R"
					( Origin gPackager )
				)
				( objectStatus "VR_P1V05_PCH_STBY_PH1_BOOT_R" )
			)
			( signal "@baseboard_fab2_lib.baseboard_fab2(sch_1):vr_pvnn_pch_ph1_boot_r"
				( attribute "CDS_PHYS_NET_NAME" "VR_PVNN_PCH_PH1_BOOT_R"
					( Origin gPackager )
				)
				( objectStatus "VR_PVNN_PCH_PH1_BOOT_R" )
			)
			( signal "@baseboard_fab2_lib.baseboard_fab2(sch_1):\unnamed_212_3d01r5f-gp_i112_2\"
				( attribute "CDS_PHYS_NET_NAME" "UNNAMED_212_3D01R5F-GP_I112_2"
					( Origin gPackager )
				)
				( objectStatus "UNNAMED_212_3D01R5F-GP_I112_2" )
			)
			( signal "@baseboard_fab2_lib.baseboard_fab2(sch_1):\unnamed_236_3d01r5f-gp_i132_2\"
				( attribute "CDS_PHYS_NET_NAME" "UNNAMED_236_3D01R5F-GP_I132_2"
					( Origin gPackager )
				)
				( objectStatus "UNNAMED_236_3D01R5F-GP_I132_2" )
			)
			( signal "@baseboard_fab2_lib.baseboard_fab2(sch_1):vr_pvccio_cpu0_ph1_boot_r"
				( attribute "CDS_PHYS_NET_NAME" "VR_PVCCIO_CPU0_PH1_BOOT_R"
					( Origin gPackager )
				)
				( objectStatus "VR_PVCCIO_CPU0_PH1_BOOT_R" )
			)
			( signal "@baseboard_fab2_lib.baseboard_fab2(sch_1):vr_pvccin_cpu1_ph2_boot_r"
				( attribute "CDS_PHYS_NET_NAME" "VR_PVCCIN_CPU1_PH2_BOOT_R"
					( Origin gPackager )
				)
				( objectStatus "VR_PVCCIN_CPU1_PH2_BOOT_R" )
			)
			( signal "@baseboard_fab2_lib.baseboard_fab2(sch_1):\unnamed_227_3d01r5f-gp_i125_1\"
				( attribute "CDS_PHYS_NET_NAME" "UNNAMED_227_3D01R5F-GP_I125_1"
					( Origin gPackager )
				)
				( objectStatus "UNNAMED_227_3D01R5F-GP_I125_1" )
			)
			( signal "@baseboard_fab2_lib.baseboard_fab2(sch_1):vr_pvccin_cpu0_ph4_boot_r"
				( attribute "CDS_PHYS_NET_NAME" "VR_PVCCIN_CPU0_PH4_BOOT_R"
					( Origin gPackager )
				)
				( objectStatus "VR_PVCCIN_CPU0_PH4_BOOT_R" )
			)
			( signal "@baseboard_fab2_lib.baseboard_fab2(sch_1):p3e_cpu0_pe1_pch_con_rxn(8)"
				( attribute "CDS_PHYS_NET_NAME" "P3E_CPU0_PE1_PCH_CON_RXN<8>"
					( Origin gPackager )
				)
				( attribute "PNN" "P3E_CPU0_PE1_PCH_CON_RXN<8>"
					( Origin gPackager )
				)
				( objectStatus "P3E_CPU0_PE1_PCH_CON_RXN<8>" )
			)
			( signal "@baseboard_fab2_lib.baseboard_fab2(sch_1):p3e_cpu0_pe1_pch_con_rxn(9)"
				( attribute "CDS_PHYS_NET_NAME" "P3E_CPU0_PE1_PCH_CON_RXN<9>"
					( Origin gPackager )
				)
				( attribute "PNN" "P3E_CPU0_PE1_PCH_CON_RXN<9>"
					( Origin gPackager )
				)
				( objectStatus "P3E_CPU0_PE1_PCH_CON_RXN<9>" )
			)
			( signal "@baseboard_fab2_lib.baseboard_fab2(sch_1):p3e_cpu0_pe1_pch_con_rxn(10)"
				( attribute "CDS_PHYS_NET_NAME" "P3E_CPU0_PE1_PCH_CON_RXN<10>"
					( Origin gPackager )
				)
				( attribute "PNN" "P3E_CPU0_PE1_PCH_CON_RXN<10>"
					( Origin gPackager )
				)
				( objectStatus "P3E_CPU0_PE1_PCH_CON_RXN<10>" )
			)
			( signal "@baseboard_fab2_lib.baseboard_fab2(sch_1):p3e_cpu0_pe1_pch_con_rxn(11)"
				( attribute "CDS_PHYS_NET_NAME" "P3E_CPU0_PE1_PCH_CON_RXN<11>"
					( Origin gPackager )
				)
				( attribute "PNN" "P3E_CPU0_PE1_PCH_CON_RXN<11>"
					( Origin gPackager )
				)
				( objectStatus "P3E_CPU0_PE1_PCH_CON_RXN<11>" )
			)
			( signal "@baseboard_fab2_lib.baseboard_fab2(sch_1):p3e_cpu0_pe1_pch_con_rxn(12)"
				( attribute "CDS_PHYS_NET_NAME" "P3E_CPU0_PE1_PCH_CON_RXN<12>"
					( Origin gPackager )
				)
				( attribute "PNN" "P3E_CPU0_PE1_PCH_CON_RXN<12>"
					( Origin gPackager )
				)
				( objectStatus "P3E_CPU0_PE1_PCH_CON_RXN<12>" )
			)
			( signal "@baseboard_fab2_lib.baseboard_fab2(sch_1):p3e_cpu0_pe1_pch_con_rxn(13)"
				( attribute "CDS_PHYS_NET_NAME" "P3E_CPU0_PE1_PCH_CON_RXN<13>"
					( Origin gPackager )
				)
				( attribute "PNN" "P3E_CPU0_PE1_PCH_CON_RXN<13>"
					( Origin gPackager )
				)
				( objectStatus "P3E_CPU0_PE1_PCH_CON_RXN<13>" )
			)
			( signal "@baseboard_fab2_lib.baseboard_fab2(sch_1):p3e_cpu0_pe1_pch_con_rxn(14)"
				( attribute "CDS_PHYS_NET_NAME" "P3E_CPU0_PE1_PCH_CON_RXN<14>"
					( Origin gPackager )
				)
				( attribute "PNN" "P3E_CPU0_PE1_PCH_CON_RXN<14>"
					( Origin gPackager )
				)
				( objectStatus "P3E_CPU0_PE1_PCH_CON_RXN<14>" )
			)
			( signal "@baseboard_fab2_lib.baseboard_fab2(sch_1):p3e_cpu0_pe1_pch_con_rxn(15)"
				( attribute "CDS_PHYS_NET_NAME" "P3E_CPU0_PE1_PCH_CON_RXN<15>"
					( Origin gPackager )
				)
				( attribute "PNN" "P3E_CPU0_PE1_PCH_CON_RXN<15>"
					( Origin gPackager )
				)
				( objectStatus "P3E_CPU0_PE1_PCH_CON_RXN<15>" )
			)
			( signal "@baseboard_fab2_lib.baseboard_fab2(sch_1):p3e_cpu0_pe1_pch_con_rxp(8)"
				( attribute "CDS_PHYS_NET_NAME" "P3E_CPU0_PE1_PCH_CON_RXP<8>"
					( Origin gPackager )
				)
				( attribute "PNN" "P3E_CPU0_PE1_PCH_CON_RXP<8>"
					( Origin gPackager )
				)
				( objectStatus "P3E_CPU0_PE1_PCH_CON_RXP<8>" )
			)
			( signal "@baseboard_fab2_lib.baseboard_fab2(sch_1):p3e_cpu0_pe1_pch_con_rxp(9)"
				( attribute "CDS_PHYS_NET_NAME" "P3E_CPU0_PE1_PCH_CON_RXP<9>"
					( Origin gPackager )
				)
				( attribute "PNN" "P3E_CPU0_PE1_PCH_CON_RXP<9>"
					( Origin gPackager )
				)
				( objectStatus "P3E_CPU0_PE1_PCH_CON_RXP<9>" )
			)
			( signal "@baseboard_fab2_lib.baseboard_fab2(sch_1):p3e_cpu0_pe1_pch_con_rxp(10)"
				( attribute "CDS_PHYS_NET_NAME" "P3E_CPU0_PE1_PCH_CON_RXP<10>"
					( Origin gPackager )
				)
				( attribute "PNN" "P3E_CPU0_PE1_PCH_CON_RXP<10>"
					( Origin gPackager )
				)
				( objectStatus "P3E_CPU0_PE1_PCH_CON_RXP<10>" )
			)
			( signal "@baseboard_fab2_lib.baseboard_fab2(sch_1):p3e_cpu0_pe1_pch_con_rxp(11)"
				( attribute "CDS_PHYS_NET_NAME" "P3E_CPU0_PE1_PCH_CON_RXP<11>"
					( Origin gPackager )
				)
				( attribute "PNN" "P3E_CPU0_PE1_PCH_CON_RXP<11>"
					( Origin gPackager )
				)
				( objectStatus "P3E_CPU0_PE1_PCH_CON_RXP<11>" )
			)
			( signal "@baseboard_fab2_lib.baseboard_fab2(sch_1):p3e_cpu0_pe1_pch_con_rxp(12)"
				( attribute "CDS_PHYS_NET_NAME" "P3E_CPU0_PE1_PCH_CON_RXP<12>"
					( Origin gPackager )
				)
				( attribute "PNN" "P3E_CPU0_PE1_PCH_CON_RXP<12>"
					( Origin gPackager )
				)
				( objectStatus "P3E_CPU0_PE1_PCH_CON_RXP<12>" )
			)
			( signal "@baseboard_fab2_lib.baseboard_fab2(sch_1):p3e_cpu0_pe1_pch_con_rxp(13)"
				( attribute "CDS_PHYS_NET_NAME" "P3E_CPU0_PE1_PCH_CON_RXP<13>"
					( Origin gPackager )
				)
				( attribute "PNN" "P3E_CPU0_PE1_PCH_CON_RXP<13>"
					( Origin gPackager )
				)
				( objectStatus "P3E_CPU0_PE1_PCH_CON_RXP<13>" )
			)
			( signal "@baseboard_fab2_lib.baseboard_fab2(sch_1):p3e_cpu0_pe1_pch_con_rxp(14)"
				( attribute "CDS_PHYS_NET_NAME" "P3E_CPU0_PE1_PCH_CON_RXP<14>"
					( Origin gPackager )
				)
				( attribute "PNN" "P3E_CPU0_PE1_PCH_CON_RXP<14>"
					( Origin gPackager )
				)
				( objectStatus "P3E_CPU0_PE1_PCH_CON_RXP<14>" )
			)
			( signal "@baseboard_fab2_lib.baseboard_fab2(sch_1):p3e_cpu0_pe1_pch_con_rxp(15)"
				( attribute "CDS_PHYS_NET_NAME" "P3E_CPU0_PE1_PCH_CON_RXP<15>"
					( Origin gPackager )
				)
				( attribute "PNN" "P3E_CPU0_PE1_PCH_CON_RXP<15>"
					( Origin gPackager )
				)
				( objectStatus "P3E_CPU0_PE1_PCH_CON_RXP<15>" )
			)
			( signal "@baseboard_fab2_lib.baseboard_fab2(sch_1):p3e_cpu0_pe1_pch_con_txn(8)"
				( attribute "CDS_PHYS_NET_NAME" "P3E_CPU0_PE1_PCH_CON_TXN<8>"
					( Origin gPackager )
				)
				( attribute "PNN" "P3E_CPU0_PE1_PCH_CON_TXN<8>"
					( Origin gPackager )
				)
				( objectStatus "P3E_CPU0_PE1_PCH_CON_TXN<8>" )
			)
			( signal "@baseboard_fab2_lib.baseboard_fab2(sch_1):p3e_cpu0_pe1_pch_con_txn(9)"
				( attribute "CDS_PHYS_NET_NAME" "P3E_CPU0_PE1_PCH_CON_TXN<9>"
					( Origin gPackager )
				)
				( attribute "PNN" "P3E_CPU0_PE1_PCH_CON_TXN<9>"
					( Origin gPackager )
				)
				( objectStatus "P3E_CPU0_PE1_PCH_CON_TXN<9>" )
			)
			( signal "@baseboard_fab2_lib.baseboard_fab2(sch_1):p3e_cpu0_pe1_pch_con_txn(10)"
				( attribute "CDS_PHYS_NET_NAME" "P3E_CPU0_PE1_PCH_CON_TXN<10>"
					( Origin gPackager )
				)
				( attribute "PNN" "P3E_CPU0_PE1_PCH_CON_TXN<10>"
					( Origin gPackager )
				)
				( objectStatus "P3E_CPU0_PE1_PCH_CON_TXN<10>" )
			)
			( signal "@baseboard_fab2_lib.baseboard_fab2(sch_1):p3e_cpu0_pe1_pch_con_txn(11)"
				( attribute "CDS_PHYS_NET_NAME" "P3E_CPU0_PE1_PCH_CON_TXN<11>"
					( Origin gPackager )
				)
				( attribute "PNN" "P3E_CPU0_PE1_PCH_CON_TXN<11>"
					( Origin gPackager )
				)
				( objectStatus "P3E_CPU0_PE1_PCH_CON_TXN<11>" )
			)
			( signal "@baseboard_fab2_lib.baseboard_fab2(sch_1):p3e_cpu0_pe1_pch_con_txn(12)"
				( attribute "CDS_PHYS_NET_NAME" "P3E_CPU0_PE1_PCH_CON_TXN<12>"
					( Origin gPackager )
				)
				( attribute "PNN" "P3E_CPU0_PE1_PCH_CON_TXN<12>"
					( Origin gPackager )
				)
				( objectStatus "P3E_CPU0_PE1_PCH_CON_TXN<12>" )
			)
			( signal "@baseboard_fab2_lib.baseboard_fab2(sch_1):p3e_cpu0_pe1_pch_con_txn(13)"
				( attribute "CDS_PHYS_NET_NAME" "P3E_CPU0_PE1_PCH_CON_TXN<13>"
					( Origin gPackager )
				)
				( attribute "PNN" "P3E_CPU0_PE1_PCH_CON_TXN<13>"
					( Origin gPackager )
				)
				( objectStatus "P3E_CPU0_PE1_PCH_CON_TXN<13>" )
			)
			( signal "@baseboard_fab2_lib.baseboard_fab2(sch_1):p3e_cpu0_pe1_pch_con_txn(14)"
				( attribute "CDS_PHYS_NET_NAME" "P3E_CPU0_PE1_PCH_CON_TXN<14>"
					( Origin gPackager )
				)
				( attribute "PNN" "P3E_CPU0_PE1_PCH_CON_TXN<14>"
					( Origin gPackager )
				)
				( objectStatus "P3E_CPU0_PE1_PCH_CON_TXN<14>" )
			)
			( signal "@baseboard_fab2_lib.baseboard_fab2(sch_1):p3e_cpu0_pe1_pch_con_txn(15)"
				( attribute "CDS_PHYS_NET_NAME" "P3E_CPU0_PE1_PCH_CON_TXN<15>"
					( Origin gPackager )
				)
				( attribute "PNN" "P3E_CPU0_PE1_PCH_CON_TXN<15>"
					( Origin gPackager )
				)
				( objectStatus "P3E_CPU0_PE1_PCH_CON_TXN<15>" )
			)
			( signal "@baseboard_fab2_lib.baseboard_fab2(sch_1):p3e_cpu0_pe1_pch_con_txp(8)"
				( attribute "CDS_PHYS_NET_NAME" "P3E_CPU0_PE1_PCH_CON_TXP<8>"
					( Origin gPackager )
				)
				( attribute "PNN" "P3E_CPU0_PE1_PCH_CON_TXP<8>"
					( Origin gPackager )
				)
				( objectStatus "P3E_CPU0_PE1_PCH_CON_TXP<8>" )
			)
			( signal "@baseboard_fab2_lib.baseboard_fab2(sch_1):p3e_cpu0_pe1_pch_con_txp(9)"
				( attribute "CDS_PHYS_NET_NAME" "P3E_CPU0_PE1_PCH_CON_TXP<9>"
					( Origin gPackager )
				)
				( attribute "PNN" "P3E_CPU0_PE1_PCH_CON_TXP<9>"
					( Origin gPackager )
				)
				( objectStatus "P3E_CPU0_PE1_PCH_CON_TXP<9>" )
			)
			( signal "@baseboard_fab2_lib.baseboard_fab2(sch_1):p3e_cpu0_pe1_pch_con_txp(10)"
				( attribute "CDS_PHYS_NET_NAME" "P3E_CPU0_PE1_PCH_CON_TXP<10>"
					( Origin gPackager )
				)
				( attribute "PNN" "P3E_CPU0_PE1_PCH_CON_TXP<10>"
					( Origin gPackager )
				)
				( objectStatus "P3E_CPU0_PE1_PCH_CON_TXP<10>" )
			)
			( signal "@baseboard_fab2_lib.baseboard_fab2(sch_1):p3e_cpu0_pe1_pch_con_txp(11)"
				( attribute "CDS_PHYS_NET_NAME" "P3E_CPU0_PE1_PCH_CON_TXP<11>"
					( Origin gPackager )
				)
				( attribute "PNN" "P3E_CPU0_PE1_PCH_CON_TXP<11>"
					( Origin gPackager )
				)
				( objectStatus "P3E_CPU0_PE1_PCH_CON_TXP<11>" )
			)
			( signal "@baseboard_fab2_lib.baseboard_fab2(sch_1):p3e_cpu0_pe1_pch_con_txp(12)"
				( attribute "CDS_PHYS_NET_NAME" "P3E_CPU0_PE1_PCH_CON_TXP<12>"
					( Origin gPackager )
				)
				( attribute "PNN" "P3E_CPU0_PE1_PCH_CON_TXP<12>"
					( Origin gPackager )
				)
				( objectStatus "P3E_CPU0_PE1_PCH_CON_TXP<12>" )
			)
			( signal "@baseboard_fab2_lib.baseboard_fab2(sch_1):p3e_cpu0_pe1_pch_con_txp(13)"
				( attribute "CDS_PHYS_NET_NAME" "P3E_CPU0_PE1_PCH_CON_TXP<13>"
					( Origin gPackager )
				)
				( attribute "PNN" "P3E_CPU0_PE1_PCH_CON_TXP<13>"
					( Origin gPackager )
				)
				( objectStatus "P3E_CPU0_PE1_PCH_CON_TXP<13>" )
			)
			( signal "@baseboard_fab2_lib.baseboard_fab2(sch_1):p3e_cpu0_pe1_pch_con_txp(14)"
				( attribute "CDS_PHYS_NET_NAME" "P3E_CPU0_PE1_PCH_CON_TXP<14>"
					( Origin gPackager )
				)
				( attribute "PNN" "P3E_CPU0_PE1_PCH_CON_TXP<14>"
					( Origin gPackager )
				)
				( objectStatus "P3E_CPU0_PE1_PCH_CON_TXP<14>" )
			)
			( signal "@baseboard_fab2_lib.baseboard_fab2(sch_1):p3e_cpu0_pe1_pch_con_txp(15)"
				( attribute "CDS_PHYS_NET_NAME" "P3E_CPU0_PE1_PCH_CON_TXP<15>"
					( Origin gPackager )
				)
				( attribute "PNN" "P3E_CPU0_PE1_PCH_CON_TXP<15>"
					( Origin gPackager )
				)
				( objectStatus "P3E_CPU0_PE1_PCH_CON_TXP<15>" )
			)
			( signal "@baseboard_fab2_lib.baseboard_fab2(sch_1):uv_high_set_n"
				( attribute "CDS_PHYS_NET_NAME" "UV_HIGH_SET_N"
					( Origin gPackager )
				)
				( objectStatus "UV_HIGH_SET_N" )
			)
			( signal "@baseboard_fab2_lib.baseboard_fab2(sch_1):bmc_uv_high_set"
				( attribute "CDS_PHYS_NET_NAME" "BMC_UV_HIGH_SET"
					( Origin gPackager )
				)
				( objectStatus "BMC_UV_HIGH_SET" )
			)
			( signal "@baseboard_fab2_lib.baseboard_fab2(sch_1):pca9555_a0"
				( attribute "CDS_PHYS_NET_NAME" "PCA9555_A0"
					( Origin gPackager )
				)
				( objectStatus "PCA9555_A0" )
			)
			( signal "@baseboard_fab2_lib.baseboard_fab2(sch_1):pca9555_a1"
				( attribute "CDS_PHYS_NET_NAME" "PCA9555_A1"
					( Origin gPackager )
				)
				( objectStatus "PCA9555_A1" )
			)
			( signal "@baseboard_fab2_lib.baseboard_fab2(sch_1):pca9555_a2"
				( attribute "CDS_PHYS_NET_NAME" "PCA9555_A2"
					( Origin gPackager )
				)
				( objectStatus "PCA9555_A2" )
			)
			( signal "@baseboard_fab2_lib.baseboard_fab2(sch_1):pca9555_int_n"
				( attribute "CDS_PHYS_NET_NAME" "PCA9555_INT_N"
					( Origin gPackager )
				)
				( objectStatus "PCA9555_INT_N" )
			)
			( signal "@baseboard_fab2_lib.baseboard_fab2(sch_1):uart_select_q"
				( attribute "CDS_PHYS_NET_NAME" "UART_SELECT_Q"
					( Origin gPackager )
				)
				( objectStatus "UART_SELECT_Q" )
			)
			( signal "@baseboard_fab2_lib.baseboard_fab2(sch_1):\spa_mid_dbg1__rx\"
				( attribute "CDS_PHYS_NET_NAME" "SPA_MID_DBG1__RX"
					( Origin gPackager )
				)
				( objectStatus "SPA_MID_DBG1__RX" )
			)
			( signal "@baseboard_fab2_lib.baseboard_fab2(sch_1):spa_mid_dbg2_rx"
				( attribute "CDS_PHYS_NET_NAME" "SPA_MID_DBG2_RX"
					( Origin gPackager )
				)
				( objectStatus "SPA_MID_DBG2_RX" )
			)
			( signal "@baseboard_fab2_lib.baseboard_fab2(sch_1):bmc_tpm_hw_c_rst"
				( attribute "CDS_PHYS_NET_NAME" "BMC_TPM_HW_C_RST"
					( Origin gPackager )
				)
				( objectStatus "BMC_TPM_HW_C_RST" )
			)
			( signal "@baseboard_fab2_lib.baseboard_fab2(sch_1):bmc_tpm_hw_rst"
				( attribute "CDS_PHYS_NET_NAME" "BMC_TPM_HW_RST"
					( Origin gPackager )
				)
				( objectStatus "BMC_TPM_HW_RST" )
			)
			( signal "@baseboard_fab2_lib.baseboard_fab2(sch_1):fm_tpm_pres_rst"
				( attribute "CDS_PHYS_NET_NAME" "FM_TPM_PRES_RST"
					( Origin gPackager )
				)
				( objectStatus "FM_TPM_PRES_RST" )
			)
			( signal "@baseboard_fab2_lib.baseboard_fab2(sch_1):fm_tpm_pres_rst_n"
				( attribute "CDS_PHYS_NET_NAME" "FM_TPM_PRES_RST_N"
					( Origin gPackager )
				)
				( objectStatus "FM_TPM_PRES_RST_N" )
			)
			( signal "@baseboard_fab2_lib.baseboard_fab2(sch_1):vref_2v2"
				( attribute "CDS_PHYS_NET_NAME" "VREF_2V2"
					( Origin gPackager )
				)
				( objectStatus "VREF_2V2" )
			)
			( signal "@baseboard_fab2_lib.baseboard_fab2(sch_1):bmc_m_a0"
				( attribute "CDS_PHYS_NET_NAME" "BMC_M_A0"
					( Origin gPackager )
				)
				( objectStatus "BMC_M_A0" )
			)
			( signal "@baseboard_fab2_lib.baseboard_fab2(sch_1):bmc_m_a1"
				( attribute "CDS_PHYS_NET_NAME" "BMC_M_A1"
					( Origin gPackager )
				)
				( objectStatus "BMC_M_A1" )
			)
			( signal "@baseboard_fab2_lib.baseboard_fab2(sch_1):bmc_m_a10"
				( attribute "CDS_PHYS_NET_NAME" "BMC_M_A10"
					( Origin gPackager )
				)
				( objectStatus "BMC_M_A10" )
			)
			( signal "@baseboard_fab2_lib.baseboard_fab2(sch_1):bmc_m_a11"
				( attribute "CDS_PHYS_NET_NAME" "BMC_M_A11"
					( Origin gPackager )
				)
				( objectStatus "BMC_M_A11" )
			)
			( signal "@baseboard_fab2_lib.baseboard_fab2(sch_1):bmc_m_a12"
				( attribute "CDS_PHYS_NET_NAME" "BMC_M_A12"
					( Origin gPackager )
				)
				( objectStatus "BMC_M_A12" )
			)
			( signal "@baseboard_fab2_lib.baseboard_fab2(sch_1):bmc_m_a13"
				( attribute "CDS_PHYS_NET_NAME" "BMC_M_A13"
					( Origin gPackager )
				)
				( objectStatus "BMC_M_A13" )
			)
			( signal "@baseboard_fab2_lib.baseboard_fab2(sch_1):bmc_m_a2"
				( attribute "CDS_PHYS_NET_NAME" "BMC_M_A2"
					( Origin gPackager )
				)
				( objectStatus "BMC_M_A2" )
			)
			( signal "@baseboard_fab2_lib.baseboard_fab2(sch_1):bmc_m_a3"
				( attribute "CDS_PHYS_NET_NAME" "BMC_M_A3"
					( Origin gPackager )
				)
				( objectStatus "BMC_M_A3" )
			)
			( signal "@baseboard_fab2_lib.baseboard_fab2(sch_1):bmc_m_a4"
				( attribute "CDS_PHYS_NET_NAME" "BMC_M_A4"
					( Origin gPackager )
				)
				( objectStatus "BMC_M_A4" )
			)
			( signal "@baseboard_fab2_lib.baseboard_fab2(sch_1):bmc_m_a5"
				( attribute "CDS_PHYS_NET_NAME" "BMC_M_A5"
					( Origin gPackager )
				)
				( objectStatus "BMC_M_A5" )
			)
			( signal "@baseboard_fab2_lib.baseboard_fab2(sch_1):bmc_m_a6"
				( attribute "CDS_PHYS_NET_NAME" "BMC_M_A6"
					( Origin gPackager )
				)
				( objectStatus "BMC_M_A6" )
			)
			( signal "@baseboard_fab2_lib.baseboard_fab2(sch_1):bmc_m_a7"
				( attribute "CDS_PHYS_NET_NAME" "BMC_M_A7"
					( Origin gPackager )
				)
				( objectStatus "BMC_M_A7" )
			)
			( signal "@baseboard_fab2_lib.baseboard_fab2(sch_1):bmc_m_a8"
				( attribute "CDS_PHYS_NET_NAME" "BMC_M_A8"
					( Origin gPackager )
				)
				( objectStatus "BMC_M_A8" )
			)
			( signal "@baseboard_fab2_lib.baseboard_fab2(sch_1):bmc_m_a9"
				( attribute "CDS_PHYS_NET_NAME" "BMC_M_A9"
					( Origin gPackager )
				)
				( objectStatus "BMC_M_A9" )
			)
			( signal "@baseboard_fab2_lib.baseboard_fab2(sch_1):bmc_m_ba0"
				( attribute "CDS_PHYS_NET_NAME" "BMC_M_BA0"
					( Origin gPackager )
				)
				( objectStatus "BMC_M_BA0" )
			)
			( signal "@baseboard_fab2_lib.baseboard_fab2(sch_1):bmc_m_ba1"
				( attribute "CDS_PHYS_NET_NAME" "BMC_M_BA1"
					( Origin gPackager )
				)
				( objectStatus "BMC_M_BA1" )
			)
			( signal "@baseboard_fab2_lib.baseboard_fab2(sch_1):bmc_m_bg0"
				( attribute "CDS_PHYS_NET_NAME" "BMC_M_BG0"
					( Origin gPackager )
				)
				( objectStatus "BMC_M_BG0" )
			)
			( signal "@baseboard_fab2_lib.baseboard_fab2(sch_1):bmc_m_cas_n"
				( attribute "CDS_PHYS_NET_NAME" "BMC_M_CAS_N"
					( Origin gPackager )
				)
				( objectStatus "BMC_M_CAS_N" )
			)
			( signal "@baseboard_fab2_lib.baseboard_fab2(sch_1):bmc_m_cke"
				( attribute "CDS_PHYS_NET_NAME" "BMC_M_CKE"
					( Origin gPackager )
				)
				( objectStatus "BMC_M_CKE" )
			)
			( signal "@baseboard_fab2_lib.baseboard_fab2(sch_1):bmc_m_clk_dn"
				( attribute "CDS_PHYS_NET_NAME" "BMC_M_CLK_DN"
					( Origin gPackager )
				)
				( objectStatus "BMC_M_CLK_DN" )
			)
			( signal "@baseboard_fab2_lib.baseboard_fab2(sch_1):bmc_m_clk_dp"
				( attribute "CDS_PHYS_NET_NAME" "BMC_M_CLK_DP"
					( Origin gPackager )
				)
				( objectStatus "BMC_M_CLK_DP" )
			)
			( signal "@baseboard_fab2_lib.baseboard_fab2(sch_1):bmc_m_cs_n"
				( attribute "CDS_PHYS_NET_NAME" "BMC_M_CS_N"
					( Origin gPackager )
				)
				( objectStatus "BMC_M_CS_N" )
			)
			( signal "@baseboard_fab2_lib.baseboard_fab2(sch_1):bmc_m_dm0"
				( attribute "CDS_PHYS_NET_NAME" "BMC_M_DM0"
					( Origin gPackager )
				)
				( objectStatus "BMC_M_DM0" )
			)
			( signal "@baseboard_fab2_lib.baseboard_fab2(sch_1):bmc_m_dm1"
				( attribute "CDS_PHYS_NET_NAME" "BMC_M_DM1"
					( Origin gPackager )
				)
				( objectStatus "BMC_M_DM1" )
			)
			( signal "@baseboard_fab2_lib.baseboard_fab2(sch_1):bmc_m_dq0"
				( attribute "CDS_PHYS_NET_NAME" "BMC_M_DQ0"
					( Origin gPackager )
				)
				( objectStatus "BMC_M_DQ0" )
			)
			( signal "@baseboard_fab2_lib.baseboard_fab2(sch_1):bmc_m_dq1"
				( attribute "CDS_PHYS_NET_NAME" "BMC_M_DQ1"
					( Origin gPackager )
				)
				( objectStatus "BMC_M_DQ1" )
			)
			( signal "@baseboard_fab2_lib.baseboard_fab2(sch_1):bmc_m_dq10"
				( attribute "CDS_PHYS_NET_NAME" "BMC_M_DQ10"
					( Origin gPackager )
				)
				( objectStatus "BMC_M_DQ10" )
			)
			( signal "@baseboard_fab2_lib.baseboard_fab2(sch_1):bmc_m_dq11"
				( attribute "CDS_PHYS_NET_NAME" "BMC_M_DQ11"
					( Origin gPackager )
				)
				( objectStatus "BMC_M_DQ11" )
			)
			( signal "@baseboard_fab2_lib.baseboard_fab2(sch_1):bmc_m_dq12"
				( attribute "CDS_PHYS_NET_NAME" "BMC_M_DQ12"
					( Origin gPackager )
				)
				( objectStatus "BMC_M_DQ12" )
			)
			( signal "@baseboard_fab2_lib.baseboard_fab2(sch_1):bmc_m_dq13"
				( attribute "CDS_PHYS_NET_NAME" "BMC_M_DQ13"
					( Origin gPackager )
				)
				( objectStatus "BMC_M_DQ13" )
			)
			( signal "@baseboard_fab2_lib.baseboard_fab2(sch_1):bmc_m_dq14"
				( attribute "CDS_PHYS_NET_NAME" "BMC_M_DQ14"
					( Origin gPackager )
				)
				( objectStatus "BMC_M_DQ14" )
			)
			( signal "@baseboard_fab2_lib.baseboard_fab2(sch_1):bmc_m_dq15"
				( attribute "CDS_PHYS_NET_NAME" "BMC_M_DQ15"
					( Origin gPackager )
				)
				( objectStatus "BMC_M_DQ15" )
			)
			( signal "@baseboard_fab2_lib.baseboard_fab2(sch_1):bmc_m_dq2"
				( attribute "CDS_PHYS_NET_NAME" "BMC_M_DQ2"
					( Origin gPackager )
				)
				( objectStatus "BMC_M_DQ2" )
			)
			( signal "@baseboard_fab2_lib.baseboard_fab2(sch_1):bmc_m_dq3"
				( attribute "CDS_PHYS_NET_NAME" "BMC_M_DQ3"
					( Origin gPackager )
				)
				( objectStatus "BMC_M_DQ3" )
			)
			( signal "@baseboard_fab2_lib.baseboard_fab2(sch_1):bmc_m_dq4"
				( attribute "CDS_PHYS_NET_NAME" "BMC_M_DQ4"
					( Origin gPackager )
				)
				( objectStatus "BMC_M_DQ4" )
			)
			( signal "@baseboard_fab2_lib.baseboard_fab2(sch_1):bmc_m_dq5"
				( attribute "CDS_PHYS_NET_NAME" "BMC_M_DQ5"
					( Origin gPackager )
				)
				( objectStatus "BMC_M_DQ5" )
			)
			( signal "@baseboard_fab2_lib.baseboard_fab2(sch_1):bmc_m_dq6"
				( attribute "CDS_PHYS_NET_NAME" "BMC_M_DQ6"
					( Origin gPackager )
				)
				( objectStatus "BMC_M_DQ6" )
			)
			( signal "@baseboard_fab2_lib.baseboard_fab2(sch_1):bmc_m_dq7"
				( attribute "CDS_PHYS_NET_NAME" "BMC_M_DQ7"
					( Origin gPackager )
				)
				( objectStatus "BMC_M_DQ7" )
			)
			( signal "@baseboard_fab2_lib.baseboard_fab2(sch_1):bmc_m_dq8"
				( attribute "CDS_PHYS_NET_NAME" "BMC_M_DQ8"
					( Origin gPackager )
				)
				( objectStatus "BMC_M_DQ8" )
			)
			( signal "@baseboard_fab2_lib.baseboard_fab2(sch_1):bmc_m_dq9"
				( attribute "CDS_PHYS_NET_NAME" "BMC_M_DQ9"
					( Origin gPackager )
				)
				( objectStatus "BMC_M_DQ9" )
			)
			( signal "@baseboard_fab2_lib.baseboard_fab2(sch_1):bmc_m_dqs0_dn"
				( attribute "CDS_PHYS_NET_NAME" "BMC_M_DQS0_DN"
					( Origin gPackager )
				)
				( objectStatus "BMC_M_DQS0_DN" )
			)
			( signal "@baseboard_fab2_lib.baseboard_fab2(sch_1):bmc_m_dqs0_dp"
				( attribute "CDS_PHYS_NET_NAME" "BMC_M_DQS0_DP"
					( Origin gPackager )
				)
				( objectStatus "BMC_M_DQS0_DP" )
			)
			( signal "@baseboard_fab2_lib.baseboard_fab2(sch_1):bmc_m_dqs1_dn"
				( attribute "CDS_PHYS_NET_NAME" "BMC_M_DQS1_DN"
					( Origin gPackager )
				)
				( objectStatus "BMC_M_DQS1_DN" )
			)
			( signal "@baseboard_fab2_lib.baseboard_fab2(sch_1):bmc_m_dqs1_dp"
				( attribute "CDS_PHYS_NET_NAME" "BMC_M_DQS1_DP"
					( Origin gPackager )
				)
				( objectStatus "BMC_M_DQS1_DP" )
			)
			( signal "@baseboard_fab2_lib.baseboard_fab2(sch_1):bmc_m_mact_n"
				( attribute "CDS_PHYS_NET_NAME" "BMC_M_MACT_N"
					( Origin gPackager )
				)
				( objectStatus "BMC_M_MACT_N" )
			)
			( signal "@baseboard_fab2_lib.baseboard_fab2(sch_1):bmc_m_malert_n"
				( attribute "CDS_PHYS_NET_NAME" "BMC_M_MALERT_N"
					( Origin gPackager )
				)
				( objectStatus "BMC_M_MALERT_N" )
			)
			( signal "@baseboard_fab2_lib.baseboard_fab2(sch_1):bmc_m_odt"
				( attribute "CDS_PHYS_NET_NAME" "BMC_M_ODT"
					( Origin gPackager )
				)
				( objectStatus "BMC_M_ODT" )
			)
			( signal "@baseboard_fab2_lib.baseboard_fab2(sch_1):bmc_m_ras_n"
				( attribute "CDS_PHYS_NET_NAME" "BMC_M_RAS_N"
					( Origin gPackager )
				)
				( objectStatus "BMC_M_RAS_N" )
			)
			( signal "@baseboard_fab2_lib.baseboard_fab2(sch_1):bmc_m_rst_n"
				( attribute "CDS_PHYS_NET_NAME" "BMC_M_RST_N"
					( Origin gPackager )
				)
				( objectStatus "BMC_M_RST_N" )
			)
			( signal "@baseboard_fab2_lib.baseboard_fab2(sch_1):bmc_m_vrefca"
				( attribute "CDS_PHYS_NET_NAME" "BMC_M_VREFCA"
					( Origin gPackager )
				)
				( objectStatus "BMC_M_VREFCA" )
			)
			( signal "@baseboard_fab2_lib.baseboard_fab2(sch_1):bmc_m_we_n"
				( attribute "CDS_PHYS_NET_NAME" "BMC_M_WE_N"
					( Origin gPackager )
				)
				( objectStatus "BMC_M_WE_N" )
			)
			( signal "@baseboard_fab2_lib.baseboard_fab2(sch_1):bmc_mioz"
				( attribute "CDS_PHYS_NET_NAME" "BMC_MIOZ"
					( Origin gPackager )
				)
				( objectStatus "BMC_MIOZ" )
			)
			( signal "@baseboard_fab2_lib.baseboard_fab2(sch_1):bmc_zq"
				( attribute "CDS_PHYS_NET_NAME" "BMC_ZQ"
					( Origin gPackager )
				)
				( objectStatus "BMC_ZQ" )
			)
			( signal "@baseboard_fab2_lib.baseboard_fab2(sch_1):p1v2_aux_bmc"
				( alias ( signalRef "@baseboard_fab2_lib.baseboard_fab2(sch_1):page239_p1v2_aux_bmc") )
				( alias ( signalRef "@baseboard_fab2_lib.baseboard_fab2(sch_1):page150_p1v2_aux_bmc") )
				( alias ( signalRef "@baseboard_fab2_lib.baseboard_fab2(sch_1):page148_p1v2_aux_bmc") )
				( alias ( signalRef "@baseboard_fab2_lib.baseboard_fab2(sch_1):page149_p1v2_aux_bmc") )
				( attribute "PHYS_NET_NAME" "P1V2_AUX_BMC"
					( Origin gPackager )
				)
				( attribute "VOLTAGE" "1.5"
					( Units "uVoltage" "V" 1.000000)
					( Status sAliasFlattened )
					( Origin gFrontEnd )
				)
				( attribute "CDS_PHYS_NET_NAME" "P1V2_AUX_BMC"
					( Origin gPackager )
				)
				( objectStatus "P1V2_AUX_BMC" )
			)
			( signal "@baseboard_fab2_lib.baseboard_fab2(sch_1):page150_p1v2_aux_bmc"
				( objectFlag fObjectAlias )
				( objectStatus "page150_p1v2_aux_bmc" )
			)
			( signal "@baseboard_fab2_lib.baseboard_fab2(sch_1):p2v5_aux_bmc"
				( alias ( signalRef "@baseboard_fab2_lib.baseboard_fab2(sch_1):page239_p2v5_aux_bmc") )
				( alias ( signalRef "@baseboard_fab2_lib.baseboard_fab2(sch_1):page149_p2v5_aux_bmc") )
				( attribute "CDS_PHYS_NET_NAME" "P2V5_AUX_BMC"
					( Origin gPackager )
				)
				( objectStatus "P2V5_AUX_BMC" )
			)
			( signal "@baseboard_fab2_lib.baseboard_fab2(sch_1):page239_p2v5_aux_bmc"
				( objectFlag fObjectAlias )
				( objectStatus "page239_p2v5_aux_bmc" )
			)
			( signal "@baseboard_fab2_lib.baseboard_fab2(sch_1):bmc_m_par"
				( attribute "CDS_PHYS_NET_NAME" "BMC_M_PAR"
					( Origin gPackager )
				)
				( objectStatus "BMC_M_PAR" )
			)
			( signal "@baseboard_fab2_lib.baseboard_fab2(sch_1):a_dacrset"
				( attribute "CDS_PHYS_NET_NAME" "A_DACRSET"
					( Origin gPackager )
				)
				( objectStatus "A_DACRSET" )
			)
			( signal "@baseboard_fab2_lib.baseboard_fab2(sch_1):irq_lpc_serirq_r"
				( attribute "CDS_PHYS_NET_NAME" "IRQ_LPC_SERIRQ_R"
					( Origin gPackager )
				)
				( objectStatus "IRQ_LPC_SERIRQ_R" )
			)
			( signal "@baseboard_fab2_lib.baseboard_fab2(sch_1):lpc_lad0_io0_r"
				( attribute "CDS_PHYS_NET_NAME" "LPC_LAD0_IO0_R"
					( Origin gPackager )
				)
				( objectStatus "LPC_LAD0_IO0_R" )
			)
			( signal "@baseboard_fab2_lib.baseboard_fab2(sch_1):lpc_lad1_io1_r"
				( attribute "CDS_PHYS_NET_NAME" "LPC_LAD1_IO1_R"
					( Origin gPackager )
				)
				( objectStatus "LPC_LAD1_IO1_R" )
			)
			( signal "@baseboard_fab2_lib.baseboard_fab2(sch_1):lpc_lad2_io2_r"
				( attribute "CDS_PHYS_NET_NAME" "LPC_LAD2_IO2_R"
					( Origin gPackager )
				)
				( objectStatus "LPC_LAD2_IO2_R" )
			)
			( signal "@baseboard_fab2_lib.baseboard_fab2(sch_1):lpc_lad3_io3_r"
				( attribute "CDS_PHYS_NET_NAME" "LPC_LAD3_IO3_R"
					( Origin gPackager )
				)
				( objectStatus "LPC_LAD3_IO3_R" )
			)
			( signal "@baseboard_fab2_lib.baseboard_fab2(sch_1):lpc_lframe_n_cs0_r_n"
				( attribute "CDS_PHYS_NET_NAME" "LPC_LFRAME_N_CS0_R_N"
					( Origin gPackager )
				)
				( objectStatus "LPC_LFRAME_N_CS0_R_N" )
			)
			( signal "@baseboard_fab2_lib.baseboard_fab2(sch_1):vcc_d_pll_3v3"
				( alias ( signalRef "@baseboard_fab2_lib.baseboard_fab2(sch_1):page150_vcc_d_pll_3v3") )
				( alias ( signalRef "@baseboard_fab2_lib.baseboard_fab2(sch_1):page148_vcc_d_pll_3v3") )
				( attribute "CDS_PHYS_NET_NAME" "VCC_D_PLL_3V3"
					( Origin gPackager )
				)
				( objectStatus "VCC_D_PLL_3V3" )
			)
			( signal "@baseboard_fab2_lib.baseboard_fab2(sch_1):page150_vcc_d_pll_3v3"
				( objectFlag fObjectAlias )
				( objectStatus "page150_vcc_d_pll_3v3" )
			)
			( signal "@baseboard_fab2_lib.baseboard_fab2(sch_1):rst_bmc_lvc3_n"
				( attribute "CDS_PHYS_NET_NAME" "RST_BMC_LVC3_N"
					( Origin gPackager )
				)
				( objectStatus "RST_BMC_LVC3_N" )
			)
			( signal "@baseboard_fab2_lib.baseboard_fab2(sch_1):sgpio_bmc_clk_r"
				( attribute "CDS_PHYS_NET_NAME" "SGPIO_BMC_CLK_R"
					( Origin gPackager )
				)
				( objectStatus "SGPIO_BMC_CLK_R" )
			)
			( signal "@baseboard_fab2_lib.baseboard_fab2(sch_1):sgpio_bmc_dout_r"
				( attribute "CDS_PHYS_NET_NAME" "SGPIO_BMC_DOUT_R"
					( Origin gPackager )
				)
				( objectStatus "SGPIO_BMC_DOUT_R" )
			)
			( signal "@baseboard_fab2_lib.baseboard_fab2(sch_1):sgpio_bmc_ld_r_n"
				( attribute "CDS_PHYS_NET_NAME" "SGPIO_BMC_LD_R_N"
					( Origin gPackager )
				)
				( objectStatus "SGPIO_BMC_LD_R_N" )
			)
			( signal "@baseboard_fab2_lib.baseboard_fab2(sch_1):vcc_d_3v3"
				( alias ( signalRef "@baseboard_fab2_lib.baseboard_fab2(sch_1):page150_vcc_d_3v3") )
				( alias ( signalRef "@baseboard_fab2_lib.baseboard_fab2(sch_1):page148_vcc_d_3v3") )
				( attribute "CDS_PHYS_NET_NAME" "VCC_D_3V3"
					( Origin gPackager )
				)
				( objectStatus "VCC_D_3V3" )
			)
			( signal "@baseboard_fab2_lib.baseboard_fab2(sch_1):page150_vcc_d_3v3"
				( objectFlag fObjectAlias )
				( objectStatus "page150_vcc_d_3v3" )
			)
			( signal "@baseboard_fab2_lib.baseboard_fab2(sch_1):tp_dacg"
				( attribute "CDS_PHYS_NET_NAME" "TP_DACG"
					( Origin gPackager )
				)
				( objectStatus "TP_DACG" )
			)
			( signal "@baseboard_fab2_lib.baseboard_fab2(sch_1):tp_dacb"
				( attribute "CDS_PHYS_NET_NAME" "TP_DACB"
					( Origin gPackager )
				)
				( objectStatus "TP_DACB" )
			)
			( signal "@baseboard_fab2_lib.baseboard_fab2(sch_1):vcc_a_1v1"
				( alias ( signalRef "@baseboard_fab2_lib.baseboard_fab2(sch_1):page150_vcc_a_1v1") )
				( alias ( signalRef "@baseboard_fab2_lib.baseboard_fab2(sch_1):page148_vcc_a_1v1") )
				( attribute "CDS_PHYS_NET_NAME" "VCC_A_1V1"
					( Origin gPackager )
				)
				( objectStatus "VCC_A_1V1" )
			)
			( signal "@baseboard_fab2_lib.baseboard_fab2(sch_1):pu_24m_osc_oe"
				( attribute "CDS_PHYS_NET_NAME" "PU_24M_OSC_OE"
					( Origin gPackager )
				)
				( objectStatus "PU_24M_OSC_OE" )
			)
			( signal "@baseboard_fab2_lib.baseboard_fab2(sch_1):tp_jtag_bmc_rtck"
				( attribute "CDS_PHYS_NET_NAME" "TP_JTAG_BMC_RTCK"
					( Origin gPackager )
				)
				( objectStatus "TP_JTAG_BMC_RTCK" )
			)
			( signal "@baseboard_fab2_lib.baseboard_fab2(sch_1):smb_pcie_ssd_3v3aux_sda"
				( attribute "CDS_PHYS_NET_NAME" "SMB_PCIE_SSD_3V3AUX_SDA"
					( Origin gPackager )
				)
				( objectStatus "SMB_PCIE_SSD_3V3AUX_SDA" )
			)
			( signal "@baseboard_fab2_lib.baseboard_fab2(sch_1):a_usb2bvres"
				( attribute "CDS_PHYS_NET_NAME" "A_USB2BVRES"
					( Origin gPackager )
				)
				( objectStatus "A_USB2BVRES" )
			)
			( signal "@baseboard_fab2_lib.baseboard_fab2(sch_1):vccbat_tw12"
				( attribute "CDS_PHYS_NET_NAME" "VCCBAT_TW12"
					( Origin gPackager )
				)
				( objectStatus "VCCBAT_TW12" )
			)
			( signal "@baseboard_fab2_lib.baseboard_fab2(sch_1):a_usb2avres"
				( attribute "CDS_PHYS_NET_NAME" "A_USB2AVRES"
					( Origin gPackager )
				)
				( objectStatus "A_USB2AVRES" )
			)
			( signal "@baseboard_fab2_lib.baseboard_fab2(sch_1):gpios7"
				( attribute "CDS_PHYS_NET_NAME" "GPIOS7"
					( Origin gPackager )
				)
				( objectStatus "GPIOS7" )
			)
			( signal "@baseboard_fab2_lib.baseboard_fab2(sch_1):smb_ipmb_3v3aux_scl_r"
				( attribute "CDS_PHYS_NET_NAME" "SMB_IPMB_3V3AUX_SCL_R"
					( Origin gPackager )
				)
				( objectStatus "SMB_IPMB_3V3AUX_SCL_R" )
			)
			( signal "@baseboard_fab2_lib.baseboard_fab2(sch_1):smb_ipmb_3v3aux_sda_r"
				( attribute "CDS_PHYS_NET_NAME" "SMB_IPMB_3V3AUX_SDA_R"
					( Origin gPackager )
				)
				( objectStatus "SMB_IPMB_3V3AUX_SDA_R" )
			)
			( signal "@baseboard_fab2_lib.baseboard_fab2(sch_1):unnamed_239_cap_i84_a"
				( attribute "CDS_PHYS_NET_NAME" "UNNAMED_239_CAP_I84_A"
					( Origin gPackager )
				)
				( objectStatus "UNNAMED_239_CAP_I84_A" )
			)
			( signal "@baseboard_fab2_lib.baseboard_fab2(sch_1):unnamed_239_offpage_i76_a"
				( attribute "CDS_PHYS_NET_NAME" "UNNAMED_239_OFFPAGE_I76_A"
					( Origin gPackager )
				)
				( objectStatus "UNNAMED_239_OFFPAGE_I76_A" )
			)
			( signal "@baseboard_fab2_lib.baseboard_fab2(sch_1):fm_tpm_pres_rst_n_r"
				( attribute "CDS_PHYS_NET_NAME" "FM_TPM_PRES_RST_N_R"
					( Origin gPackager )
				)
				( objectStatus "FM_TPM_PRES_RST_N_R" )
			)
			( signal "@baseboard_fab2_lib.baseboard_fab2(sch_1):fm_speaker_pch_n_r"
				( attribute "CDS_PHYS_NET_NAME" "FM_SPEAKER_PCH_N_R"
					( Origin gPackager )
				)
				( objectStatus "FM_SPEAKER_PCH_N_R" )
			)
			( signal "@baseboard_fab2_lib.baseboard_fab2(sch_1):usb2_p02_dn"
				( attribute "CDS_PHYS_NET_NAME" "USB2_P02_DN"
					( Origin gPackager )
				)
				( objectStatus "USB2_P02_DN" )
			)
			( signal "@baseboard_fab2_lib.baseboard_fab2(sch_1):usb2_p02_dp"
				( attribute "CDS_PHYS_NET_NAME" "USB2_P02_DP"
					( Origin gPackager )
				)
				( objectStatus "USB2_P02_DP" )
			)
			( signal "@baseboard_fab2_lib.baseboard_fab2(sch_1):clk_100m_src13_dn"
				( attribute "CDS_PHYS_NET_NAME" "CLK_100M_SRC13_DN"
					( Origin gPackager )
				)
				( objectStatus "CLK_100M_SRC13_DN" )
			)
			( signal "@baseboard_fab2_lib.baseboard_fab2(sch_1):clk_100m_src13_dp"
				( attribute "CDS_PHYS_NET_NAME" "CLK_100M_SRC13_DP"
					( Origin gPackager )
				)
				( objectStatus "CLK_100M_SRC13_DP" )
			)
			( signal "@baseboard_fab2_lib.baseboard_fab2(sch_1):tp_smb_bus11_scl"
				( attribute "CDS_PHYS_NET_NAME" "TP_SMB_BUS11_SCL"
					( Origin gPackager )
				)
				( objectStatus "TP_SMB_BUS11_SCL" )
			)
			( signal "@baseboard_fab2_lib.baseboard_fab2(sch_1):clk_24m_bmc_lpc_r1"
				( attribute "CDS_PHYS_NET_NAME" "CLK_24M_BMC_LPC_R1"
					( Origin gPackager )
				)
				( objectStatus "CLK_24M_BMC_LPC_R1" )
			)
			( signal "@baseboard_fab2_lib.baseboard_fab2(sch_1):tp_smb_bus11_sda"
				( attribute "CDS_PHYS_NET_NAME" "TP_SMB_BUS11_SDA"
					( Origin gPackager )
				)
				( objectStatus "TP_SMB_BUS11_SDA" )
			)
			( signal "@baseboard_fab2_lib.baseboard_fab2(sch_1):hsc_smbus_switch_en"
				( attribute "CDS_PHYS_NET_NAME" "HSC_SMBUS_SWITCH_EN"
					( Origin gPackager )
				)
				( objectStatus "HSC_SMBUS_SWITCH_EN" )
			)
			( signal "@baseboard_fab2_lib.baseboard_fab2(sch_1):smb_host_stby_lvc3_scl_r3"
				( attribute "CDS_PHYS_NET_NAME" "SMB_HOST_STBY_LVC3_SCL_R3"
					( Origin gPackager )
				)
				( objectStatus "SMB_HOST_STBY_LVC3_SCL_R3" )
			)
			( signal "@baseboard_fab2_lib.baseboard_fab2(sch_1):smb_host_stby_lvc3_sda_r3"
				( attribute "CDS_PHYS_NET_NAME" "SMB_HOST_STBY_LVC3_SDA_R3"
					( Origin gPackager )
				)
				( objectStatus "SMB_HOST_STBY_LVC3_SDA_R3" )
			)
			( signal "@baseboard_fab2_lib.baseboard_fab2(sch_1):pd_id_eeprom_wp"
				( attribute "CDS_PHYS_NET_NAME" "PD_ID_EEPROM_WP"
					( Origin gPackager )
				)
				( objectStatus "PD_ID_EEPROM_WP" )
			)
			( signal "@baseboard_fab2_lib.baseboard_fab2(sch_1):pu_id_eeprom_a2"
				( attribute "CDS_PHYS_NET_NAME" "PU_ID_EEPROM_A2"
					( Origin gPackager )
				)
				( objectStatus "PU_ID_EEPROM_A2" )
			)
			( signal "@baseboard_fab2_lib.baseboard_fab2(sch_1):tp_bmc_m_a15"
				( attribute "CDS_PHYS_NET_NAME" "TP_BMC_M_A15"
					( Origin gPackager )
				)
				( objectStatus "TP_BMC_M_A15" )
			)
			( signal "@baseboard_fab2_lib.baseboard_fab2(sch_1):page155_p5v"
				( attribute "VOLTAGE" "5.0V"
					( Units "uVoltage" "V" 1.000000)
					( Origin gFrontEnd )
				)
				( objectFlag fObjectAlias )
				( objectStatus "page155_p5v" )
			)
			( signal "@baseboard_fab2_lib.baseboard_fab2(sch_1):uart_pwr_sel"
				( objectStatus "uart_pwr_sel" )
			)
			( gate "@baseboard_fab2_lib.baseboard_fab2(sch_1):page21_i149"
				( attribute "BOM_COST" "PROC_SIDEBAND"
					( Origin gFrontEnd )
				)
				( attribute "CDS_LIB" "mstr_discrete"
					( Origin gPackager )
				)
				( attribute "CDS_LOCATION" "R6N10"
					( Origin gPackager )
				)
				( attribute "CDS_SEC" "1"
					( Origin gPackager )
				)
				( attribute "LOCATION" "R6N10"
					( Origin gFrontEnd )
				)
				( attribute "MATERIAL" "CHIP"
					( Origin gFrontEnd )
				)
				( attribute "PACK_TYPE" "0402"
					( Origin gFrontEnd )
				)
				( attribute "PART_NUMBER" "G21796-271"
					( Origin gFrontEnd )
				)
				( attribute "PHYS_PAGE" "21"
					( Origin gFrontEnd )
				)
				( attribute "ROOM" "CPU0"
					( Origin gFrontEnd )
				)
				( attribute "ROT" "0"
					( Origin gFrontEnd )
				)
				( attribute "SEC" "1"
					( Origin gFrontEnd )
				)
				( attribute "SEC_TYPE" "0402"
					( Origin gFrontEnd )
				)
				( attribute "TOLERANCE" "1.0%"
					( Origin gFrontEnd )
				)
				( attribute "VALUE" "221"
					( Origin gFrontEnd )
				)
				( attribute "VER" "1"
					( Origin gFrontEnd )
				)
				( attribute "WATTAGE" "1/16W"
					( Origin gFrontEnd )
				)
				( attribute "XY" "(-1975,3750)"
					( Origin gFrontEnd )
				)
				( attribute "CHIPS_PART_NAME" "RES"
					( Origin gPackager )
				)
				( attribute "CDS_PART_NAME" "RES_0402-221,1.0%,1/16W,CHIP,GA"
					( Origin gPackager )
				)
				( objectStatus "R6N10" )
				( pin "a"
					( attribute "PN" "1"
						( Origin gPackager )
					)
					( objectStatus "R6N10.1" )
				)
				( pin "b"
					( attribute "PN" "2"
						( Origin gPackager )
					)
					( objectStatus "R6N10.2" )
				)
			)
			( gate "@baseboard_fab2_lib.baseboard_fab2(sch_1):page21_i150"
				( attribute "BOM_COST" "PROC_SIDEBAND"
					( Origin gFrontEnd )
				)
				( attribute "CDS_LIB" "mstr_discrete"
					( Origin gPackager )
				)
				( attribute "CDS_LOCATION" "R6N12"
					( Origin gPackager )
				)
				( attribute "CDS_SEC" "1"
					( Origin gPackager )
				)
				( attribute "LOCATION" "R6N12"
					( Origin gFrontEnd )
				)
				( attribute "MATERIAL" "CHIP"
					( Origin gFrontEnd )
				)
				( attribute "PACK_TYPE" "0402"
					( Origin gFrontEnd )
				)
				( attribute "PART_NUMBER" "G21497-005"
					( Origin gFrontEnd )
				)
				( attribute "PHYS_PAGE" "21"
					( Origin gFrontEnd )
				)
				( attribute "ROOM" "CPU0"
					( Origin gFrontEnd )
				)
				( attribute "ROT" "0"
					( Origin gFrontEnd )
				)
				( attribute "SEC" "1"
					( Origin gFrontEnd )
				)
				( attribute "SEC_TYPE" "0402"
					( Origin gFrontEnd )
				)
				( attribute "TOLERANCE" "5%"
					( Origin gFrontEnd )
				)
				( attribute "VALUE" "0.0"
					( Origin gFrontEnd )
				)
				( attribute "VER" "1"
					( Origin gFrontEnd )
				)
				( attribute "WATTAGE" "1/16W"
					( Origin gFrontEnd )
				)
				( attribute "XY" "(-1975,3800)"
					( Origin gFrontEnd )
				)
				( attribute "CHIPS_PART_NAME" "RES"
					( Origin gPackager )
				)
				( attribute "CDS_PART_NAME" "RES_0402-0.0,5%,1/16W,CHIP,G21A"
					( Origin gPackager )
				)
				( objectStatus "R6N12" )
				( pin "a"
					( attribute "PN" "1"
						( Origin gPackager )
					)
					( objectStatus "R6N12.1" )
				)
				( pin "b"
					( attribute "PN" "2"
						( Origin gPackager )
					)
					( objectStatus "R6N12.2" )
				)
			)
			( gate "@baseboard_fab2_lib.baseboard_fab2(sch_1):page21_i151"
				( attribute "BOM_COST" "PROC_SIDEBAND"
					( Origin gFrontEnd )
				)
				( attribute "CDS_LIB" "mstr_discrete"
					( Origin gPackager )
				)
				( attribute "CDS_LOCATION" "R6N11"
					( Origin gPackager )
				)
				( attribute "CDS_SEC" "1"
					( Origin gPackager )
				)
				( attribute "LOCATION" "R6N11"
					( Origin gFrontEnd )
				)
				( attribute "MATERIAL" "CHIP"
					( Origin gFrontEnd )
				)
				( attribute "PACK_TYPE" "0402"
					( Origin gFrontEnd )
				)
				( attribute "PART_NUMBER" "G21497-005"
					( Origin gFrontEnd )
				)
				( attribute "PHYS_PAGE" "21"
					( Origin gFrontEnd )
				)
				( attribute "ROOM" "CPU0"
					( Origin gFrontEnd )
				)
				( attribute "ROT" "0"
					( Origin gFrontEnd )
				)
				( attribute "SEC" "1"
					( Origin gFrontEnd )
				)
				( attribute "SEC_TYPE" "0402"
					( Origin gFrontEnd )
				)
				( attribute "TOLERANCE" "5%"
					( Origin gFrontEnd )
				)
				( attribute "VALUE" "0.0"
					( Origin gFrontEnd )
				)
				( attribute "VER" "1"
					( Origin gFrontEnd )
				)
				( attribute "WATTAGE" "1/16W"
					( Origin gFrontEnd )
				)
				( attribute "XY" "(-1975,3850)"
					( Origin gFrontEnd )
				)
				( attribute "CHIPS_PART_NAME" "RES"
					( Origin gPackager )
				)
				( attribute "CDS_PART_NAME" "RES_0402-0.0,5%,1/16W,CHIP,G21A"
					( Origin gPackager )
				)
				( objectStatus "R6N11" )
				( pin "a"
					( attribute "PN" "1"
						( Origin gPackager )
					)
					( objectStatus "R6N11.1" )
				)
				( pin "b"
					( attribute "PN" "2"
						( Origin gPackager )
					)
					( objectStatus "R6N11.2" )
				)
			)
			( gate "@baseboard_fab2_lib.baseboard_fab2(sch_1):page21_i152"
				( attribute "BOM_COST" "PROC_SIDEBAND"
					( Origin gFrontEnd )
				)
				( attribute "CDS_LIB" "mstr_discrete"
					( Origin gPackager )
				)
				( attribute "CDS_LOCATION" "R6B3"
					( Origin gPackager )
				)
				( attribute "CDS_SEC" "1"
					( Origin gPackager )
				)
				( attribute "LOCATION" "R6B3"
					( Origin gFrontEnd )
				)
				( attribute "MATERIAL" "CHIP"
					( Origin gFrontEnd )
				)
				( attribute "PACK_TYPE" "0402"
					( Origin gFrontEnd )
				)
				( attribute "PART_NUMBER" "G21796-271"
					( Origin gFrontEnd )
				)
				( attribute "PHYS_PAGE" "21"
					( Origin gFrontEnd )
				)
				( attribute "ROOM" "CPU0"
					( Origin gFrontEnd )
				)
				( attribute "ROT" "0"
					( Origin gFrontEnd )
				)
				( attribute "SEC" "1"
					( Origin gFrontEnd )
				)
				( attribute "SEC_TYPE" "0402"
					( Origin gFrontEnd )
				)
				( attribute "TOLERANCE" "1.0%"
					( Origin gFrontEnd )
				)
				( attribute "VALUE" "221"
					( Origin gFrontEnd )
				)
				( attribute "VER" "1"
					( Origin gFrontEnd )
				)
				( attribute "WATTAGE" "1/16W"
					( Origin gFrontEnd )
				)
				( attribute "XY" "(-1975,3900)"
					( Origin gFrontEnd )
				)
				( attribute "CHIPS_PART_NAME" "RES"
					( Origin gPackager )
				)
				( attribute "CDS_PART_NAME" "RES_0402-221,1.0%,1/16W,CHIP,GA"
					( Origin gPackager )
				)
				( objectStatus "R6B3" )
				( pin "a"
					( attribute "PN" "1"
						( Origin gPackager )
					)
					( objectStatus "R6B3.1" )
				)
				( pin "b"
					( attribute "PN" "2"
						( Origin gPackager )
					)
					( objectStatus "R6B3.2" )
				)
			)
			( gate "@baseboard_fab2_lib.baseboard_fab2(sch_1):page21_i153"
				( attribute "BOM_COST" "PROC_SIDEBAND"
					( Origin gFrontEnd )
				)
				( attribute "CDS_LIB" "mstr_discrete"
					( Origin gPackager )
				)
				( attribute "CDS_LOCATION" "R6B5"
					( Origin gPackager )
				)
				( attribute "CDS_SEC" "1"
					( Origin gPackager )
				)
				( attribute "LOCATION" "R6B5"
					( Origin gFrontEnd )
				)
				( attribute "MATERIAL" "CHIP"
					( Origin gFrontEnd )
				)
				( attribute "PACK_TYPE" "0402"
					( Origin gFrontEnd )
				)
				( attribute "PART_NUMBER" "G21497-005"
					( Origin gFrontEnd )
				)
				( attribute "PHYS_PAGE" "21"
					( Origin gFrontEnd )
				)
				( attribute "ROOM" "CPU0"
					( Origin gFrontEnd )
				)
				( attribute "ROT" "0"
					( Origin gFrontEnd )
				)
				( attribute "SEC" "1"
					( Origin gFrontEnd )
				)
				( attribute "SEC_TYPE" "0402"
					( Origin gFrontEnd )
				)
				( attribute "TOLERANCE" "5%"
					( Origin gFrontEnd )
				)
				( attribute "VALUE" "0.0"
					( Origin gFrontEnd )
				)
				( attribute "VER" "1"
					( Origin gFrontEnd )
				)
				( attribute "WATTAGE" "1/16W"
					( Origin gFrontEnd )
				)
				( attribute "XY" "(-1975,3950)"
					( Origin gFrontEnd )
				)
				( attribute "CHIPS_PART_NAME" "RES"
					( Origin gPackager )
				)
				( attribute "CDS_PART_NAME" "RES_0402-0.0,5%,1/16W,CHIP,G21A"
					( Origin gPackager )
				)
				( objectStatus "R6B5" )
				( pin "a"
					( attribute "PN" "1"
						( Origin gPackager )
					)
					( objectStatus "R6B5.1" )
				)
				( pin "b"
					( attribute "PN" "2"
						( Origin gPackager )
					)
					( objectStatus "R6B5.2" )
				)
			)
			( gate "@baseboard_fab2_lib.baseboard_fab2(sch_1):page21_i154"
				( attribute "BOM_COST" "PROC_SIDEBAND"
					( Origin gFrontEnd )
				)
				( attribute "CDS_LIB" "mstr_discrete"
					( Origin gPackager )
				)
				( attribute "CDS_LOCATION" "R6B4"
					( Origin gPackager )
				)
				( attribute "CDS_SEC" "1"
					( Origin gPackager )
				)
				( attribute "LOCATION" "R6B4"
					( Origin gFrontEnd )
				)
				( attribute "MATERIAL" "CHIP"
					( Origin gFrontEnd )
				)
				( attribute "PACK_TYPE" "0402"
					( Origin gFrontEnd )
				)
				( attribute "PART_NUMBER" "G21497-005"
					( Origin gFrontEnd )
				)
				( attribute "PHYS_PAGE" "21"
					( Origin gFrontEnd )
				)
				( attribute "ROOM" "CPU0"
					( Origin gFrontEnd )
				)
				( attribute "ROT" "0"
					( Origin gFrontEnd )
				)
				( attribute "SEC" "1"
					( Origin gFrontEnd )
				)
				( attribute "SEC_TYPE" "0402"
					( Origin gFrontEnd )
				)
				( attribute "TOLERANCE" "5%"
					( Origin gFrontEnd )
				)
				( attribute "VALUE" "0.0"
					( Origin gFrontEnd )
				)
				( attribute "VER" "1"
					( Origin gFrontEnd )
				)
				( attribute "WATTAGE" "1/16W"
					( Origin gFrontEnd )
				)
				( attribute "XY" "(-1975,4000)"
					( Origin gFrontEnd )
				)
				( attribute "CHIPS_PART_NAME" "RES"
					( Origin gPackager )
				)
				( attribute "CDS_PART_NAME" "RES_0402-0.0,5%,1/16W,CHIP,G21A"
					( Origin gPackager )
				)
				( objectStatus "R6B4" )
				( pin "a"
					( attribute "PN" "1"
						( Origin gPackager )
					)
					( objectStatus "R6B4.1" )
				)
				( pin "b"
					( attribute "PN" "2"
						( Origin gPackager )
					)
					( objectStatus "R6B4.2" )
				)
			)
			( gate "@baseboard_fab2_lib.baseboard_fab2(sch_1):page21_i159"
				( attribute "BOM_COST" "PROC_SIDEBAND"
					( Origin gFrontEnd )
				)
				( attribute "CDS_LIB" "mstr_discrete"
					( Origin gPackager )
				)
				( attribute "CDS_LOCATION" "R6B2"
					( Origin gPackager )
				)
				( attribute "CDS_SEC" "1"
					( Origin gPackager )
				)
				( attribute "LOCATION" "R6B2"
					( Origin gFrontEnd )
				)
				( attribute "MATERIAL" "CHIP"
					( Origin gFrontEnd )
				)
				( attribute "PACK_TYPE" "0402"
					( Origin gFrontEnd )
				)
				( attribute "PART_NUMBER" "G21796-017"
					( Origin gFrontEnd )
				)
				( attribute "PHYS_PAGE" "21"
					( Origin gFrontEnd )
				)
				( attribute "ROOM" "CPU0"
					( Origin gFrontEnd )
				)
				( attribute "ROT" "0"
					( Origin gFrontEnd )
				)
				( attribute "SEC" "1"
					( Origin gFrontEnd )
				)
				( attribute "SEC_TYPE" "0402"
					( Origin gFrontEnd )
				)
				( attribute "TOLERANCE" "1%"
					( Origin gFrontEnd )
				)
				( attribute "VALUE" "100.0"
					( Origin gFrontEnd )
				)
				( attribute "VER" "2"
					( Origin gFrontEnd )
				)
				( attribute "WATTAGE" "1/16W"
					( Origin gFrontEnd )
				)
				( attribute "XY" "(-1200,4300)"
					( Origin gFrontEnd )
				)
				( attribute "CHIPS_PART_NAME" "RES"
					( Origin gPackager )
				)
				( attribute "CDS_PART_NAME" "RES_0402-100.0,1%,1/16W,CHIP,GA"
					( Origin gPackager )
				)
				( objectStatus "R6B2" )
				( pin "a"
					( attribute "PN" "1"
						( Origin gPackager )
					)
					( objectStatus "R6B2.1" )
				)
				( pin "b"
					( attribute "PN" "2"
						( Origin gPackager )
					)
					( objectStatus "R6B2.2" )
				)
			)
			( gate "@baseboard_fab2_lib.baseboard_fab2(sch_1):page21_i161"
				( attribute "BOM_COST" "PROC_SIDEBAND"
					( Origin gFrontEnd )
				)
				( attribute "CDS_LIB" "mstr_discrete"
					( Origin gPackager )
				)
				( attribute "CDS_LOCATION" "R6B1"
					( Origin gPackager )
				)
				( attribute "CDS_SEC" "1"
					( Origin gPackager )
				)
				( attribute "LOCATION" "R6B1"
					( Origin gFrontEnd )
				)
				( attribute "MATERIAL" "CHIP"
					( Origin gFrontEnd )
				)
				( attribute "PACK_TYPE" "0402"
					( Origin gFrontEnd )
				)
				( attribute "PART_NUMBER" "G21796-047"
					( Origin gFrontEnd )
				)
				( attribute "PHYS_PAGE" "21"
					( Origin gFrontEnd )
				)
				( attribute "ROOM" "CPU0"
					( Origin gFrontEnd )
				)
				( attribute "ROT" "0"
					( Origin gFrontEnd )
				)
				( attribute "SEC" "1"
					( Origin gFrontEnd )
				)
				( attribute "SEC_TYPE" "0402"
					( Origin gFrontEnd )
				)
				( attribute "TOLERANCE" "1%"
					( Origin gFrontEnd )
				)
				( attribute "VALUE" "49.9"
					( Origin gFrontEnd )
				)
				( attribute "VER" "2"
					( Origin gFrontEnd )
				)
				( attribute "WATTAGE" "1/16W"
					( Origin gFrontEnd )
				)
				( attribute "XY" "(-975,4300)"
					( Origin gFrontEnd )
				)
				( attribute "CHIPS_PART_NAME" "RES"
					( Origin gPackager )
				)
				( attribute "CDS_PART_NAME" "RES_0402-49.9,1%,1/16W,CHIP,G2A"
					( Origin gPackager )
				)
				( objectStatus "R6B1" )
				( pin "a"
					( attribute "PN" "1"
						( Origin gPackager )
					)
					( objectStatus "R6B1.1" )
				)
				( pin "b"
					( attribute "PN" "2"
						( Origin gPackager )
					)
					( objectStatus "R6B1.2" )
				)
			)
			( gate "@baseboard_fab2_lib.baseboard_fab2(sch_1):page21_i163"
				( attribute "BOM_COST" "PROC_SIDEBAND"
					( Origin gFrontEnd )
				)
				( attribute "CDS_LIB" "mstr_discrete"
					( Origin gPackager )
				)
				( attribute "CDS_LOCATION" "R6N2"
					( Origin gPackager )
				)
				( attribute "CDS_SEC" "1"
					( Origin gPackager )
				)
				( attribute "LOCATION" "R6N2"
					( Origin gFrontEnd )
				)
				( attribute "MATERIAL" "CHIP"
					( Origin gFrontEnd )
				)
				( attribute "PACK_TYPE" "0402"
					( Origin gFrontEnd )
				)
				( attribute "PART_NUMBER" "G21796-017"
					( Origin gFrontEnd )
				)
				( attribute "PHYS_PAGE" "21"
					( Origin gFrontEnd )
				)
				( attribute "ROOM" "CPU0"
					( Origin gFrontEnd )
				)
				( attribute "ROT" "0"
					( Origin gFrontEnd )
				)
				( attribute "SEC" "1"
					( Origin gFrontEnd )
				)
				( attribute "SEC_TYPE" "0402"
					( Origin gFrontEnd )
				)
				( attribute "TOLERANCE" "1%"
					( Origin gFrontEnd )
				)
				( attribute "VALUE" "100.0"
					( Origin gFrontEnd )
				)
				( attribute "VER" "2"
					( Origin gFrontEnd )
				)
				( attribute "WATTAGE" "1/16W"
					( Origin gFrontEnd )
				)
				( attribute "XY" "(-1200,3475)"
					( Origin gFrontEnd )
				)
				( attribute "CHIPS_PART_NAME" "RES"
					( Origin gPackager )
				)
				( attribute "CDS_PART_NAME" "RES_0402-100.0,1%,1/16W,CHIP,GA"
					( Origin gPackager )
				)
				( objectStatus "R6N2" )
				( pin "a"
					( attribute "PN" "1"
						( Origin gPackager )
					)
					( objectStatus "R6N2.1" )
				)
				( pin "b"
					( attribute "PN" "2"
						( Origin gPackager )
					)
					( objectStatus "R6N2.2" )
				)
			)
			( gate "@baseboard_fab2_lib.baseboard_fab2(sch_1):page21_i164"
				( attribute "BOM_COST" "PROC_SIDEBAND"
					( Origin gFrontEnd )
				)
				( attribute "CDS_LIB" "mstr_discrete"
					( Origin gPackager )
				)
				( attribute "CDS_LOCATION" "R6N1"
					( Origin gPackager )
				)
				( attribute "CDS_SEC" "1"
					( Origin gPackager )
				)
				( attribute "LOCATION" "R6N1"
					( Origin gFrontEnd )
				)
				( attribute "MATERIAL" "CHIP"
					( Origin gFrontEnd )
				)
				( attribute "PACK_TYPE" "0402"
					( Origin gFrontEnd )
				)
				( attribute "PART_NUMBER" "G21796-047"
					( Origin gFrontEnd )
				)
				( attribute "PHYS_PAGE" "21"
					( Origin gFrontEnd )
				)
				( attribute "ROOM" "CPU0"
					( Origin gFrontEnd )
				)
				( attribute "ROT" "0"
					( Origin gFrontEnd )
				)
				( attribute "SEC" "1"
					( Origin gFrontEnd )
				)
				( attribute "SEC_TYPE" "0402"
					( Origin gFrontEnd )
				)
				( attribute "TOLERANCE" "1%"
					( Origin gFrontEnd )
				)
				( attribute "VALUE" "49.9"
					( Origin gFrontEnd )
				)
				( attribute "VER" "2"
					( Origin gFrontEnd )
				)
				( attribute "WATTAGE" "1/16W"
					( Origin gFrontEnd )
				)
				( attribute "XY" "(-975,3500)"
					( Origin gFrontEnd )
				)
				( attribute "CHIPS_PART_NAME" "RES"
					( Origin gPackager )
				)
				( attribute "CDS_PART_NAME" "RES_0402-49.9,1%,1/16W,CHIP,G2A"
					( Origin gPackager )
				)
				( objectStatus "R6N1" )
				( pin "a"
					( attribute "PN" "1"
						( Origin gPackager )
					)
					( objectStatus "R6N1.1" )
				)
				( pin "b"
					( attribute "PN" "2"
						( Origin gPackager )
					)
					( objectStatus "R6N1.2" )
				)
			)
			( gate "@baseboard_fab2_lib.baseboard_fab2(sch_1):page21_i177"
				( attribute "BOM_COST" "PROC_SOCKET"
					( Origin gFrontEnd )
				)
				( attribute "CDS_LIB" "mstr_discrete"
					( Origin gPackager )
				)
				( attribute "CDS_LOCATION" "R5D1"
					( Origin gPackager )
				)
				( attribute "CDS_SEC" "1"
					( Origin gPackager )
				)
				( attribute "LOCATION" "R5D1"
					( Origin gFrontEnd )
				)
				( attribute "MATERIAL" "CHIP"
					( Origin gFrontEnd )
				)
				( attribute "PACK_TYPE" "0402"
					( Origin gFrontEnd )
				)
				( attribute "PART_NUMBER" "G21796-365"
					( Origin gFrontEnd )
				)
				( attribute "PHYS_PAGE" "21"
					( Origin gFrontEnd )
				)
				( attribute "ROOM" "CPU0"
					( Origin gFrontEnd )
				)
				( attribute "ROT" "2"
					( Origin gFrontEnd )
				)
				( attribute "SEC" "1"
					( Origin gFrontEnd )
				)
				( attribute "SEC_TYPE" "0402"
					( Origin gFrontEnd )
				)
				( attribute "TOLERANCE" "1%"
					( Origin gFrontEnd )
				)
				( attribute "VALUE" "90.9"
					( Origin gFrontEnd )
				)
				( attribute "VER" "2"
					( Origin gFrontEnd )
				)
				( attribute "WATTAGE" "1/16W"
					( Origin gFrontEnd )
				)
				( attribute "XY" "(-6625,2875)"
					( Origin gFrontEnd )
				)
				( attribute "CHIPS_PART_NAME" "RES"
					( Origin gPackager )
				)
				( attribute "CDS_PART_NAME" "RES_0402-90.9,1%,1/16W,CHIP,G2A"
					( Origin gPackager )
				)
				( objectStatus "R5D1" )
				( pin "a"
					( attribute "PN" "1"
						( Origin gPackager )
					)
					( objectStatus "R5D1.1" )
				)
				( pin "b"
					( attribute "PN" "2"
						( Origin gPackager )
					)
					( objectStatus "R5D1.2" )
				)
			)
			( gate "@baseboard_fab2_lib.baseboard_fab2(sch_1):page21_i178"
				( attribute "BOM_COST" "PROC_SOCKET"
					( Origin gFrontEnd )
				)
				( attribute "CDS_LIB" "mstr_discrete"
					( Origin gPackager )
				)
				( attribute "CDS_LOCATION" "R5D2"
					( Origin gPackager )
				)
				( attribute "CDS_SEC" "1"
					( Origin gPackager )
				)
				( attribute "LOCATION" "R5D2"
					( Origin gFrontEnd )
				)
				( attribute "MATERIAL" "CHIP"
					( Origin gFrontEnd )
				)
				( attribute "PACK_TYPE" "0402"
					( Origin gFrontEnd )
				)
				( attribute "PART_NUMBER" "G21796-365"
					( Origin gFrontEnd )
				)
				( attribute "PHYS_PAGE" "21"
					( Origin gFrontEnd )
				)
				( attribute "ROOM" "CPU0"
					( Origin gFrontEnd )
				)
				( attribute "ROT" "2"
					( Origin gFrontEnd )
				)
				( attribute "SEC" "1"
					( Origin gFrontEnd )
				)
				( attribute "SEC_TYPE" "0402"
					( Origin gFrontEnd )
				)
				( attribute "TOLERANCE" "1%"
					( Origin gFrontEnd )
				)
				( attribute "VALUE" "90.9"
					( Origin gFrontEnd )
				)
				( attribute "VER" "2"
					( Origin gFrontEnd )
				)
				( attribute "WATTAGE" "1/16W"
					( Origin gFrontEnd )
				)
				( attribute "XY" "(-6875,2925)"
					( Origin gFrontEnd )
				)
				( attribute "CHIPS_PART_NAME" "RES"
					( Origin gPackager )
				)
				( attribute "CDS_PART_NAME" "RES_0402-90.9,1%,1/16W,CHIP,G2A"
					( Origin gPackager )
				)
				( objectStatus "R5D2" )
				( pin "a"
					( attribute "PN" "1"
						( Origin gPackager )
					)
					( objectStatus "R5D2.1" )
				)
				( pin "b"
					( attribute "PN" "2"
						( Origin gPackager )
					)
					( objectStatus "R5D2.2" )
				)
			)
			( gate "@baseboard_fab2_lib.baseboard_fab2(sch_1):page21_i179"
				( attribute "BOM_COST" "PROC_SOCKET"
					( Origin gFrontEnd )
				)
				( attribute "CDS_LIB" "mstr_discrete"
					( Origin gPackager )
				)
				( attribute "CDS_LOCATION" "R6D1"
					( Origin gPackager )
				)
				( attribute "CDS_SEC" "1"
					( Origin gPackager )
				)
				( attribute "LOCATION" "R6D1"
					( Origin gFrontEnd )
				)
				( attribute "MATERIAL" "CHIP"
					( Origin gFrontEnd )
				)
				( attribute "PACK_TYPE" "0402"
					( Origin gFrontEnd )
				)
				( attribute "PART_NUMBER" "G21796-017"
					( Origin gFrontEnd )
				)
				( attribute "PHYS_PAGE" "21"
					( Origin gFrontEnd )
				)
				( attribute "ROOM" "CPU0"
					( Origin gFrontEnd )
				)
				( attribute "ROT" "2"
					( Origin gFrontEnd )
				)
				( attribute "SEC" "1"
					( Origin gFrontEnd )
				)
				( attribute "SEC_TYPE" "0402"
					( Origin gFrontEnd )
				)
				( attribute "TOLERANCE" "1%"
					( Origin gFrontEnd )
				)
				( attribute "VALUE" "100.0"
					( Origin gFrontEnd )
				)
				( attribute "VER" "2"
					( Origin gFrontEnd )
				)
				( attribute "WATTAGE" "1/16W"
					( Origin gFrontEnd )
				)
				( attribute "XY" "(-7125,2925)"
					( Origin gFrontEnd )
				)
				( attribute "CHIPS_PART_NAME" "RES"
					( Origin gPackager )
				)
				( attribute "CDS_PART_NAME" "RES_0402-100.0,1%,1/16W,CHIP,GA"
					( Origin gPackager )
				)
				( objectStatus "R6D1" )
				( pin "a"
					( attribute "PN" "1"
						( Origin gPackager )
					)
					( objectStatus "R6D1.1" )
				)
				( pin "b"
					( attribute "PN" "2"
						( Origin gPackager )
					)
					( objectStatus "R6D1.2" )
				)
			)
			( gate "@baseboard_fab2_lib.baseboard_fab2(sch_1):page21_i180"
				( attribute "BOM_COST" "PROC_SOCKET"
					( Origin gFrontEnd )
				)
				( attribute "CDS_LIB" "mstr_discrete"
					( Origin gPackager )
				)
				( attribute "CDS_LOCATION" "R4P8"
					( Origin gPackager )
				)
				( attribute "CDS_SEC" "1"
					( Origin gPackager )
				)
				( attribute "LOCATION" "R4P8"
					( Origin gFrontEnd )
				)
				( attribute "MATERIAL" "CHIP"
					( Origin gFrontEnd )
				)
				( attribute "PACK_TYPE" "0402"
					( Origin gFrontEnd )
				)
				( attribute "PART_NUMBER" "G21796-365"
					( Origin gFrontEnd )
				)
				( attribute "PHYS_PAGE" "21"
					( Origin gFrontEnd )
				)
				( attribute "ROOM" "CPU0"
					( Origin gFrontEnd )
				)
				( attribute "ROT" "2"
					( Origin gFrontEnd )
				)
				( attribute "SEC" "1"
					( Origin gFrontEnd )
				)
				( attribute "SEC_TYPE" "0402"
					( Origin gFrontEnd )
				)
				( attribute "TOLERANCE" "1%"
					( Origin gFrontEnd )
				)
				( attribute "VALUE" "90.9"
					( Origin gFrontEnd )
				)
				( attribute "VER" "2"
					( Origin gFrontEnd )
				)
				( attribute "WATTAGE" "1/16W"
					( Origin gFrontEnd )
				)
				( attribute "XY" "(-7350,2925)"
					( Origin gFrontEnd )
				)
				( attribute "CHIPS_PART_NAME" "RES"
					( Origin gPackager )
				)
				( attribute "CDS_PART_NAME" "RES_0402-90.9,1%,1/16W,CHIP,G2A"
					( Origin gPackager )
				)
				( objectStatus "R4P8" )
				( pin "a"
					( attribute "PN" "1"
						( Origin gPackager )
					)
					( objectStatus "R4P8.1" )
				)
				( pin "b"
					( attribute "PN" "2"
						( Origin gPackager )
					)
					( objectStatus "R4P8.2" )
				)
			)
			( gate "@baseboard_fab2_lib.baseboard_fab2(sch_1):page21_i181"
				( attribute "BOM_COST" "PROC_SOCKET"
					( Origin gFrontEnd )
				)
				( attribute "CDS_LIB" "mstr_discrete"
					( Origin gPackager )
				)
				( attribute "CDS_LOCATION" "R4P10"
					( Origin gPackager )
				)
				( attribute "CDS_SEC" "1"
					( Origin gPackager )
				)
				( attribute "LOCATION" "R4P10"
					( Origin gFrontEnd )
				)
				( attribute "MATERIAL" "CHIP"
					( Origin gFrontEnd )
				)
				( attribute "PACK_TYPE" "0402"
					( Origin gFrontEnd )
				)
				( attribute "PART_NUMBER" "G21796-365"
					( Origin gFrontEnd )
				)
				( attribute "PHYS_PAGE" "21"
					( Origin gFrontEnd )
				)
				( attribute "ROOM" "CPU0"
					( Origin gFrontEnd )
				)
				( attribute "ROT" "2"
					( Origin gFrontEnd )
				)
				( attribute "SEC" "1"
					( Origin gFrontEnd )
				)
				( attribute "SEC_TYPE" "0402"
					( Origin gFrontEnd )
				)
				( attribute "TOLERANCE" "1%"
					( Origin gFrontEnd )
				)
				( attribute "VALUE" "90.9"
					( Origin gFrontEnd )
				)
				( attribute "VER" "2"
					( Origin gFrontEnd )
				)
				( attribute "WATTAGE" "1/16W"
					( Origin gFrontEnd )
				)
				( attribute "XY" "(-7575,3000)"
					( Origin gFrontEnd )
				)
				( attribute "CHIPS_PART_NAME" "RES"
					( Origin gPackager )
				)
				( attribute "CDS_PART_NAME" "RES_0402-90.9,1%,1/16W,CHIP,G2A"
					( Origin gPackager )
				)
				( objectStatus "R4P10" )
				( pin "a"
					( attribute "PN" "1"
						( Origin gPackager )
					)
					( objectStatus "R4P10.1" )
				)
				( pin "b"
					( attribute "PN" "2"
						( Origin gPackager )
					)
					( objectStatus "R4P10.2" )
				)
			)
			( gate "@baseboard_fab2_lib.baseboard_fab2(sch_1):page21_i182"
				( attribute "BOM_COST" "PROC_SOCKET"
					( Origin gFrontEnd )
				)
				( attribute "CDS_LIB" "mstr_discrete"
					( Origin gPackager )
				)
				( attribute "CDS_LOCATION" "R4P11"
					( Origin gPackager )
				)
				( attribute "CDS_SEC" "1"
					( Origin gPackager )
				)
				( attribute "LOCATION" "R4P11"
					( Origin gFrontEnd )
				)
				( attribute "MATERIAL" "CHIP"
					( Origin gFrontEnd )
				)
				( attribute "PACK_TYPE" "0402"
					( Origin gFrontEnd )
				)
				( attribute "PART_NUMBER" "G21796-017"
					( Origin gFrontEnd )
				)
				( attribute "PHYS_PAGE" "21"
					( Origin gFrontEnd )
				)
				( attribute "ROOM" "CPU0"
					( Origin gFrontEnd )
				)
				( attribute "ROT" "2"
					( Origin gFrontEnd )
				)
				( attribute "SEC" "1"
					( Origin gFrontEnd )
				)
				( attribute "SEC_TYPE" "0402"
					( Origin gFrontEnd )
				)
				( attribute "TOLERANCE" "1%"
					( Origin gFrontEnd )
				)
				( attribute "VALUE" "100.0"
					( Origin gFrontEnd )
				)
				( attribute "VER" "2"
					( Origin gFrontEnd )
				)
				( attribute "WATTAGE" "1/16W"
					( Origin gFrontEnd )
				)
				( attribute "XY" "(-7800,3000)"
					( Origin gFrontEnd )
				)
				( attribute "CHIPS_PART_NAME" "RES"
					( Origin gPackager )
				)
				( attribute "CDS_PART_NAME" "RES_0402-100.0,1%,1/16W,CHIP,GA"
					( Origin gPackager )
				)
				( objectStatus "R4P11" )
				( pin "a"
					( attribute "PN" "1"
						( Origin gPackager )
					)
					( objectStatus "R4P11.1" )
				)
				( pin "b"
					( attribute "PN" "2"
						( Origin gPackager )
					)
					( objectStatus "R4P11.2" )
				)
			)
			( gate "@baseboard_fab2_lib.baseboard_fab2(sch_1):page21_i184"
				( attribute "BOM_COST" "PROC_SOCKET"
					( Origin gFrontEnd )
				)
				( attribute "CDS_LIB" "mstr_discrete"
					( Origin gPackager )
				)
				( attribute "CDS_LOCATION" "R6D11"
					( Origin gPackager )
				)
				( attribute "CDS_SEC" "1"
					( Origin gPackager )
				)
				( attribute "LOCATION" "R6D11"
					( Origin gFrontEnd )
				)
				( attribute "MATERIAL" "CHIP"
					( Origin gFrontEnd )
				)
				( attribute "PACK_TYPE" "0402"
					( Origin gFrontEnd )
				)
				( attribute "PART_NUMBER" "G21796-047"
					( Origin gFrontEnd )
				)
				( attribute "PHYS_PAGE" "21"
					( Origin gFrontEnd )
				)
				( attribute "ROOM" "CPU0"
					( Origin gFrontEnd )
				)
				( attribute "ROT" "2"
					( Origin gFrontEnd )
				)
				( attribute "SEC" "1"
					( Origin gFrontEnd )
				)
				( attribute "SEC_TYPE" "0402"
					( Origin gFrontEnd )
				)
				( attribute "TOLERANCE" "1%"
					( Origin gFrontEnd )
				)
				( attribute "VALUE" "49.9"
					( Origin gFrontEnd )
				)
				( attribute "VER" "2"
					( Origin gFrontEnd )
				)
				( attribute "WATTAGE" "1/16W"
					( Origin gFrontEnd )
				)
				( attribute "XY" "(-7375,2100)"
					( Origin gFrontEnd )
				)
				( attribute "CHIPS_PART_NAME" "RES"
					( Origin gPackager )
				)
				( attribute "CDS_PART_NAME" "RES_0402-49.9,1%,1/16W,CHIP,G2A"
					( Origin gPackager )
				)
				( objectStatus "R6D11" )
				( pin "a"
					( attribute "PN" "1"
						( Origin gPackager )
					)
					( objectStatus "R6D11.1" )
				)
				( pin "b"
					( attribute "PN" "2"
						( Origin gPackager )
					)
					( objectStatus "R6D11.2" )
				)
			)
			( gate "@baseboard_fab2_lib.baseboard_fab2(sch_1):page21_i186"
				( attribute "BOM_COST" "PROC_SOCKET"
					( Origin gFrontEnd )
				)
				( attribute "CDS_LIB" "mstr_discrete"
					( Origin gPackager )
				)
				( attribute "CDS_LOCATION" "R4P3"
					( Origin gPackager )
				)
				( attribute "CDS_SEC" "1"
					( Origin gPackager )
				)
				( attribute "LOCATION" "R4P3"
					( Origin gFrontEnd )
				)
				( attribute "MATERIAL" "CHIP"
					( Origin gFrontEnd )
				)
				( attribute "PACK_TYPE" "0402"
					( Origin gFrontEnd )
				)
				( attribute "PART_NUMBER" "G21796-047"
					( Origin gFrontEnd )
				)
				( attribute "PHYS_PAGE" "21"
					( Origin gFrontEnd )
				)
				( attribute "ROOM" "CPU0"
					( Origin gFrontEnd )
				)
				( attribute "ROT" "2"
					( Origin gFrontEnd )
				)
				( attribute "SEC" "1"
					( Origin gFrontEnd )
				)
				( attribute "SEC_TYPE" "0402"
					( Origin gFrontEnd )
				)
				( attribute "TOLERANCE" "1%"
					( Origin gFrontEnd )
				)
				( attribute "VALUE" "49.9"
					( Origin gFrontEnd )
				)
				( attribute "VER" "2"
					( Origin gFrontEnd )
				)
				( attribute "WATTAGE" "1/16W"
					( Origin gFrontEnd )
				)
				( attribute "XY" "(-7575,2100)"
					( Origin gFrontEnd )
				)
				( attribute "CHIPS_PART_NAME" "RES"
					( Origin gPackager )
				)
				( attribute "CDS_PART_NAME" "RES_0402-49.9,1%,1/16W,CHIP,G2A"
					( Origin gPackager )
				)
				( objectStatus "R4P3" )
				( pin "a"
					( attribute "PN" "1"
						( Origin gPackager )
					)
					( objectStatus "R4P3.1" )
				)
				( pin "b"
					( attribute "PN" "2"
						( Origin gPackager )
					)
					( objectStatus "R4P3.2" )
				)
			)
			( gate "@baseboard_fab2_lib.baseboard_fab2(sch_1):page21_i188"
				( attribute "BOM_COST" "PROC_SOCKET"
					( Origin gFrontEnd )
				)
				( attribute "CDS_LIB" "mstr_discrete"
					( Origin gPackager )
				)
				( attribute "CDS_LOCATION" "R4P2"
					( Origin gPackager )
				)
				( attribute "CDS_SEC" "1"
					( Origin gPackager )
				)
				( attribute "LOCATION" "R4P2"
					( Origin gFrontEnd )
				)
				( attribute "MATERIAL" "CHIP"
					( Origin gFrontEnd )
				)
				( attribute "PACK_TYPE" "0402"
					( Origin gFrontEnd )
				)
				( attribute "PART_NUMBER" "G21796-047"
					( Origin gFrontEnd )
				)
				( attribute "PHYS_PAGE" "21"
					( Origin gFrontEnd )
				)
				( attribute "ROOM" "CPU0"
					( Origin gFrontEnd )
				)
				( attribute "ROT" "2"
					( Origin gFrontEnd )
				)
				( attribute "SEC" "1"
					( Origin gFrontEnd )
				)
				( attribute "SEC_TYPE" "0402"
					( Origin gFrontEnd )
				)
				( attribute "TOLERANCE" "1%"
					( Origin gFrontEnd )
				)
				( attribute "VALUE" "49.9"
					( Origin gFrontEnd )
				)
				( attribute "VER" "2"
					( Origin gFrontEnd )
				)
				( attribute "WATTAGE" "1/16W"
					( Origin gFrontEnd )
				)
				( attribute "XY" "(-7800,2100)"
					( Origin gFrontEnd )
				)
				( attribute "CHIPS_PART_NAME" "RES"
					( Origin gPackager )
				)
				( attribute "CDS_PART_NAME" "RES_0402-49.9,1%,1/16W,CHIP,G2A"
					( Origin gPackager )
				)
				( objectStatus "R4P2" )
				( pin "a"
					( attribute "PN" "1"
						( Origin gPackager )
					)
					( objectStatus "R4P2.1" )
				)
				( pin "b"
					( attribute "PN" "2"
						( Origin gPackager )
					)
					( objectStatus "R4P2.2" )
				)
			)
			( gate "@baseboard_fab2_lib.baseboard_fab2(sch_1):page21_i189"
				( attribute "BOM_COST" "PROC_SOCKET"
					( Origin gFrontEnd )
				)
				( attribute "CDS_LIB" "mstr_discrete"
					( Origin gPackager )
				)
				( attribute "CDS_LOCATION" "R4P4"
					( Origin gPackager )
				)
				( attribute "CDS_SEC" "1"
					( Origin gPackager )
				)
				( attribute "LOCATION" "R4P4"
					( Origin gFrontEnd )
				)
				( attribute "MATERIAL" "CHIP"
					( Origin gFrontEnd )
				)
				( attribute "PACK_TYPE" "0402"
					( Origin gFrontEnd )
				)
				( attribute "PART_NUMBER" "G21796-047"
					( Origin gFrontEnd )
				)
				( attribute "PHYS_PAGE" "21"
					( Origin gFrontEnd )
				)
				( attribute "ROOM" "CPU0"
					( Origin gFrontEnd )
				)
				( attribute "ROT" "2"
					( Origin gFrontEnd )
				)
				( attribute "SEC" "1"
					( Origin gFrontEnd )
				)
				( attribute "SEC_TYPE" "0402"
					( Origin gFrontEnd )
				)
				( attribute "TOLERANCE" "1%"
					( Origin gFrontEnd )
				)
				( attribute "VALUE" "49.9"
					( Origin gFrontEnd )
				)
				( attribute "VER" "2"
					( Origin gFrontEnd )
				)
				( attribute "WATTAGE" "1/16W"
					( Origin gFrontEnd )
				)
				( attribute "XY" "(-7150,2050)"
					( Origin gFrontEnd )
				)
				( attribute "CHIPS_PART_NAME" "RES"
					( Origin gPackager )
				)
				( attribute "CDS_PART_NAME" "RES_0402-49.9,1%,1/16W,CHIP,G2A"
					( Origin gPackager )
				)
				( objectStatus "R4P4" )
				( pin "a"
					( attribute "PN" "1"
						( Origin gPackager )
					)
					( objectStatus "R4P4.1" )
				)
				( pin "b"
					( attribute "PN" "2"
						( Origin gPackager )
					)
					( objectStatus "R4P4.2" )
				)
			)
			( gate "@baseboard_fab2_lib.baseboard_fab2(sch_1):page21_i204"
				( attribute "BOM_COST" "PROC_SOCKET"
					( Origin gFrontEnd )
				)
				( attribute "CDS_LIB" "mstr_discrete"
					( Origin gPackager )
				)
				( attribute "CDS_LOCATION" "R6D2"
					( Origin gPackager )
				)
				( attribute "CDS_SEC" "1"
					( Origin gPackager )
				)
				( attribute "LOCATION" "R6D2"
					( Origin gFrontEnd )
				)
				( attribute "MATERIAL" "CHIP"
					( Origin gFrontEnd )
				)
				( attribute "PACK_TYPE" "0402"
					( Origin gFrontEnd )
				)
				( attribute "PART_NUMBER" "G21796-047"
					( Origin gFrontEnd )
				)
				( attribute "PHYS_PAGE" "21"
					( Origin gFrontEnd )
				)
				( attribute "ROOM" "CPU0"
					( Origin gFrontEnd )
				)
				( attribute "ROT" "2"
					( Origin gFrontEnd )
				)
				( attribute "SEC" "1"
					( Origin gFrontEnd )
				)
				( attribute "SEC_TYPE" "0402"
					( Origin gFrontEnd )
				)
				( attribute "TOLERANCE" "1%"
					( Origin gFrontEnd )
				)
				( attribute "VALUE" "49.9"
					( Origin gFrontEnd )
				)
				( attribute "VER" "2"
					( Origin gFrontEnd )
				)
				( attribute "WATTAGE" "1/16W"
					( Origin gFrontEnd )
				)
				( attribute "XY" "(-6925,2000)"
					( Origin gFrontEnd )
				)
				( attribute "CHIPS_PART_NAME" "RES"
					( Origin gPackager )
				)
				( attribute "CDS_PART_NAME" "RES_0402-49.9,1%,1/16W,CHIP,G2A"
					( Origin gPackager )
				)
				( objectStatus "R6D2" )
				( pin "a"
					( attribute "PN" "1"
						( Origin gPackager )
					)
					( objectStatus "R6D2.1" )
				)
				( pin "b"
					( attribute "PN" "2"
						( Origin gPackager )
					)
					( objectStatus "R6D2.2" )
				)
			)
			( gate "@baseboard_fab2_lib.baseboard_fab2(sch_1):page21_i216"
				( attribute "BOM_COST" "PROC_SOCKET"
					( Origin gFrontEnd )
				)
				( attribute "CDS_LIB" "chpset_lib"
					( Origin gPackager )
				)
				( attribute "CDS_LOCATION" "XRU1"
					( Origin gPackager )
				)
				( attribute "LOCATION" "XRU1"
					( Origin gFrontEnd )
				)
				( attribute "MATERIAL" "PLASTIC"
					( Origin gFrontEnd )
				)
				( attribute "PACK_TYPE" "RIGHT"
					( Origin gFrontEnd )
				)
				( attribute "PART_NUMBER" "H37604-101"
					( Origin gFrontEnd )
				)
				( attribute "PHYS_PAGE" "21"
					( Origin gFrontEnd )
				)
				( attribute "ROOM" "CPU0"
					( Origin gFrontEnd )
				)
				( attribute "ROT" "0"
					( Origin gFrontEnd )
				)
				( attribute "SKT_NUMBER" "P0"
					( Origin gFrontEnd )
				)
				( attribute "VER" "1"
					( Origin gFrontEnd )
				)
				( attribute "XY" "(-7525,4450)"
					( Origin gFrontEnd )
				)
				( attribute "CHIPS_PART_NAME" "SOCKET_P_MECH_A"
					( Origin gPackager )
				)
				( attribute "CDS_PART_NAME" "SOCKET_P_MECH_A_RIGHT-P0,PLASTA"
					( Origin gPackager )
				)
				( objectStatus "XRU1" )
			)
			( gate "@baseboard_fab2_lib.baseboard_fab2(sch_1):page21_i217"
				( attribute "BOM_COST" "PROC_SOCKET"
					( Origin gFrontEnd )
				)
				( attribute "CDS_LIB" "chpset_lib"
					( Origin gPackager )
				)
				( attribute "CDS_LOCATION" "XLU1"
					( Origin gPackager )
				)
				( attribute "LOCATION" "XLU1"
					( Origin gFrontEnd )
				)
				( attribute "MATERIAL" "PLASTIC"
					( Origin gFrontEnd )
				)
				( attribute "PACK_TYPE" "LEFT"
					( Origin gFrontEnd )
				)
				( attribute "PART_NUMBER" "H37604-201"
					( Origin gFrontEnd )
				)
				( attribute "PHYS_PAGE" "21"
					( Origin gFrontEnd )
				)
				( attribute "ROOM" "CPU0"
					( Origin gFrontEnd )
				)
				( attribute "ROT" "0"
					( Origin gFrontEnd )
				)
				( attribute "SKT_NUMBER" "P0"
					( Origin gFrontEnd )
				)
				( attribute "VER" "1"
					( Origin gFrontEnd )
				)
				( attribute "XY" "(-7525,4150)"
					( Origin gFrontEnd )
				)
				( attribute "CHIPS_PART_NAME" "SOCKET_P_MECH_A"
					( Origin gPackager )
				)
				( attribute "CDS_PART_NAME" "SOCKET_P_MECH_A_LEFT-P0,PLASTIA"
					( Origin gPackager )
				)
				( objectStatus "XLU1" )
			)
			( gate "@baseboard_fab2_lib.baseboard_fab2(sch_1):page21_i219"
				( attribute "BOM_COST" "PROC_SOCKET"
					( Origin gFrontEnd )
				)
				( attribute "CDS_LIB" "mstr_discrete"
					( Origin gPackager )
				)
				( attribute "CDS_LOCATION" "R4P19"
					( Origin gPackager )
				)
				( attribute "CDS_SEC" "1"
					( Origin gPackager )
				)
				( attribute "LOCATION" "R4P19"
					( Origin gFrontEnd )
				)
				( attribute "MATERIAL" "CHIP"
					( Origin gFrontEnd )
				)
				( attribute "PACK_TYPE" "0402"
					( Origin gFrontEnd )
				)
				( attribute "PART_NUMBER" "G21796-047"
					( Origin gFrontEnd )
				)
				( attribute "PHYS_PAGE" "21"
					( Origin gFrontEnd )
				)
				( attribute "ROOM" "CPU0"
					( Origin gFrontEnd )
				)
				( attribute "ROT" "0"
					( Origin gFrontEnd )
				)
				( attribute "SEC" "1"
					( Origin gFrontEnd )
				)
				( attribute "SEC_TYPE" "0402"
					( Origin gFrontEnd )
				)
				( attribute "TOLERANCE" "1%"
					( Origin gFrontEnd )
				)
				( attribute "VALUE" "49.9"
					( Origin gFrontEnd )
				)
				( attribute "VER" "1"
					( Origin gFrontEnd )
				)
				( attribute "WATTAGE" "1/16W"
					( Origin gFrontEnd )
				)
				( attribute "XY" "(-2375,4200)"
					( Origin gFrontEnd )
				)
				( attribute "CHIPS_PART_NAME" "RES"
					( Origin gPackager )
				)
				( attribute "CDS_PART_NAME" "RES_0402-49.9,1%,1/16W,CHIP,G2A"
					( Origin gPackager )
				)
				( objectStatus "R4P19" )
				( pin "a"
					( attribute "PN" "1"
						( Origin gPackager )
					)
					( objectStatus "R4P19.1" )
				)
				( pin "b"
					( attribute "PN" "2"
						( Origin gPackager )
					)
					( objectStatus "R4P19.2" )
				)
			)
			( gate "@baseboard_fab2_lib.baseboard_fab2(sch_1):page21_i227"
				( attribute "BOM_COST" "PROC_SIDEBAND"
					( Origin gFrontEnd )
				)
				( attribute "CDS_LIB" "mstr_discrete"
					( Origin gPackager )
				)
				( attribute "CDS_LOCATION" "R5N2"
					( Origin gPackager )
				)
				( attribute "CDS_SEC" "1"
					( Origin gPackager )
				)
				( attribute "LOCATION" "R5N2"
					( Origin gFrontEnd )
				)
				( attribute "MATERIAL" "CHIP"
					( Origin gFrontEnd )
				)
				( attribute "PACK_TYPE" "0402"
					( Origin gFrontEnd )
				)
				( attribute "PART_NUMBER" "G21796-336"
					( Origin gFrontEnd )
				)
				( attribute "PHYS_PAGE" "21"
					( Origin gFrontEnd )
				)
				( attribute "ROOM" "CPU0"
					( Origin gFrontEnd )
				)
				( attribute "ROT" "0"
					( Origin gFrontEnd )
				)
				( attribute "SEC" "1"
					( Origin gFrontEnd )
				)
				( attribute "SEC_TYPE" "0402"
					( Origin gFrontEnd )
				)
				( attribute "TOLERANCE" "1%"
					( Origin gFrontEnd )
				)
				( attribute "VALUE" "1.8K"
					( Origin gFrontEnd )
				)
				( attribute "VER" "2"
					( Origin gFrontEnd )
				)
				( attribute "WATTAGE" "1/16W"
					( Origin gFrontEnd )
				)
				( attribute "XY" "(-1475,2700)"
					( Origin gFrontEnd )
				)
				( attribute "CHIPS_PART_NAME" "RES"
					( Origin gPackager )
				)
				( attribute "CDS_PART_NAME" "RES_0402-1.8K,1%,1/16W,CHIP,G2A"
					( Origin gPackager )
				)
				( objectStatus "R5N2" )
				( pin "a"
					( attribute "PN" "1"
						( Origin gPackager )
					)
					( objectStatus "R5N2.1" )
				)
				( pin "b"
					( attribute "PN" "2"
						( Origin gPackager )
					)
					( objectStatus "R5N2.2" )
				)
			)
			( gate "@baseboard_fab2_lib.baseboard_fab2(sch_1):page21_i238"
				( attribute "BOM_COST" "PROC_SIDEBAND"
					( Origin gFrontEnd )
				)
				( attribute "CDS_LIB" "mstr_discrete"
					( Origin gPackager )
				)
				( attribute "CDS_LOCATION" "R5N1"
					( Origin gPackager )
				)
				( attribute "CDS_SEC" "1"
					( Origin gPackager )
				)
				( attribute "LOCATION" "R5N1"
					( Origin gFrontEnd )
				)
				( attribute "MATERIAL" "CHIP"
					( Origin gFrontEnd )
				)
				( attribute "PACK_TYPE" "0402"
					( Origin gFrontEnd )
				)
				( attribute "PART_NUMBER" "G21796-016"
					( Origin gFrontEnd )
				)
				( attribute "PHYS_PAGE" "21"
					( Origin gFrontEnd )
				)
				( attribute "ROOM" "CPU0"
					( Origin gFrontEnd )
				)
				( attribute "ROT" "0"
					( Origin gFrontEnd )
				)
				( attribute "SEC" "1"
					( Origin gFrontEnd )
				)
				( attribute "SEC_TYPE" "0402"
					( Origin gFrontEnd )
				)
				( attribute "TOLERANCE" "1%"
					( Origin gFrontEnd )
				)
				( attribute "VALUE" "10.0K"
					( Origin gFrontEnd )
				)
				( attribute "VER" "2"
					( Origin gFrontEnd )
				)
				( attribute "WATTAGE" "1/16W"
					( Origin gFrontEnd )
				)
				( attribute "XY" "(-675,2700)"
					( Origin gFrontEnd )
				)
				( attribute "CHIPS_PART_NAME" "RES"
					( Origin gPackager )
				)
				( attribute "CDS_PART_NAME" "RES_0402-10.0K,1%,1/16W,CHIP,GA"
					( Origin gPackager )
				)
				( objectStatus "R5N1" )
				( pin "a"
					( attribute "PN" "1"
						( Origin gPackager )
					)
					( objectStatus "R5N1.1" )
				)
				( pin "b"
					( attribute "PN" "2"
						( Origin gPackager )
					)
					( objectStatus "R5N1.2" )
				)
			)
			( gate "@baseboard_fab2_lib.baseboard_fab2(sch_1):page21_i239"
				( attribute "BOM_COST" "PROC_SIDEBAND"
					( Origin gFrontEnd )
				)
				( attribute "CDS_LIB" "mstr_discrete"
					( Origin gPackager )
				)
				( attribute "CDS_LOCATION" "R5N5"
					( Origin gPackager )
				)
				( attribute "CDS_SEC" "1"
					( Origin gPackager )
				)
				( attribute "LOCATION" "R5N5"
					( Origin gFrontEnd )
				)
				( attribute "MATERIAL" "CHIP"
					( Origin gFrontEnd )
				)
				( attribute "PACK_TYPE" "0402"
					( Origin gFrontEnd )
				)
				( attribute "PART_NUMBER" "G21796-016"
					( Origin gFrontEnd )
				)
				( attribute "PHYS_PAGE" "21"
					( Origin gFrontEnd )
				)
				( attribute "ROOM" "CPU0"
					( Origin gFrontEnd )
				)
				( attribute "ROT" "0"
					( Origin gFrontEnd )
				)
				( attribute "SEC" "1"
					( Origin gFrontEnd )
				)
				( attribute "SEC_TYPE" "0402"
					( Origin gFrontEnd )
				)
				( attribute "TOLERANCE" "1%"
					( Origin gFrontEnd )
				)
				( attribute "VALUE" "10.0K"
					( Origin gFrontEnd )
				)
				( attribute "VER" "2"
					( Origin gFrontEnd )
				)
				( attribute "WATTAGE" "1/16W"
					( Origin gFrontEnd )
				)
				( attribute "XY" "(-875,2700)"
					( Origin gFrontEnd )
				)
				( attribute "CHIPS_PART_NAME" "RES"
					( Origin gPackager )
				)
				( attribute "CDS_PART_NAME" "RES_0402-10.0K,1%,1/16W,CHIP,GA"
					( Origin gPackager )
				)
				( objectStatus "R5N5" )
				( pin "a"
					( attribute "PN" "1"
						( Origin gPackager )
					)
					( objectStatus "R5N5.1" )
				)
				( pin "b"
					( attribute "PN" "2"
						( Origin gPackager )
					)
					( objectStatus "R5N5.2" )
				)
			)
			( gate "@baseboard_fab2_lib.baseboard_fab2(sch_1):page21_i240"
				( attribute "BOM_COST" "PROC_SIDEBAND"
					( Origin gFrontEnd )
				)
				( attribute "CDS_LIB" "mstr_discrete"
					( Origin gPackager )
				)
				( attribute "CDS_LOCATION" "R5N3"
					( Origin gPackager )
				)
				( attribute "CDS_SEC" "1"
					( Origin gPackager )
				)
				( attribute "LOCATION" "R5N3"
					( Origin gFrontEnd )
				)
				( attribute "MATERIAL" "CHIP"
					( Origin gFrontEnd )
				)
				( attribute "PACK_TYPE" "0402"
					( Origin gFrontEnd )
				)
				( attribute "PART_NUMBER" "G21796-016"
					( Origin gFrontEnd )
				)
				( attribute "PHYS_PAGE" "21"
					( Origin gFrontEnd )
				)
				( attribute "ROOM" "CPU0"
					( Origin gFrontEnd )
				)
				( attribute "ROT" "0"
					( Origin gFrontEnd )
				)
				( attribute "SEC" "1"
					( Origin gFrontEnd )
				)
				( attribute "SEC_TYPE" "0402"
					( Origin gFrontEnd )
				)
				( attribute "TOLERANCE" "1%"
					( Origin gFrontEnd )
				)
				( attribute "VALUE" "10.0K"
					( Origin gFrontEnd )
				)
				( attribute "VER" "2"
					( Origin gFrontEnd )
				)
				( attribute "WATTAGE" "1/16W"
					( Origin gFrontEnd )
				)
				( attribute "XY" "(-1075,2700)"
					( Origin gFrontEnd )
				)
				( attribute "CHIPS_PART_NAME" "RES"
					( Origin gPackager )
				)
				( attribute "CDS_PART_NAME" "RES_0402-10.0K,1%,1/16W,CHIP,GA"
					( Origin gPackager )
				)
				( objectStatus "R5N3" )
				( pin "a"
					( attribute "PN" "1"
						( Origin gPackager )
					)
					( objectStatus "R5N3.1" )
				)
				( pin "b"
					( attribute "PN" "2"
						( Origin gPackager )
					)
					( objectStatus "R5N3.2" )
				)
			)
			( gate "@baseboard_fab2_lib.baseboard_fab2(sch_1):page21_i241"
				( attribute "BOM_COST" "PROC_SIDEBAND"
					( Origin gFrontEnd )
				)
				( attribute "CDS_LIB" "mstr_discrete"
					( Origin gPackager )
				)
				( attribute "CDS_LOCATION" "R5N4"
					( Origin gPackager )
				)
				( attribute "CDS_SEC" "1"
					( Origin gPackager )
				)
				( attribute "LOCATION" "R5N4"
					( Origin gFrontEnd )
				)
				( attribute "MATERIAL" "CHIP"
					( Origin gFrontEnd )
				)
				( attribute "PACK_TYPE" "0402"
					( Origin gFrontEnd )
				)
				( attribute "PART_NUMBER" "G21796-336"
					( Origin gFrontEnd )
				)
				( attribute "PHYS_PAGE" "21"
					( Origin gFrontEnd )
				)
				( attribute "ROOM" "CPU0"
					( Origin gFrontEnd )
				)
				( attribute "ROT" "0"
					( Origin gFrontEnd )
				)
				( attribute "SEC" "1"
					( Origin gFrontEnd )
				)
				( attribute "SEC_TYPE" "0402"
					( Origin gFrontEnd )
				)
				( attribute "TOLERANCE" "1%"
					( Origin gFrontEnd )
				)
				( attribute "VALUE" "1.8K"
					( Origin gFrontEnd )
				)
				( attribute "VER" "2"
					( Origin gFrontEnd )
				)
				( attribute "WATTAGE" "1/16W"
					( Origin gFrontEnd )
				)
				( attribute "XY" "(-1275,2700)"
					( Origin gFrontEnd )
				)
				( attribute "CHIPS_PART_NAME" "RES"
					( Origin gPackager )
				)
				( attribute "CDS_PART_NAME" "RES_0402-1.8K,1%,1/16W,CHIP,G2A"
					( Origin gPackager )
				)
				( objectStatus "R5N4" )
				( pin "a"
					( attribute "PN" "1"
						( Origin gPackager )
					)
					( objectStatus "R5N4.1" )
				)
				( pin "b"
					( attribute "PN" "2"
						( Origin gPackager )
					)
					( objectStatus "R5N4.2" )
				)
			)
			( gate "@baseboard_fab2_lib.baseboard_fab2(sch_1):page21_i244"
				( attribute "BOM_COST" "PROC_SIDEBAND"
					( Origin gFrontEnd )
				)
				( attribute "CDS_LIB" "mstr_discrete"
					( Origin gPackager )
				)
				( attribute "CDS_LOCATION" "R4P18"
					( Origin gPackager )
				)
				( attribute "CDS_SEC" "1"
					( Origin gPackager )
				)
				( attribute "LOCATION" "R4P18"
					( Origin gFrontEnd )
				)
				( attribute "MATERIAL" "CHIP"
					( Origin gFrontEnd )
				)
				( attribute "PACK_TYPE" "0402"
					( Origin gFrontEnd )
				)
				( attribute "PART_NUMBER" "G21796-047"
					( Origin gFrontEnd )
				)
				( attribute "PHYS_PAGE" "21"
					( Origin gFrontEnd )
				)
				( attribute "ROOM" "CPU0"
					( Origin gFrontEnd )
				)
				( attribute "ROT" "0"
					( Origin gFrontEnd )
				)
				( attribute "SEC" "1"
					( Origin gFrontEnd )
				)
				( attribute "SEC_TYPE" "0402"
					( Origin gFrontEnd )
				)
				( attribute "TOLERANCE" "1%"
					( Origin gFrontEnd )
				)
				( attribute "VALUE" "49.9"
					( Origin gFrontEnd )
				)
				( attribute "VER" "1"
					( Origin gFrontEnd )
				)
				( attribute "WATTAGE" "1/16W"
					( Origin gFrontEnd )
				)
				( attribute "XY" "(-2450,4250)"
					( Origin gFrontEnd )
				)
				( attribute "CHIPS_PART_NAME" "RES"
					( Origin gPackager )
				)
				( attribute "CDS_PART_NAME" "RES_0402-49.9,1%,1/16W,CHIP,G2A"
					( Origin gPackager )
				)
				( objectStatus "R4P18" )
				( pin "a"
					( attribute "PN" "1"
						( Origin gPackager )
					)
					( objectStatus "R4P18.1" )
				)
				( pin "b"
					( attribute "PN" "2"
						( Origin gPackager )
					)
					( objectStatus "R4P18.2" )
				)
			)
			( gate "@baseboard_fab2_lib.baseboard_fab2(sch_1):page21_i258"
				( attribute "CDS_LIB" "mstr_discrete"
					( Origin gPackager )
				)
				( attribute "CDS_LOCATION" "R4R5"
					( Origin gPackager )
				)
				( attribute "CDS_SEC" "1"
					( Origin gPackager )
				)
				( attribute "LOCATION" "R4R5"
					( Origin gFrontEnd )
				)
				( attribute "MATERIAL" "CHIP"
					( Origin gFrontEnd )
				)
				( attribute "PACK_TYPE" "0402"
					( Origin gFrontEnd )
				)
				( attribute "PART_NUMBER" "G21796-072"
					( Origin gFrontEnd )
				)
				( attribute "PHYS_PAGE" "21"
					( Origin gFrontEnd )
				)
				( attribute "ROOM" "CPU0"
					( Origin gFrontEnd )
				)
				( attribute "ROT" "0"
					( Origin gFrontEnd )
				)
				( attribute "SEC" "1"
					( Origin gFrontEnd )
				)
				( attribute "SEC_TYPE" "0402"
					( Origin gFrontEnd )
				)
				( attribute "TOLERANCE" "1%"
					( Origin gFrontEnd )
				)
				( attribute "VALUE" "4.75K"
					( Origin gFrontEnd )
				)
				( attribute "VER" "2"
					( Origin gFrontEnd )
				)
				( attribute "WATTAGE" "1/16W"
					( Origin gFrontEnd )
				)
				( attribute "XY" "(-1075,1450)"
					( Origin gFrontEnd )
				)
				( attribute "CHIPS_PART_NAME" "RES"
					( Origin gPackager )
				)
				( attribute "CDS_PART_NAME" "RES_0402-4.75K,1%,1/16W,CHIP,GA"
					( Origin gPackager )
				)
				( objectStatus "R4R5" )
				( pin "a"
					( attribute "PN" "1"
						( Origin gPackager )
					)
					( objectStatus "R4R5.1" )
				)
				( pin "b"
					( attribute "PN" "2"
						( Origin gPackager )
					)
					( objectStatus "R4R5.2" )
				)
			)
			( gate "@baseboard_fab2_lib.baseboard_fab2(sch_1):page21_i259"
				( attribute "CDS_LIB" "chpset_lib"
					( Origin gPackager )
				)
				( attribute "CDS_LOCATION" "U5D1"
					( Origin gPackager )
				)
				( attribute "CDS_SEC" "1"
					( Origin gPackager )
				)
				( attribute "LOCATION" "U5D1"
					( Origin gFrontEnd )
				)
				( attribute "MATERIAL" "IC"
					( Origin gFrontEnd )
				)
				( attribute "PACK_TYPE" "BGA1"
					( Origin gFrontEnd )
				)
				( attribute "PART_NUMBER" "TBD"
					( Origin gFrontEnd )
				)
				( attribute "PHYS_PAGE" "21"
					( Origin gFrontEnd )
				)
				( attribute "ROOM" "CPU0"
					( Origin gFrontEnd )
				)
				( attribute "ROT" "0"
					( Origin gFrontEnd )
				)
				( attribute "SEC" "1"
					( Origin gFrontEnd )
				)
				( attribute "SEC_TYPE" "BGA1"
					( Origin gFrontEnd )
				)
				( attribute "VER" "1"
					( Origin gFrontEnd )
				)
				( attribute "XY" "(-4075,2850)"
					( Origin gFrontEnd )
				)
				( attribute "CHIPS_PART_NAME" "SKX_EXT_B"
					( Origin gPackager )
				)
				( attribute "CDS_PART_NAME" "SKX_EXT_B_BGA1-IC,TBD"
					( Origin gPackager )
				)
				( objectStatus "U5D1" )
				( pin "bclk0_dn"
					( attribute "PN" "AU24"
						( Origin gPackager )
					)
					( objectStatus "U5D1.AU24" )
				)
				( pin "bclk0_dp"
					( attribute "PN" "AW24"
						( Origin gPackager )
					)
					( objectStatus "U5D1.AW24" )
				)
				( pin "bclk1_dn"
					( attribute "PN" "CR26"
						( Origin gPackager )
					)
					( objectStatus "U5D1.CR26" )
				)
				( pin "bclk1_dp"
					( attribute "PN" "CP27"
						( Origin gPackager )
					)
					( objectStatus "U5D1.CP27" )
				)
				( pin "bclk2_dn"
					( attribute "PN" "CT25"
						( Origin gPackager )
					)
					( objectStatus "U5D1.CT25" )
				)
				( pin "bclk2_dp"
					( attribute "PN" "CU26"
						( Origin gPackager )
					)
					( objectStatus "U5D1.CU26" )
				)
				( pin "bist_enable"
					( attribute "PN" "BA20"
						( Origin gPackager )
					)
					( objectStatus "U5D1.BA20" )
				)
				( pin "bmcinit"
					( attribute "PN" "BD23"
						( Origin gPackager )
					)
					( objectStatus "U5D1.BD23" )
				)
				( pin "bpm_n(0)"
					( attribute "PN" "AJ10"
						( Origin gPackager )
					)
					( objectStatus "U5D1.AJ10" )
				)
				( pin "bpm_n(1)"
					( attribute "PN" "AH11"
						( Origin gPackager )
					)
					( objectStatus "U5D1.AH11" )
				)
				( pin "bpm_n(2)"
					( attribute "PN" "AG10"
						( Origin gPackager )
					)
					( objectStatus "U5D1.AG10" )
				)
				( pin "bpm_n(3)"
					( attribute "PN" "AF11"
						( Origin gPackager )
					)
					( objectStatus "U5D1.AF11" )
				)
				( pin "bpm_n(4)"
					( attribute "PN" "AA12"
						( Origin gPackager )
					)
					( objectStatus "U5D1.AA12" )
				)
				( pin "bpm_n(5)"
					( attribute "PN" "Y11"
						( Origin gPackager )
					)
					( objectStatus "U5D1.Y11" )
				)
				( pin "bpm_n(6)"
					( attribute "PN" "AE12"
						( Origin gPackager )
					)
					( objectStatus "U5D1.AE12" )
				)
				( pin "bpm_n(7)"
					( attribute "PN" "AC12"
						( Origin gPackager )
					)
					( objectStatus "U5D1.AC12" )
				)
				( pin "caterr_n"
					( attribute "PN" "AL14"
						( Origin gPackager )
					)
					( objectStatus "U5D1.AL14" )
				)
				( pin "ddr0_cavref"
					( attribute "PN" "AJ64"
						( Origin gPackager )
					)
					( objectStatus "U5D1.AJ64" )
				)
				( pin "ddr1_cavref"
					( attribute "PN" "AK63"
						( Origin gPackager )
					)
					( objectStatus "U5D1.AK63" )
				)
				( pin "ddr2_cavref"
					( attribute "PN" "AH63"
						( Origin gPackager )
					)
					( objectStatus "U5D1.AH63" )
				)
				( pin "ddr3_cavref"
					( attribute "PN" "CP61"
						( Origin gPackager )
					)
					( objectStatus "U5D1.CP61" )
				)
				( pin "ddr4_cavref"
					( attribute "PN" "CT61"
						( Origin gPackager )
					)
					( objectStatus "U5D1.CT61" )
				)
				( pin "ddr5_cavref"
					( attribute "PN" "CV61"
						( Origin gPackager )
					)
					( objectStatus "U5D1.CV61" )
				)
				( pin "ddr012_dram_pwr_ok"
					( attribute "PN" "AN30"
						( Origin gPackager )
					)
					( objectStatus "U5D1.AN30" )
				)
				( pin "ddr012_rcomp(0)"
					( attribute "PN" "Y43"
						( Origin gPackager )
					)
					( objectStatus "U5D1.Y43" )
				)
				( pin "ddr012_rcomp(1)"
					( attribute "PN" "AB43"
						( Origin gPackager )
					)
					( objectStatus "U5D1.AB43" )
				)
				( pin "ddr012_rcomp(2)"
					( attribute "PN" "AC42"
						( Origin gPackager )
					)
					( objectStatus "U5D1.AC42" )
				)
				( pin "ddr012_reset_n"
					( attribute "PN" "U64"
						( Origin gPackager )
					)
					( objectStatus "U5D1.U64" )
				)
				( pin "ddr012_spdscl"
					( attribute "PN" "AJ18"
						( Origin gPackager )
					)
					( objectStatus "U5D1.AJ18" )
				)
				( pin "ddr012_spdsda"
					( attribute "PN" "AF17"
						( Origin gPackager )
					)
					( objectStatus "U5D1.AF17" )
				)
				( pin "ddr345_dram_pwr_ok"
					( attribute "PN" "CR28"
						( Origin gPackager )
					)
					( objectStatus "U5D1.CR28" )
				)
				( pin "ddr345_rcomp(0)"
					( attribute "PN" "DC48"
						( Origin gPackager )
					)
					( objectStatus "U5D1.DC48" )
				)
				( pin "ddr345_rcomp(1)"
					( attribute "PN" "DD47"
						( Origin gPackager )
					)
					( objectStatus "U5D1.DD47" )
				)
				( pin "ddr345_rcomp(2)"
					( attribute "PN" "DD49"
						( Origin gPackager )
					)
					( objectStatus "U5D1.DD49" )
				)
				( pin "ddr345_reset_n"
					( attribute "PN" "DV63"
						( Origin gPackager )
					)
					( objectStatus "U5D1.DV63" )
				)
				( pin "ddr345_spdscl"
					( attribute "PN" "AE18"
						( Origin gPackager )
					)
					( objectStatus "U5D1.AE18" )
				)
				( pin "ddr345_spdsda"
					( attribute "PN" "AD17"
						( Origin gPackager )
					)
					( objectStatus "U5D1.AD17" )
				)
				( pin "ear_n"
					( attribute "PN" "AJ14"
						( Origin gPackager )
					)
					( objectStatus "U5D1.AJ14" )
				)
				( pin "error_n(0)"
					( attribute "PN" "AJ12"
						( Origin gPackager )
					)
					( objectStatus "U5D1.AJ12" )
				)
				( pin "error_n(1)"
					( attribute "PN" "AK11"
						( Origin gPackager )
					)
					( objectStatus "U5D1.AK11" )
				)
				( pin "error_n(2)"
					( attribute "PN" "AL12"
						( Origin gPackager )
					)
					( objectStatus "U5D1.AL12" )
				)
				( pin "frmagent"
					( attribute "PN" "AV17"
						( Origin gPackager )
					)
					( objectStatus "U5D1.AV17" )
				)
				( pin "legacy_skt"
					( attribute "PN" "AE20"
						( Origin gPackager )
					)
					( objectStatus "U5D1.AE20" )
				)
				( pin "mcp01_rbias(0)"
					( attribute "PN" "CU32"
						( Origin gPackager )
					)
					( objectStatus "U5D1.CU32" )
				)
				( pin "mcp01_rbias(1)"
					( attribute "PN" "CT31"
						( Origin gPackager )
					)
					( objectStatus "U5D1.CT31" )
				)
				( pin "mem_hot_c012_n"
					( attribute "PN" "AH13"
						( Origin gPackager )
					)
					( objectStatus "U5D1.AH13" )
				)
				( pin "mem_hot_c345_n"
					( attribute "PN" "AF13"
						( Origin gPackager )
					)
					( objectStatus "U5D1.AF13" )
				)
				( pin "msmi_n"
					( attribute "PN" "AN20"
						( Origin gPackager )
					)
					( objectStatus "U5D1.AN20" )
				)
				( pin "nmi"
					( attribute "PN" "AP11"
						( Origin gPackager )
					)
					( objectStatus "U5D1.AP11" )
				)
				( pin "pe3_rbias(0)"
					( attribute "PN" "CP29"
						( Origin gPackager )
					)
					( objectStatus "U5D1.CP29" )
				)
				( pin "pe3_rbias(1)"
					( attribute "PN" "CR30"
						( Origin gPackager )
					)
					( objectStatus "U5D1.CR30" )
				)
				( pin "pe012_rbias(0)"
					( attribute "PN" "CN30"
						( Origin gPackager )
					)
					( objectStatus "U5D1.CN30" )
				)
				( pin "pe012_rbias(1)"
					( attribute "PN" "CL30"
						( Origin gPackager )
					)
					( objectStatus "U5D1.CL30" )
				)
				( pin "pe_hp_scl"
					( attribute "PN" "AM19"
						( Origin gPackager )
					)
					( objectStatus "U5D1.AM19" )
				)
				( pin "pe_hp_sda"
					( attribute "PN" "AL18"
						( Origin gPackager )
					)
					( objectStatus "U5D1.AL18" )
				)
				( pin "peci"
					( attribute "PN" "AU12"
						( Origin gPackager )
					)
					( objectStatus "U5D1.AU12" )
				)
				( pin "pirom_addr(0)"
					( attribute "PN" "CU58"
						( Origin gPackager )
					)
					( objectStatus "U5D1.CU58" )
				)
				( pin "pirom_addr(1)"
					( attribute "PN" "CV57"
						( Origin gPackager )
					)
					( objectStatus "U5D1.CV57" )
				)
				( pin "pirom_addr(2)"
					( attribute "PN" "CW56"
						( Origin gPackager )
					)
					( objectStatus "U5D1.CW56" )
				)
				( pin "pkgid(0)"
					( attribute "PN" "DC72"
						( Origin gPackager )
					)
					( objectStatus "U5D1.DC72" )
				)
				( pin "pkgid(1)"
					( attribute "PN" "CW72"
						( Origin gPackager )
					)
					( objectStatus "U5D1.CW72" )
				)
				( pin "pkgid(2)"
					( attribute "PN" "DA72"
						( Origin gPackager )
					)
					( objectStatus "U5D1.DA72" )
				)
				( pin "pm_fast_wake_n"
					( attribute "PN" "AF15"
						( Origin gPackager )
					)
					( objectStatus "U5D1.AF15" )
				)
				( pin "pmsync"
					( attribute "PN" "AR14"
						( Origin gPackager )
					)
					( objectStatus "U5D1.AR14" )
				)
				( pin "pmsync_clk"
					( attribute "PN" "AT19"
						( Origin gPackager )
					)
					( objectStatus "U5D1.AT19" )
				)
				( pin "prdy_n"
					( attribute "PN" "AG16"
						( Origin gPackager )
					)
					( objectStatus "U5D1.AG16" )
				)
				( pin "preq_n"
					( attribute "PN" "AR12"
						( Origin gPackager )
					)
					( objectStatus "U5D1.AR12" )
				)
				( pin "proc_id(0)"
					( attribute "PN" "CY71"
						( Origin gPackager )
					)
					( objectStatus "U5D1.CY71" )
				)
				( pin "proc_id(1)"
					( attribute "PN" "DB71"
						( Origin gPackager )
					)
					( objectStatus "U5D1.DB71" )
				)
				( pin "procdis_n"
					( attribute "PN" "AB17"
						( Origin gPackager )
					)
					( objectStatus "U5D1.AB17" )
				)
				( pin "prochot_n"
					( attribute "PN" "AC16"
						( Origin gPackager )
					)
					( objectStatus "U5D1.AC16" )
				)
				( pin "pwrgood"
					( attribute "PN" "BC24"
						( Origin gPackager )
					)
					( objectStatus "U5D1.BC24" )
				)
				( pin "reset_n"
					( attribute "PN" "AP21"
						( Origin gPackager )
					)
					( objectStatus "U5D1.AP21" )
				)
				( pin "safe_mode_boot"
					( attribute "PN" "AR18"
						( Origin gPackager )
					)
					( objectStatus "U5D1.AR18" )
				)
				( pin "sktocc_n"
					( attribute "PN" "AB13"
						( Origin gPackager )
					)
					( objectStatus "U5D1.AB13" )
				)
				( pin "sm_wp"
					( attribute "PN" "CV59"
						( Origin gPackager )
					)
					( objectStatus "U5D1.CV59" )
				)
				( pin "smbclk"
					( attribute "PN" "CT59"
						( Origin gPackager )
					)
					( objectStatus "U5D1.CT59" )
				)
				( pin "smbdat"
					( attribute "PN" "CW58"
						( Origin gPackager )
					)
					( objectStatus "U5D1.CW58" )
				)
				( pin "socket_id(0)"
					( attribute "PN" "AU22"
						( Origin gPackager )
					)
					( objectStatus "U5D1.AU22" )
				)
				( pin "socket_id(1)"
					( attribute "PN" "AU16"
						( Origin gPackager )
					)
					( objectStatus "U5D1.AU16" )
				)
				( pin "socket_id(2)"
					( attribute "PN" "AU20"
						( Origin gPackager )
					)
					( objectStatus "U5D1.AU20" )
				)
				( pin "svidalert_n(0)"
					( attribute "PN" "DE44"
						( Origin gPackager )
					)
					( objectStatus "U5D1.DE44" )
				)
				( pin "svidalert_n(1)"
					( attribute "PN" "DL44"
						( Origin gPackager )
					)
					( objectStatus "U5D1.DL44" )
				)
				( pin "svidclk(0)"
					( attribute "PN" "DC44"
						( Origin gPackager )
					)
					( objectStatus "U5D1.DC44" )
				)
				( pin "svidclk(1)"
					( attribute "PN" "DG44"
						( Origin gPackager )
					)
					( objectStatus "U5D1.DG44" )
				)
				( pin "sviddata(0)"
					( attribute "PN" "DB45"
						( Origin gPackager )
					)
					( objectStatus "U5D1.DB45" )
				)
				( pin "sviddata(1)"
					( attribute "PN" "DJ44"
						( Origin gPackager )
					)
					( objectStatus "U5D1.DJ44" )
				)
				( pin "tck"
					( attribute "PN" "AA14"
						( Origin gPackager )
					)
					( objectStatus "U5D1.AA14" )
				)
				( pin "tdi"
					( attribute "PN" "AC14"
						( Origin gPackager )
					)
					( objectStatus "U5D1.AC14" )
				)
				( pin "tdo"
					( attribute "PN" "AE14"
						( Origin gPackager )
					)
					( objectStatus "U5D1.AE14" )
				)
				( pin "test_12"
					( attribute "PN" "AY19"
						( Origin gPackager )
					)
					( objectStatus "U5D1.AY19" )
				)
				( pin "test_13"
					( attribute "PN" "DB51"
						( Origin gPackager )
					)
					( objectStatus "U5D1.DB51" )
				)
				( pin "test_14"
					( attribute "PN" "DC50"
						( Origin gPackager )
					)
					( objectStatus "U5D1.DC50" )
				)
				( pin "test_15"
					( attribute "PN" "AW14"
						( Origin gPackager )
					)
					( objectStatus "U5D1.AW14" )
				)
				( pin "thermtrip_n"
					( attribute "PN" "AB15"
						( Origin gPackager )
					)
					( objectStatus "U5D1.AB15" )
				)
				( pin "tms"
					( attribute "PN" "W14"
						( Origin gPackager )
					)
					( objectStatus "U5D1.W14" )
				)
				( pin "trst_n"
					( attribute "PN" "Y13"
						( Origin gPackager )
					)
					( objectStatus "U5D1.Y13" )
				)
				( pin "tsc_sync"
					( attribute "PN" "AM11"
						( Origin gPackager )
					)
					( objectStatus "U5D1.AM11" )
				)
				( pin "txt_agent"
					( attribute "PN" "AW18"
						( Origin gPackager )
					)
					( objectStatus "U5D1.AW18" )
				)
				( pin "txt_plten"
					( attribute "PN" "AV15"
						( Origin gPackager )
					)
					( objectStatus "U5D1.AV15" )
				)
				( pin "upi01_rbias(0)"
					( attribute "PN" "AT29"
						( Origin gPackager )
					)
					( objectStatus "U5D1.AT29" )
				)
				( pin "upi01_rbias(1)"
					( attribute "PN" "AP29"
						( Origin gPackager )
					)
					( objectStatus "U5D1.AP29" )
				)
				( pin "upi2_rbias(0)"
					( attribute "PN" "CL28"
						( Origin gPackager )
					)
					( objectStatus "U5D1.CL28" )
				)
				( pin "upi2_rbias(1)"
					( attribute "PN" "CK29"
						( Origin gPackager )
					)
					( objectStatus "U5D1.CK29" )
				)
			)
			( gate "@baseboard_fab2_lib.baseboard_fab2(sch_1):page22_i188"
				( attribute "CDS_LIB" "mstr_discrete"
					( Origin gPackager )
				)
				( attribute "CDS_LOCATION" "R5R1"
					( Origin gPackager )
				)
				( attribute "CDS_SEC" "1"
					( Origin gPackager )
				)
				( attribute "LOCATION" "R5R1"
					( Origin gFrontEnd )
				)
				( attribute "MATERIAL" "CHIP"
					( Origin gFrontEnd )
				)
				( attribute "PACK_TYPE" "0402"
					( Origin gFrontEnd )
				)
				( attribute "PART_NUMBER" "G21796-047"
					( Origin gFrontEnd )
				)
				( attribute "PHYS_PAGE" "22"
					( Origin gFrontEnd )
				)
				( attribute "ROOM" "CPU0"
					( Origin gFrontEnd )
				)
				( attribute "ROT" "0"
					( Origin gFrontEnd )
				)
				( attribute "SEC" "1"
					( Origin gFrontEnd )
				)
				( attribute "SEC_TYPE" "0402"
					( Origin gFrontEnd )
				)
				( attribute "TOLERANCE" "1%"
					( Origin gFrontEnd )
				)
				( attribute "VALUE" "49.9"
					( Origin gFrontEnd )
				)
				( attribute "VER" "2"
					( Origin gFrontEnd )
				)
				( attribute "WATTAGE" "1/16W"
					( Origin gFrontEnd )
				)
				( attribute "XY" "(-300,2775)"
					( Origin gFrontEnd )
				)
				( attribute "CHIPS_PART_NAME" "RES"
					( Origin gPackager )
				)
				( attribute "CDS_PART_NAME" "RES_0402-49.9,1%,1/16W,CHIP,G2A"
					( Origin gPackager )
				)
				( objectStatus "R5R1" )
				( pin "a"
					( attribute "PN" "1"
						( Origin gPackager )
					)
					( objectStatus "R5R1.1" )
				)
				( pin "b"
					( attribute "PN" "2"
						( Origin gPackager )
					)
					( objectStatus "R5R1.2" )
				)
			)
			( gate "@baseboard_fab2_lib.baseboard_fab2(sch_1):page22_i190"
				( attribute "CDS_LIB" "mstr_discrete"
					( Origin gPackager )
				)
				( attribute "CDS_LOCATION" "R5P4"
					( Origin gPackager )
				)
				( attribute "CDS_SEC" "1"
					( Origin gPackager )
				)
				( attribute "LOCATION" "R5P4"
					( Origin gFrontEnd )
				)
				( attribute "MATERIAL" "CHIP"
					( Origin gFrontEnd )
				)
				( attribute "PACK_TYPE" "0402"
					( Origin gFrontEnd )
				)
				( attribute "PART_NUMBER" "G21796-047"
					( Origin gFrontEnd )
				)
				( attribute "PHYS_PAGE" "22"
					( Origin gFrontEnd )
				)
				( attribute "ROOM" "CPU0"
					( Origin gFrontEnd )
				)
				( attribute "ROT" "0"
					( Origin gFrontEnd )
				)
				( attribute "SEC" "1"
					( Origin gFrontEnd )
				)
				( attribute "SEC_TYPE" "0402"
					( Origin gFrontEnd )
				)
				( attribute "TOLERANCE" "1%"
					( Origin gFrontEnd )
				)
				( attribute "VALUE" "49.9"
					( Origin gFrontEnd )
				)
				( attribute "VER" "2"
					( Origin gFrontEnd )
				)
				( attribute "WATTAGE" "1/16W"
					( Origin gFrontEnd )
				)
				( attribute "XY" "(-575,2775)"
					( Origin gFrontEnd )
				)
				( attribute "CHIPS_PART_NAME" "RES"
					( Origin gPackager )
				)
				( attribute "CDS_PART_NAME" "RES_0402-49.9,1%,1/16W,CHIP,G2A"
					( Origin gPackager )
				)
				( objectStatus "R5P4" )
				( pin "a"
					( attribute "PN" "1"
						( Origin gPackager )
					)
					( objectStatus "R5P4.1" )
				)
				( pin "b"
					( attribute "PN" "2"
						( Origin gPackager )
					)
					( objectStatus "R5P4.2" )
				)
			)
			( gate "@baseboard_fab2_lib.baseboard_fab2(sch_1):page22_i204"
				( attribute "CDS_LIB" "chpset_lib"
					( Origin gPackager )
				)
				( attribute "CDS_LOCATION" "U5D1"
					( Origin gPackager )
				)
				( attribute "CDS_SEC" "2"
					( Origin gPackager )
				)
				( attribute "LOCATION" "U5D1"
					( Origin gFrontEnd )
				)
				( attribute "MATERIAL" "IC"
					( Origin gFrontEnd )
				)
				( attribute "PACK_TYPE" "BGA1"
					( Origin gFrontEnd )
				)
				( attribute "PART_NUMBER" "TBD"
					( Origin gFrontEnd )
				)
				( attribute "PHYS_PAGE" "22"
					( Origin gFrontEnd )
				)
				( attribute "ROOM" "CPU0"
					( Origin gFrontEnd )
				)
				( attribute "ROT" "0"
					( Origin gFrontEnd )
				)
				( attribute "SEC" "2"
					( Origin gFrontEnd )
				)
				( attribute "SEC_TYPE" "BGA1"
					( Origin gFrontEnd )
				)
				( attribute "VER" "2"
					( Origin gFrontEnd )
				)
				( attribute "XY" "(-4150,2550)"
					( Origin gFrontEnd )
				)
				( attribute "CHIPS_PART_NAME" "SKX_EXT_B"
					( Origin gPackager )
				)
				( attribute "CDS_PART_NAME" "SKX_EXT_B_BGA1-IC,TBD"
					( Origin gPackager )
				)
				( objectStatus "U5D1" )
				( pin "debug_en_n"
					( attribute "PN" "AV21"
						( Origin gPackager )
					)
					( objectStatus "U5D1.AV21" )
				)
				( pin "dmimode_override"
					( attribute "PN" "AW12"
						( Origin gPackager )
					)
					( objectStatus "U5D1.AW12" )
				)
				( pin "fivr_fault"
					( attribute "PN" "AU14"
						( Origin gPackager )
					)
					( objectStatus "U5D1.AU14" )
				)
				( pin "pwr_debug_n"
					( attribute "PN" "AP17"
						( Origin gPackager )
					)
					( objectStatus "U5D1.AP17" )
				)
				( pin "rsvd(194)"
					( attribute "PN" "AP61"
						( Origin gPackager )
					)
					( objectStatus "U5D1.AP61" )
				)
				( pin "rsvd(195)"
					( attribute "PN" "AP27"
						( Origin gPackager )
					)
					( objectStatus "U5D1.AP27" )
				)
				( pin "rsvd(196)"
					( attribute "PN" "AP25"
						( Origin gPackager )
					)
					( objectStatus "U5D1.AP25" )
				)
				( pin "rsvd(197)"
					( attribute "PN" "AP23"
						( Origin gPackager )
					)
					( objectStatus "U5D1.AP23" )
				)
				( pin "rsvd(198)"
					( attribute "PN" "AN62"
						( Origin gPackager )
					)
					( objectStatus "U5D1.AN62" )
				)
				( pin "rsvd(199)"
					( attribute "PN" "AN60"
						( Origin gPackager )
					)
					( objectStatus "U5D1.AN60" )
				)
				( pin "rsvd(200)"
					( attribute "PN" "AN26"
						( Origin gPackager )
					)
					( objectStatus "U5D1.AN26" )
				)
				( pin "rsvd(201)"
					( attribute "PN" "AN24"
						( Origin gPackager )
					)
					( objectStatus "U5D1.AN24" )
				)
				( pin "rsvd(202)"
					( attribute "PN" "AN22"
						( Origin gPackager )
					)
					( objectStatus "U5D1.AN22" )
				)
				( pin "rsvd(203)"
					( attribute "PN" "AN18"
						( Origin gPackager )
					)
					( objectStatus "U5D1.AN18" )
				)
				( pin "rsvd(204)"
					( attribute "PN" "AM61"
						( Origin gPackager )
					)
					( objectStatus "U5D1.AM61" )
				)
				( pin "rsvd(205)"
					( attribute "PN" "AM59"
						( Origin gPackager )
					)
					( objectStatus "U5D1.AM59" )
				)
				( pin "rsvd(206)"
					( attribute "PN" "AM27"
						( Origin gPackager )
					)
					( objectStatus "U5D1.AM27" )
				)
				( pin "rsvd(207)"
					( attribute "PN" "AM25"
						( Origin gPackager )
					)
					( objectStatus "U5D1.AM25" )
				)
				( pin "rsvd(208)"
					( attribute "PN" "AM23"
						( Origin gPackager )
					)
					( objectStatus "U5D1.AM23" )
				)
				( pin "rsvd(209)"
					( attribute "PN" "AM21"
						( Origin gPackager )
					)
					( objectStatus "U5D1.AM21" )
				)
				( pin "rsvd(210)"
					( attribute "PN" "AL62"
						( Origin gPackager )
					)
					( objectStatus "U5D1.AL62" )
				)
				( pin "rsvd(211)"
					( attribute "PN" "AL60"
						( Origin gPackager )
					)
					( objectStatus "U5D1.AL60" )
				)
				( pin "rsvd(212)"
					( attribute "PN" "AL58"
						( Origin gPackager )
					)
					( objectStatus "U5D1.AL58" )
				)
				( pin "rsvd(213)"
					( attribute "PN" "AL26"
						( Origin gPackager )
					)
					( objectStatus "U5D1.AL26" )
				)
				( pin "rsvd(214)"
					( attribute "PN" "AL22"
						( Origin gPackager )
					)
					( objectStatus "U5D1.AL22" )
				)
				( pin "rsvd(215)"
					( attribute "PN" "AL20"
						( Origin gPackager )
					)
					( objectStatus "U5D1.AL20" )
				)
				( pin "rsvd(216)"
					( attribute "PN" "AK69"
						( Origin gPackager )
					)
					( objectStatus "U5D1.AK69" )
				)
				( pin "rsvd(217)"
					( attribute "PN" "AK61"
						( Origin gPackager )
					)
					( objectStatus "U5D1.AK61" )
				)
				( pin "rsvd(218)"
					( attribute "PN" "AK59"
						( Origin gPackager )
					)
					( objectStatus "U5D1.AK59" )
				)
				( pin "rsvd(219)"
					( attribute "PN" "AK57"
						( Origin gPackager )
					)
					( objectStatus "U5D1.AK57" )
				)
				( pin "rsvd(220)"
					( attribute "PN" "AK27"
						( Origin gPackager )
					)
					( objectStatus "U5D1.AK27" )
				)
				( pin "rsvd(221)"
					( attribute "PN" "AK21"
						( Origin gPackager )
					)
					( objectStatus "U5D1.AK21" )
				)
				( pin "rsvd(222)"
					( attribute "PN" "AJ70"
						( Origin gPackager )
					)
					( objectStatus "U5D1.AJ70" )
				)
				( pin "rsvd(223)"
					( attribute "PN" "AJ62"
						( Origin gPackager )
					)
					( objectStatus "U5D1.AJ62" )
				)
				( pin "rsvd(224)"
					( attribute "PN" "AJ60"
						( Origin gPackager )
					)
					( objectStatus "U5D1.AJ60" )
				)
				( pin "rsvd(225)"
					( attribute "PN" "AJ58"
						( Origin gPackager )
					)
					( objectStatus "U5D1.AJ58" )
				)
				( pin "rsvd(226)"
					( attribute "PN" "AJ56"
						( Origin gPackager )
					)
					( objectStatus "U5D1.AJ56" )
				)
				( pin "rsvd(227)"
					( attribute "PN" "AJ20"
						( Origin gPackager )
					)
					( objectStatus "U5D1.AJ20" )
				)
				( pin "rsvd(228)"
					( attribute "PN" "AH73"
						( Origin gPackager )
					)
					( objectStatus "U5D1.AH73" )
				)
				( pin "rsvd(229)"
					( attribute "PN" "AH71"
						( Origin gPackager )
					)
					( objectStatus "U5D1.AH71" )
				)
				( pin "rsvd(230)"
					( attribute "PN" "AH57"
						( Origin gPackager )
					)
					( objectStatus "U5D1.AH57" )
				)
				( pin "rsvd(231)"
					( attribute "PN" "AH55"
						( Origin gPackager )
					)
					( objectStatus "U5D1.AH55" )
				)
				( pin "rsvd(232)"
					( attribute "PN" "AH19"
						( Origin gPackager )
					)
					( objectStatus "U5D1.AH19" )
				)
				( pin "rsvd(233)"
					( attribute "PN" "AH15"
						( Origin gPackager )
					)
					( objectStatus "U5D1.AH15" )
				)
				( pin "rsvd(234)"
					( attribute "PN" "AG72"
						( Origin gPackager )
					)
					( objectStatus "U5D1.AG72" )
				)
				( pin "rsvd(235)"
					( attribute "PN" "AG56"
						( Origin gPackager )
					)
					( objectStatus "U5D1.AG56" )
				)
				( pin "rsvd(236)"
					( attribute "PN" "AG54"
						( Origin gPackager )
					)
					( objectStatus "U5D1.AG54" )
				)
				( pin "rsvd(237)"
					( attribute "PN" "AG52"
						( Origin gPackager )
					)
					( objectStatus "U5D1.AG52" )
				)
				( pin "rsvd(238)"
					( attribute "PN" "AG50"
						( Origin gPackager )
					)
					( objectStatus "U5D1.AG50" )
				)
				( pin "rsvd(239)"
					( attribute "PN" "AG48"
						( Origin gPackager )
					)
					( objectStatus "U5D1.AG48" )
				)
				( pin "rsvd(240)"
					( attribute "PN" "AG20"
						( Origin gPackager )
					)
					( objectStatus "U5D1.AG20" )
				)
				( pin "rsvd(241)"
					( attribute "PN" "AF71"
						( Origin gPackager )
					)
					( objectStatus "U5D1.AF71" )
				)
				( pin "rsvd(242)"
					( attribute "PN" "AF53"
						( Origin gPackager )
					)
					( objectStatus "U5D1.AF53" )
				)
				( pin "rsvd(243)"
					( attribute "PN" "AF51"
						( Origin gPackager )
					)
					( objectStatus "U5D1.AF51" )
				)
				( pin "rsvd(244)"
					( attribute "PN" "AF49"
						( Origin gPackager )
					)
					( objectStatus "U5D1.AF49" )
				)
				( pin "rsvd(245)"
					( attribute "PN" "AF47"
						( Origin gPackager )
					)
					( objectStatus "U5D1.AF47" )
				)
				( pin "rsvd(246)"
					( attribute "PN" "AF19"
						( Origin gPackager )
					)
					( objectStatus "U5D1.AF19" )
				)
				( pin "rsvd(247)"
					( attribute "PN" "AE72"
						( Origin gPackager )
					)
					( objectStatus "U5D1.AE72" )
				)
				( pin "rsvd(248)"
					( attribute "PN" "AE52"
						( Origin gPackager )
					)
					( objectStatus "U5D1.AE52" )
				)
				( pin "rsvd(249)"
					( attribute "PN" "AE50"
						( Origin gPackager )
					)
					( objectStatus "U5D1.AE50" )
				)
				( pin "rsvd(250)"
					( attribute "PN" "AE48"
						( Origin gPackager )
					)
					( objectStatus "U5D1.AE48" )
				)
				( pin "rsvd(251)"
					( attribute "PN" "AE46"
						( Origin gPackager )
					)
					( objectStatus "U5D1.AE46" )
				)
				( pin "rsvd(252)"
					( attribute "PN" "AD51"
						( Origin gPackager )
					)
					( objectStatus "U5D1.AD51" )
				)
				( pin "rsvd(253)"
					( attribute "PN" "AD49"
						( Origin gPackager )
					)
					( objectStatus "U5D1.AD49" )
				)
				( pin "rsvd(254)"
					( attribute "PN" "AD47"
						( Origin gPackager )
					)
					( objectStatus "U5D1.AD47" )
				)
				( pin "rsvd(255)"
					( attribute "CDS_NOT_ON_SYM" "TRUE"
						( Origin gFrontEnd )
					)
				)
				( pin "rsvd(256)"
					( attribute "PN" "Y65"
						( Origin gPackager )
					)
					( objectStatus "U5D1.Y65" )
				)
				( pin "rsvd(257)"
					( attribute "PN" "Y23"
						( Origin gPackager )
					)
					( objectStatus "U5D1.Y23" )
				)
				( pin "rsvd(258)"
					( attribute "PN" "W66"
						( Origin gPackager )
					)
					( objectStatus "U5D1.W66" )
				)
				( pin "rsvd(259)"
					( attribute "PN" "V67"
						( Origin gPackager )
					)
					( objectStatus "U5D1.V67" )
				)
				( pin "rsvd(260)"
					( attribute "PN" "V65"
						( Origin gPackager )
					)
					( objectStatus "U5D1.V65" )
				)
				( pin "rsvd(261)"
					( attribute "PN" "U66"
						( Origin gPackager )
					)
					( objectStatus "U5D1.U66" )
				)
				( pin "rsvd(262)"
					( attribute "PN" "T67"
						( Origin gPackager )
					)
					( objectStatus "U5D1.T67" )
				)
				( pin "rsvd(263)"
					( attribute "PN" "R66"
						( Origin gPackager )
					)
					( objectStatus "U5D1.R66" )
				)
				( pin "rsvd(264)"
					( attribute "PN" "R62"
						( Origin gPackager )
					)
					( objectStatus "U5D1.R62" )
				)
				( pin "rsvd(265)"
					( attribute "PN" "P65"
						( Origin gPackager )
					)
					( objectStatus "U5D1.P65" )
				)
				( pin "rsvd(266)"
					( attribute "PN" "M63"
						( Origin gPackager )
					)
					( objectStatus "U5D1.M63" )
				)
				( pin "rsvd(267)"
					( attribute "PN" "K61"
						( Origin gPackager )
					)
					( objectStatus "U5D1.K61" )
				)
				( pin "rsvd(268)"
					( attribute "PN" "J62"
						( Origin gPackager )
					)
					( objectStatus "U5D1.J62" )
				)
				( pin "rsvd(269)"
					( attribute "PN" "J46"
						( Origin gPackager )
					)
					( objectStatus "U5D1.J46" )
				)
				( pin "rsvd(270)"
					( attribute "PN" "H85"
						( Origin gPackager )
					)
					( objectStatus "U5D1.H85" )
				)
				( pin "rsvd(271)"
					( attribute "PN" "H83"
						( Origin gPackager )
					)
					( objectStatus "U5D1.H83" )
				)
				( pin "rsvd(272)"
					( attribute "PN" "H1"
						( Origin gPackager )
					)
					( objectStatus "U5D1.H1" )
				)
				( pin "rsvd(273)"
					( attribute "PN" "G84"
						( Origin gPackager )
					)
					( objectStatus "U5D1.G84" )
				)
				( pin "rsvd(274)"
					( attribute "PN" "G64"
						( Origin gPackager )
					)
					( objectStatus "U5D1.G64" )
				)
				( pin "rsvd(275)"
					( attribute "PN" "G2"
						( Origin gPackager )
					)
					( objectStatus "U5D1.G2" )
				)
				( pin "rsvd(276)"
					( attribute "PN" "F83"
						( Origin gPackager )
					)
					( objectStatus "U5D1.F83" )
				)
				( pin "rsvd(277)"
					( attribute "PN" "F65"
						( Origin gPackager )
					)
					( objectStatus "U5D1.F65" )
				)
				( pin "rsvd(278)"
					( attribute "PN" "F23"
						( Origin gPackager )
					)
					( objectStatus "U5D1.F23" )
				)
				( pin "rsvd(279)"
					( attribute "PN" "F3"
						( Origin gPackager )
					)
					( objectStatus "U5D1.F3" )
				)
				( pin "rsvd(280)"
					( attribute "PN" "E84"
						( Origin gPackager )
					)
					( objectStatus "U5D1.E84" )
				)
				( pin "rsvd(281)"
					( attribute "PN" "E24"
						( Origin gPackager )
					)
					( objectStatus "U5D1.E24" )
				)
				( pin "rsvd(282)"
					( attribute "PN" "E4"
						( Origin gPackager )
					)
					( objectStatus "U5D1.E4" )
				)
				( pin "rsvd(283)"
					( attribute "PN" "E2"
						( Origin gPackager )
					)
					( objectStatus "U5D1.E2" )
				)
				( pin "rsvd(284)"
					( attribute "PN" "D83"
						( Origin gPackager )
					)
					( objectStatus "U5D1.D83" )
				)
				( pin "rsvd(285)"
					( attribute "PN" "D65"
						( Origin gPackager )
					)
					( objectStatus "U5D1.D65" )
				)
				( pin "rsvd(286)"
					( attribute "PN" "D17"
						( Origin gPackager )
					)
					( objectStatus "U5D1.D17" )
				)
				( pin "rsvd(287)"
					( attribute "PN" "D5"
						( Origin gPackager )
					)
					( objectStatus "U5D1.D5" )
				)
				( pin "rsvd(288)"
					( attribute "PN" "C82"
						( Origin gPackager )
					)
					( objectStatus "U5D1.C82" )
				)
				( pin "rsvd(289)"
					( attribute "PN" "C24"
						( Origin gPackager )
					)
					( objectStatus "U5D1.C24" )
				)
				( pin "rsvd(290)"
					( attribute "PN" "C18"
						( Origin gPackager )
					)
					( objectStatus "U5D1.C18" )
				)
				( pin "rsvd(291)"
					( attribute "PN" "C6"
						( Origin gPackager )
					)
					( objectStatus "U5D1.C6" )
				)
				( pin "rsvd(292)"
					( attribute "PN" "B81"
						( Origin gPackager )
					)
					( objectStatus "U5D1.B81" )
				)
				( pin "rsvd(293)"
					( attribute "PN" "B77"
						( Origin gPackager )
					)
					( objectStatus "U5D1.B77" )
				)
				( pin "rsvd(294)"
					( attribute "PN" "B17"
						( Origin gPackager )
					)
					( objectStatus "U5D1.B17" )
				)
				( pin "rsvd(295)"
					( attribute "PN" "B15"
						( Origin gPackager )
					)
					( objectStatus "U5D1.B15" )
				)
				( pin "rsvd(296)"
					( attribute "PN" "B13"
						( Origin gPackager )
					)
					( objectStatus "U5D1.B13" )
				)
				( pin "rsvd(297)"
					( attribute "CDS_NOT_ON_SYM" "TRUE"
						( Origin gFrontEnd )
					)
				)
				( pin "rsvd(298)"
					( attribute "PN" "B7"
						( Origin gPackager )
					)
					( objectStatus "U5D1.B7" )
				)
				( pin "rsvd(299)"
					( attribute "PN" "B3"
						( Origin gPackager )
					)
					( objectStatus "U5D1.B3" )
				)
				( pin "rsvd(300)"
					( attribute "PN" "A24"
						( Origin gPackager )
					)
					( objectStatus "U5D1.A24" )
				)
				( pin "rsvd(301)"
					( attribute "PN" "A16"
						( Origin gPackager )
					)
					( objectStatus "U5D1.A16" )
				)
				( pin "rsvd(302)"
					( attribute "PN" "A14"
						( Origin gPackager )
					)
					( objectStatus "U5D1.A14" )
				)
				( pin "rsvd(303)"
					( attribute "PN" "A6"
						( Origin gPackager )
					)
					( objectStatus "U5D1.A6" )
				)
				( pin "rsvd(304)"
					( attribute "PN" "A4"
						( Origin gPackager )
					)
					( objectStatus "U5D1.A4" )
				)
				( pin "test_1"
					( attribute "PN" "AF45"
						( Origin gPackager )
					)
					( objectStatus "U5D1.AF45" )
				)
				( pin "test_2"
					( attribute "PN" "AG46"
						( Origin gPackager )
					)
					( objectStatus "U5D1.AG46" )
				)
				( pin "test_3"
					( attribute "PN" "AM13"
						( Origin gPackager )
					)
					( objectStatus "U5D1.AM13" )
				)
				( pin "test_4"
					( attribute "PN" "AN12"
						( Origin gPackager )
					)
					( objectStatus "U5D1.AN12" )
				)
				( pin "test_5"
					( attribute "PN" "AN14"
						( Origin gPackager )
					)
					( objectStatus "U5D1.AN14" )
				)
				( pin "test_11"
					( attribute "PN" "AY13"
						( Origin gPackager )
					)
					( objectStatus "U5D1.AY13" )
				)
			)
			( gate "@baseboard_fab2_lib.baseboard_fab2(sch_1):page23_i172"
				( attribute "CDS_LIB" "chpset_lib"
					( Origin gPackager )
				)
				( attribute "CDS_LOCATION" "U5D1"
					( Origin gPackager )
				)
				( attribute "CDS_SEC" "3"
					( Origin gPackager )
				)
				( attribute "LOCATION" "U5D1"
					( Origin gFrontEnd )
				)
				( attribute "MATERIAL" "IC"
					( Origin gFrontEnd )
				)
				( attribute "PACK_TYPE" "BGA1"
					( Origin gFrontEnd )
				)
				( attribute "PART_NUMBER" "TBD"
					( Origin gFrontEnd )
				)
				( attribute "PHYS_PAGE" "23"
					( Origin gFrontEnd )
				)
				( attribute "ROOM" "CPU0"
					( Origin gFrontEnd )
				)
				( attribute "ROT" "0"
					( Origin gFrontEnd )
				)
				( attribute "SEC" "3"
					( Origin gFrontEnd )
				)
				( attribute "SEC_TYPE" "BGA1"
					( Origin gFrontEnd )
				)
				( attribute "VER" "3"
					( Origin gFrontEnd )
				)
				( attribute "XY" "(-4200,2600)"
					( Origin gFrontEnd )
				)
				( attribute "CHIPS_PART_NAME" "SKX_EXT_B"
					( Origin gPackager )
				)
				( attribute "CDS_PART_NAME" "SKX_EXT_B_BGA1-IC,TBD"
					( Origin gPackager )
				)
				( objectStatus "U5D1" )
				( pin "ddr0_act_n"
					( attribute "PN" "J60"
						( Origin gPackager )
					)
					( objectStatus "U5D1.J60" )
				)
				( pin "ddr0_alert_n"
					( attribute "PN" "B61"
						( Origin gPackager )
					)
					( objectStatus "U5D1.B61" )
				)
				( pin "ddr0_ba(0)"
					( attribute "PN" "C52"
						( Origin gPackager )
					)
					( objectStatus "U5D1.C52" )
				)
				( pin "ddr0_ba(1)"
					( attribute "PN" "G54"
						( Origin gPackager )
					)
					( objectStatus "U5D1.G54" )
				)
				( pin "ddr0_bg(0)"
					( attribute "PN" "D61"
						( Origin gPackager )
					)
					( objectStatus "U5D1.D61" )
				)
				( pin "ddr0_bg(1)"
					( attribute "PN" "F63"
						( Origin gPackager )
					)
					( objectStatus "U5D1.F63" )
				)
				( pin "ddr0_cid(2)"
					( attribute "PN" "G46"
						( Origin gPackager )
					)
					( objectStatus "U5D1.G46" )
				)
				( pin "ddr0_cke(0)"
					( attribute "PN" "C62"
						( Origin gPackager )
					)
					( objectStatus "U5D1.C62" )
				)
				( pin "ddr0_cke(1)"
					( attribute "PN" "C64"
						( Origin gPackager )
					)
					( objectStatus "U5D1.C64" )
				)
				( pin "ddr0_cke(2)"
					( attribute "PN" "B63"
						( Origin gPackager )
					)
					( objectStatus "U5D1.B63" )
				)
				( pin "ddr0_cke(3)"
					( attribute "PN" "D63"
						( Origin gPackager )
					)
					( objectStatus "U5D1.D63" )
				)
				( pin "ddr0_clk_dn(0)"
					( attribute "PN" "F55"
						( Origin gPackager )
					)
					( objectStatus "U5D1.F55" )
				)
				( pin "ddr0_clk_dn(1)"
					( attribute "PN" "C54"
						( Origin gPackager )
					)
					( objectStatus "U5D1.C54" )
				)
				( pin "ddr0_clk_dn(2)"
					( attribute "PN" "J56"
						( Origin gPackager )
					)
					( objectStatus "U5D1.J56" )
				)
				( pin "ddr0_clk_dn(3)"
					( attribute "PN" "C56"
						( Origin gPackager )
					)
					( objectStatus "U5D1.C56" )
				)
				( pin "ddr0_clk_dp(0)"
					( attribute "PN" "D55"
						( Origin gPackager )
					)
					( objectStatus "U5D1.D55" )
				)
				( pin "ddr0_clk_dp(1)"
					( attribute "PN" "B55"
						( Origin gPackager )
					)
					( objectStatus "U5D1.B55" )
				)
				( pin "ddr0_clk_dp(2)"
					( attribute "PN" "G56"
						( Origin gPackager )
					)
					( objectStatus "U5D1.G56" )
				)
				( pin "ddr0_clk_dp(3)"
					( attribute "PN" "B57"
						( Origin gPackager )
					)
					( objectStatus "U5D1.B57" )
				)
				( pin "ddr0_cs_n(0)"
					( attribute "PN" "G52"
						( Origin gPackager )
					)
					( objectStatus "U5D1.G52" )
				)
				( pin "ddr0_cs_n(1)"
					( attribute "PN" "F49"
						( Origin gPackager )
					)
					( objectStatus "U5D1.F49" )
				)
				( pin "ddr0_cs_n(2)"
					( attribute "PN" "D47"
						( Origin gPackager )
					)
					( objectStatus "U5D1.D47" )
				)
				( pin "ddr0_cs_n(3)"
					( attribute "PN" "F47"
						( Origin gPackager )
					)
					( objectStatus "U5D1.F47" )
				)
				( pin "ddr0_cs_n(4)"
					( attribute "PN" "B51"
						( Origin gPackager )
					)
					( objectStatus "U5D1.B51" )
				)
				( pin "ddr0_cs_n(5)"
					( attribute "PN" "D49"
						( Origin gPackager )
					)
					( objectStatus "U5D1.D49" )
				)
				( pin "ddr0_cs_n(6)"
					( attribute "PN" "F45"
						( Origin gPackager )
					)
					( objectStatus "U5D1.F45" )
				)
				( pin "ddr0_cs_n(7)"
					( attribute "PN" "K45"
						( Origin gPackager )
					)
					( objectStatus "U5D1.K45" )
				)
				( pin "ddr0_dq(0)"
					( attribute "PN" "AN86"
						( Origin gPackager )
					)
					( objectStatus "U5D1.AN86" )
				)
				( pin "ddr0_dq(1)"
					( attribute "PN" "AN84"
						( Origin gPackager )
					)
					( objectStatus "U5D1.AN84" )
				)
				( pin "ddr0_dq(2)"
					( attribute "PN" "AE86"
						( Origin gPackager )
					)
					( objectStatus "U5D1.AE86" )
				)
				( pin "ddr0_dq(3)"
					( attribute "PN" "AE84"
						( Origin gPackager )
					)
					( objectStatus "U5D1.AE84" )
				)
				( pin "ddr0_dq(4)"
					( attribute "PN" "AR86"
						( Origin gPackager )
					)
					( objectStatus "U5D1.AR86" )
				)
				( pin "ddr0_dq(5)"
					( attribute "PN" "AR84"
						( Origin gPackager )
					)
					( objectStatus "U5D1.AR84" )
				)
				( pin "ddr0_dq(6)"
					( attribute "PN" "AG86"
						( Origin gPackager )
					)
					( objectStatus "U5D1.AG86" )
				)
				( pin "ddr0_dq(7)"
					( attribute "PN" "AG84"
						( Origin gPackager )
					)
					( objectStatus "U5D1.AG84" )
				)
				( pin "ddr0_dq(8)"
					( attribute "PN" "W86"
						( Origin gPackager )
					)
					( objectStatus "U5D1.W86" )
				)
				( pin "ddr0_dq(9)"
					( attribute "PN" "W84"
						( Origin gPackager )
					)
					( objectStatus "U5D1.W84" )
				)
				( pin "ddr0_dq(10)"
					( attribute "PN" "L86"
						( Origin gPackager )
					)
					( objectStatus "U5D1.L86" )
				)
				( pin "ddr0_dq(11)"
					( attribute "PN" "L84"
						( Origin gPackager )
					)
					( objectStatus "U5D1.L84" )
				)
				( pin "ddr0_dq(12)"
					( attribute "PN" "AA86"
						( Origin gPackager )
					)
					( objectStatus "U5D1.AA86" )
				)
				( pin "ddr0_dq(13)"
					( attribute "PN" "AA84"
						( Origin gPackager )
					)
					( objectStatus "U5D1.AA84" )
				)
				( pin "ddr0_dq(14)"
					( attribute "PN" "N86"
						( Origin gPackager )
					)
					( objectStatus "U5D1.N86" )
				)
				( pin "ddr0_dq(15)"
					( attribute "PN" "N84"
						( Origin gPackager )
					)
					( objectStatus "U5D1.N84" )
				)
				( pin "ddr0_dq(16)"
					( attribute "PN" "V81"
						( Origin gPackager )
					)
					( objectStatus "U5D1.V81" )
				)
				( pin "ddr0_dq(17)"
					( attribute "PN" "T79"
						( Origin gPackager )
					)
					( objectStatus "U5D1.T79" )
				)
				( pin "ddr0_dq(18)"
					( attribute "PN" "N82"
						( Origin gPackager )
					)
					( objectStatus "U5D1.N82" )
				)
				( pin "ddr0_dq(19)"
					( attribute "PN" "M81"
						( Origin gPackager )
					)
					( objectStatus "U5D1.M81" )
				)
				( pin "ddr0_dq(20)"
					( attribute "PN" "W80"
						( Origin gPackager )
					)
					( objectStatus "U5D1.W80" )
				)
				( pin "ddr0_dq(21)"
					( attribute "PN" "V79"
						( Origin gPackager )
					)
					( objectStatus "U5D1.V79" )
				)
				( pin "ddr0_dq(22)"
					( attribute "PN" "R82"
						( Origin gPackager )
					)
					( objectStatus "U5D1.R82" )
				)
				( pin "ddr0_dq(23)"
					( attribute "PN" "N80"
						( Origin gPackager )
					)
					( objectStatus "U5D1.N80" )
				)
				( pin "ddr0_dq(24)"
					( attribute "PN" "L76"
						( Origin gPackager )
					)
					( objectStatus "U5D1.L76" )
				)
				( pin "ddr0_dq(25)"
					( attribute "PN" "R76"
						( Origin gPackager )
					)
					( objectStatus "U5D1.R76" )
				)
				( pin "ddr0_dq(26)"
					( attribute "PN" "M73"
						( Origin gPackager )
					)
					( objectStatus "U5D1.M73" )
				)
				( pin "ddr0_dq(27)"
					( attribute "PN" "P73"
						( Origin gPackager )
					)
					( objectStatus "U5D1.P73" )
				)
				( pin "ddr0_dq(28)"
					( attribute "PN" "M77"
						( Origin gPackager )
					)
					( objectStatus "U5D1.M77" )
				)
				( pin "ddr0_dq(29)"
					( attribute "PN" "P77"
						( Origin gPackager )
					)
					( objectStatus "U5D1.P77" )
				)
				( pin "ddr0_dq(30)"
					( attribute "PN" "L74"
						( Origin gPackager )
					)
					( objectStatus "U5D1.L74" )
				)
				( pin "ddr0_dq(31)"
					( attribute "PN" "R74"
						( Origin gPackager )
					)
					( objectStatus "U5D1.R74" )
				)
				( pin "ddr0_dq(32)"
					( attribute "PN" "C42"
						( Origin gPackager )
					)
					( objectStatus "U5D1.C42" )
				)
				( pin "ddr0_dq(33)"
					( attribute "PN" "B41"
						( Origin gPackager )
					)
					( objectStatus "U5D1.B41" )
				)
				( pin "ddr0_dq(34)"
					( attribute "PN" "C38"
						( Origin gPackager )
					)
					( objectStatus "U5D1.C38" )
				)
				( pin "ddr0_dq(35)"
					( attribute "PN" "E38"
						( Origin gPackager )
					)
					( objectStatus "U5D1.E38" )
				)
				( pin "ddr0_dq(36)"
					( attribute "PN" "E42"
						( Origin gPackager )
					)
					( objectStatus "U5D1.E42" )
				)
				( pin "ddr0_dq(37)"
					( attribute "PN" "F41"
						( Origin gPackager )
					)
					( objectStatus "U5D1.F41" )
				)
				( pin "ddr0_dq(38)"
					( attribute "PN" "B39"
						( Origin gPackager )
					)
					( objectStatus "U5D1.B39" )
				)
				( pin "ddr0_dq(39)"
					( attribute "PN" "F39"
						( Origin gPackager )
					)
					( objectStatus "U5D1.F39" )
				)
				( pin "ddr0_dq(40)"
					( attribute "PN" "K37"
						( Origin gPackager )
					)
					( objectStatus "U5D1.K37" )
				)
				( pin "ddr0_dq(41)"
					( attribute "PN" "P37"
						( Origin gPackager )
					)
					( objectStatus "U5D1.P37" )
				)
				( pin "ddr0_dq(42)"
					( attribute "PN" "L34"
						( Origin gPackager )
					)
					( objectStatus "U5D1.L34" )
				)
				( pin "ddr0_dq(43)"
					( attribute "PN" "N34"
						( Origin gPackager )
					)
					( objectStatus "U5D1.N34" )
				)
				( pin "ddr0_dq(44)"
					( attribute "PN" "L38"
						( Origin gPackager )
					)
					( objectStatus "U5D1.L38" )
				)
				( pin "ddr0_dq(45)"
					( attribute "PN" "N38"
						( Origin gPackager )
					)
					( objectStatus "U5D1.N38" )
				)
				( pin "ddr0_dq(46)"
					( attribute "PN" "K35"
						( Origin gPackager )
					)
					( objectStatus "U5D1.K35" )
				)
				( pin "ddr0_dq(47)"
					( attribute "PN" "P35"
						( Origin gPackager )
					)
					( objectStatus "U5D1.P35" )
				)
				( pin "ddr0_dq(48)"
					( attribute "PN" "K31"
						( Origin gPackager )
					)
					( objectStatus "U5D1.K31" )
				)
				( pin "ddr0_dq(49)"
					( attribute "PN" "P31"
						( Origin gPackager )
					)
					( objectStatus "U5D1.P31" )
				)
				( pin "ddr0_dq(50)"
					( attribute "PN" "L28"
						( Origin gPackager )
					)
					( objectStatus "U5D1.L28" )
				)
				( pin "ddr0_dq(51)"
					( attribute "PN" "N28"
						( Origin gPackager )
					)
					( objectStatus "U5D1.N28" )
				)
				( pin "ddr0_dq(52)"
					( attribute "PN" "L32"
						( Origin gPackager )
					)
					( objectStatus "U5D1.L32" )
				)
				( pin "ddr0_dq(53)"
					( attribute "PN" "N32"
						( Origin gPackager )
					)
					( objectStatus "U5D1.N32" )
				)
				( pin "ddr0_dq(54)"
					( attribute "PN" "K29"
						( Origin gPackager )
					)
					( objectStatus "U5D1.K29" )
				)
				( pin "ddr0_dq(55)"
					( attribute "PN" "P29"
						( Origin gPackager )
					)
					( objectStatus "U5D1.P29" )
				)
				( pin "ddr0_dq(56)"
					( attribute "PN" "K25"
						( Origin gPackager )
					)
					( objectStatus "U5D1.K25" )
				)
				( pin "ddr0_dq(57)"
					( attribute "PN" "P25"
						( Origin gPackager )
					)
					( objectStatus "U5D1.P25" )
				)
				( pin "ddr0_dq(58)"
					( attribute "PN" "P23"
						( Origin gPackager )
					)
					( objectStatus "U5D1.P23" )
				)
				( pin "ddr0_dq(59)"
					( attribute "PN" "T23"
						( Origin gPackager )
					)
					( objectStatus "U5D1.T23" )
				)
				( pin "ddr0_dq(60)"
					( attribute "PN" "L26"
						( Origin gPackager )
					)
					( objectStatus "U5D1.L26" )
				)
				( pin "ddr0_dq(61)"
					( attribute "PN" "N26"
						( Origin gPackager )
					)
					( objectStatus "U5D1.N26" )
				)
				( pin "ddr0_dq(62)"
					( attribute "PN" "H23"
						( Origin gPackager )
					)
					( objectStatus "U5D1.H23" )
				)
				( pin "ddr0_dq(63)"
					( attribute "PN" "K23"
						( Origin gPackager )
					)
					( objectStatus "U5D1.K23" )
				)
				( pin "ddr0_dqs_dn(0)"
					( attribute "PN" "AJ84"
						( Origin gPackager )
					)
					( objectStatus "U5D1.AJ84" )
				)
				( pin "ddr0_dqs_dn(1)"
					( attribute "PN" "R84"
						( Origin gPackager )
					)
					( objectStatus "U5D1.R84" )
				)
				( pin "ddr0_dqs_dn(2)"
					( attribute "PN" "P79"
						( Origin gPackager )
					)
					( objectStatus "U5D1.P79" )
				)
				( pin "ddr0_dqs_dn(3)"
					( attribute "PN" "T75"
						( Origin gPackager )
					)
					( objectStatus "U5D1.T75" )
				)
				( pin "ddr0_dqs_dn(4)"
					( attribute "PN" "G40"
						( Origin gPackager )
					)
					( objectStatus "U5D1.G40" )
				)
				( pin "ddr0_dqs_dn(5)"
					( attribute "PN" "R36"
						( Origin gPackager )
					)
					( objectStatus "U5D1.R36" )
				)
				( pin "ddr0_dqs_dn(6)"
					( attribute "PN" "R30"
						( Origin gPackager )
					)
					( objectStatus "U5D1.R30" )
				)
				( pin "ddr0_dqs_dn(7)"
					( attribute "PN" "N24"
						( Origin gPackager )
					)
					( objectStatus "U5D1.N24" )
				)
				( pin "ddr0_dqs_dn(8)"
					( attribute "PN" "AH67"
						( Origin gPackager )
					)
					( objectStatus "U5D1.AH67" )
				)
				( pin "ddr0_dqs_dn(9)"
					( attribute "PN" "AL84"
						( Origin gPackager )
					)
					( objectStatus "U5D1.AL84" )
				)
				( pin "ddr0_dqs_dn(10)"
					( attribute "PN" "U84"
						( Origin gPackager )
					)
					( objectStatus "U5D1.U84" )
				)
				( pin "ddr0_dqs_dn(11)"
					( attribute "PN" "U82"
						( Origin gPackager )
					)
					( objectStatus "U5D1.U82" )
				)
				( pin "ddr0_dqs_dn(12)"
					( attribute "PN" "K75"
						( Origin gPackager )
					)
					( objectStatus "U5D1.K75" )
				)
				( pin "ddr0_dqs_dn(13)"
					( attribute "PN" "A40"
						( Origin gPackager )
					)
					( objectStatus "U5D1.A40" )
				)
				( pin "ddr0_dqs_dn(14)"
					( attribute "PN" "J36"
						( Origin gPackager )
					)
					( objectStatus "U5D1.J36" )
				)
				( pin "ddr0_dqs_dn(15)"
					( attribute "PN" "J30"
						( Origin gPackager )
					)
					( objectStatus "U5D1.J30" )
				)
				( pin "ddr0_dqs_dn(16)"
					( attribute "PN" "J24"
						( Origin gPackager )
					)
					( objectStatus "U5D1.J24" )
				)
				( pin "ddr0_dqs_dn(17)"
					( attribute "PN" "AB67"
						( Origin gPackager )
					)
					( objectStatus "U5D1.AB67" )
				)
				( pin "ddr0_dqs_dp(0)"
					( attribute "PN" "AH85"
						( Origin gPackager )
					)
					( objectStatus "U5D1.AH85" )
				)
				( pin "ddr0_dqs_dp(1)"
					( attribute "PN" "P85"
						( Origin gPackager )
					)
					( objectStatus "U5D1.P85" )
				)
				( pin "ddr0_dqs_dp(2)"
					( attribute "PN" "R80"
						( Origin gPackager )
					)
					( objectStatus "U5D1.R80" )
				)
				( pin "ddr0_dqs_dp(3)"
					( attribute "PN" "P75"
						( Origin gPackager )
					)
					( objectStatus "U5D1.P75" )
				)
				( pin "ddr0_dqs_dp(4)"
					( attribute "PN" "E40"
						( Origin gPackager )
					)
					( objectStatus "U5D1.E40" )
				)
				( pin "ddr0_dqs_dp(5)"
					( attribute "PN" "N36"
						( Origin gPackager )
					)
					( objectStatus "U5D1.N36" )
				)
				( pin "ddr0_dqs_dp(6)"
					( attribute "PN" "N30"
						( Origin gPackager )
					)
					( objectStatus "U5D1.N30" )
				)
				( pin "ddr0_dqs_dp(7)"
					( attribute "PN" "R24"
						( Origin gPackager )
					)
					( objectStatus "U5D1.R24" )
				)
				( pin "ddr0_dqs_dp(8)"
					( attribute "PN" "AF67"
						( Origin gPackager )
					)
					( objectStatus "U5D1.AF67" )
				)
				( pin "ddr0_dqs_dp(9)"
					( attribute "PN" "AM85"
						( Origin gPackager )
					)
					( objectStatus "U5D1.AM85" )
				)
				( pin "ddr0_dqs_dp(10)"
					( attribute "PN" "V85"
						( Origin gPackager )
					)
					( objectStatus "U5D1.V85" )
				)
				( pin "ddr0_dqs_dp(11)"
					( attribute "PN" "T81"
						( Origin gPackager )
					)
					( objectStatus "U5D1.T81" )
				)
				( pin "ddr0_dqs_dp(12)"
					( attribute "PN" "M75"
						( Origin gPackager )
					)
					( objectStatus "U5D1.M75" )
				)
				( pin "ddr0_dqs_dp(13)"
					( attribute "PN" "C40"
						( Origin gPackager )
					)
					( objectStatus "U5D1.C40" )
				)
				( pin "ddr0_dqs_dp(14)"
					( attribute "PN" "L36"
						( Origin gPackager )
					)
					( objectStatus "U5D1.L36" )
				)
				( pin "ddr0_dqs_dp(15)"
					( attribute "PN" "L30"
						( Origin gPackager )
					)
					( objectStatus "U5D1.L30" )
				)
				( pin "ddr0_dqs_dp(16)"
					( attribute "PN" "L24"
						( Origin gPackager )
					)
					( objectStatus "U5D1.L24" )
				)
				( pin "ddr0_dqs_dp(17)"
					( attribute "PN" "AD67"
						( Origin gPackager )
					)
					( objectStatus "U5D1.AD67" )
				)
				( pin "ddr0_ecc(0)"
					( attribute "PN" "AC68"
						( Origin gPackager )
					)
					( objectStatus "U5D1.AC68" )
				)
				( pin "ddr0_ecc(1)"
					( attribute "PN" "AG68"
						( Origin gPackager )
					)
					( objectStatus "U5D1.AG68" )
				)
				( pin "ddr0_ecc(2)"
					( attribute "PN" "AD65"
						( Origin gPackager )
					)
					( objectStatus "U5D1.AD65" )
				)
				( pin "ddr0_ecc(3)"
					( attribute "PN" "AF65"
						( Origin gPackager )
					)
					( objectStatus "U5D1.AF65" )
				)
				( pin "ddr0_ecc(4)"
					( attribute "PN" "AD69"
						( Origin gPackager )
					)
					( objectStatus "U5D1.AD69" )
				)
				( pin "ddr0_ecc(5)"
					( attribute "PN" "AF69"
						( Origin gPackager )
					)
					( objectStatus "U5D1.AF69" )
				)
				( pin "ddr0_ecc(6)"
					( attribute "PN" "AC66"
						( Origin gPackager )
					)
					( objectStatus "U5D1.AC66" )
				)
				( pin "ddr0_ecc(7)"
					( attribute "PN" "AG66"
						( Origin gPackager )
					)
					( objectStatus "U5D1.AG66" )
				)
				( pin "ddr0_ma(0)"
					( attribute "PN" "F53"
						( Origin gPackager )
					)
					( objectStatus "U5D1.F53" )
				)
				( pin "ddr0_ma(1)"
					( attribute "PN" "F57"
						( Origin gPackager )
					)
					( objectStatus "U5D1.F57" )
				)
				( pin "ddr0_ma(2)"
					( attribute "PN" "D57"
						( Origin gPackager )
					)
					( objectStatus "U5D1.D57" )
				)
				( pin "ddr0_ma(3)"
					( attribute "PN" "C58"
						( Origin gPackager )
					)
					( objectStatus "U5D1.C58" )
				)
				( pin "ddr0_ma(4)"
					( attribute "PN" "G58"
						( Origin gPackager )
					)
					( objectStatus "U5D1.G58" )
				)
				( pin "ddr0_ma(5)"
					( attribute "PN" "F59"
						( Origin gPackager )
					)
					( objectStatus "U5D1.F59" )
				)
				( pin "ddr0_ma(6)"
					( attribute "PN" "D59"
						( Origin gPackager )
					)
					( objectStatus "U5D1.D59" )
				)
				( pin "ddr0_ma(7)"
					( attribute "PN" "G60"
						( Origin gPackager )
					)
					( objectStatus "U5D1.G60" )
				)
				( pin "ddr0_ma(8)"
					( attribute "PN" "C60"
						( Origin gPackager )
					)
					( objectStatus "U5D1.C60" )
				)
				( pin "ddr0_ma(9)"
					( attribute "PN" "F61"
						( Origin gPackager )
					)
					( objectStatus "U5D1.F61" )
				)
				( pin "ddr0_ma(10)"
					( attribute "PN" "J54"
						( Origin gPackager )
					)
					( objectStatus "U5D1.J54" )
				)
				( pin "ddr0_ma(11)"
					( attribute "PN" "G62"
						( Origin gPackager )
					)
					( objectStatus "U5D1.G62" )
				)
				( pin "ddr0_ma(12)"
					( attribute "PN" "J64"
						( Origin gPackager )
					)
					( objectStatus "U5D1.J64" )
				)
				( pin "ddr0_ma(13)"
					( attribute "PN" "J48"
						( Origin gPackager )
					)
					( objectStatus "U5D1.J48" )
				)
				( pin "ddr0_ma(14)"
					( attribute "PN" "F51"
						( Origin gPackager )
					)
					( objectStatus "U5D1.F51" )
				)
				( pin "ddr0_ma(15)"
					( attribute "PN" "K49"
						( Origin gPackager )
					)
					( objectStatus "U5D1.K49" )
				)
				( pin "ddr0_ma(16)"
					( attribute "PN" "D51"
						( Origin gPackager )
					)
					( objectStatus "U5D1.D51" )
				)
				( pin "ddr0_ma(17)"
					( attribute "PN" "K47"
						( Origin gPackager )
					)
					( objectStatus "U5D1.K47" )
				)
				( pin "ddr0_odt(0)"
					( attribute "PN" "C50"
						( Origin gPackager )
					)
					( objectStatus "U5D1.C50" )
				)
				( pin "ddr0_odt(1)"
					( attribute "PN" "C48"
						( Origin gPackager )
					)
					( objectStatus "U5D1.C48" )
				)
				( pin "ddr0_odt(2)"
					( attribute "PN" "G50"
						( Origin gPackager )
					)
					( objectStatus "U5D1.G50" )
				)
				( pin "ddr0_odt(3)"
					( attribute "PN" "G48"
						( Origin gPackager )
					)
					( objectStatus "U5D1.G48" )
				)
				( pin "ddr0_par"
					( attribute "PN" "D53"
						( Origin gPackager )
					)
					( objectStatus "U5D1.D53" )
				)
			)
			( gate "@baseboard_fab2_lib.baseboard_fab2(sch_1):page24_i172"
				( attribute "CDS_LIB" "chpset_lib"
					( Origin gPackager )
				)
				( attribute "CDS_LOCATION" "U5D1"
					( Origin gPackager )
				)
				( attribute "CDS_SEC" "4"
					( Origin gPackager )
				)
				( attribute "LOCATION" "U5D1"
					( Origin gFrontEnd )
				)
				( attribute "MATERIAL" "IC"
					( Origin gFrontEnd )
				)
				( attribute "PACK_TYPE" "BGA1"
					( Origin gFrontEnd )
				)
				( attribute "PART_NUMBER" "TBD"
					( Origin gFrontEnd )
				)
				( attribute "PHYS_PAGE" "24"
					( Origin gFrontEnd )
				)
				( attribute "ROOM" "CPU0"
					( Origin gFrontEnd )
				)
				( attribute "ROT" "0"
					( Origin gFrontEnd )
				)
				( attribute "SEC" "4"
					( Origin gFrontEnd )
				)
				( attribute "SEC_TYPE" "BGA1"
					( Origin gFrontEnd )
				)
				( attribute "VER" "4"
					( Origin gFrontEnd )
				)
				( attribute "XY" "(-4125,2550)"
					( Origin gFrontEnd )
				)
				( attribute "CHIPS_PART_NAME" "SKX_EXT_B"
					( Origin gPackager )
				)
				( attribute "CDS_PART_NAME" "SKX_EXT_B_BGA1-IC,TBD"
					( Origin gPackager )
				)
				( objectStatus "U5D1" )
				( pin "ddr1_act_n"
					( attribute "PN" "T63"
						( Origin gPackager )
					)
					( objectStatus "U5D1.T63" )
				)
				( pin "ddr1_alert_n"
					( attribute "PN" "W62"
						( Origin gPackager )
					)
					( objectStatus "U5D1.W62" )
				)
				( pin "ddr1_ba(0)"
					( attribute "PN" "T53"
						( Origin gPackager )
					)
					( objectStatus "U5D1.T53" )
				)
				( pin "ddr1_ba(1)"
					( attribute "PN" "K55"
						( Origin gPackager )
					)
					( objectStatus "U5D1.K55" )
				)
				( pin "ddr1_bg(0)"
					( attribute "PN" "M61"
						( Origin gPackager )
					)
					( objectStatus "U5D1.M61" )
				)
				( pin "ddr1_bg(1)"
					( attribute "PN" "N60"
						( Origin gPackager )
					)
					( objectStatus "U5D1.N60" )
				)
				( pin "ddr1_cid(2)"
					( attribute "PN" "M47"
						( Origin gPackager )
					)
					( objectStatus "U5D1.M47" )
				)
				( pin "ddr1_cke(0)"
					( attribute "PN" "N62"
						( Origin gPackager )
					)
					( objectStatus "U5D1.N62" )
				)
				( pin "ddr1_cke(1)"
					( attribute "PN" "R64"
						( Origin gPackager )
					)
					( objectStatus "U5D1.R64" )
				)
				( pin "ddr1_cke(2)"
					( attribute "PN" "K63"
						( Origin gPackager )
					)
					( objectStatus "U5D1.K63" )
				)
				( pin "ddr1_cke(3)"
					( attribute "PN" "L64"
						( Origin gPackager )
					)
					( objectStatus "U5D1.L64" )
				)
				( pin "ddr1_clk_dn(0)"
					( attribute "PN" "M53"
						( Origin gPackager )
					)
					( objectStatus "U5D1.M53" )
				)
				( pin "ddr1_clk_dn(1)"
					( attribute "PN" "R54"
						( Origin gPackager )
					)
					( objectStatus "U5D1.R54" )
				)
				( pin "ddr1_clk_dn(2)"
					( attribute "PN" "N56"
						( Origin gPackager )
					)
					( objectStatus "U5D1.N56" )
				)
				( pin "ddr1_clk_dn(3)"
					( attribute "PN" "R56"
						( Origin gPackager )
					)
					( objectStatus "U5D1.R56" )
				)
				( pin "ddr1_clk_dp(0)"
					( attribute "PN" "N54"
						( Origin gPackager )
					)
					( objectStatus "U5D1.N54" )
				)
				( pin "ddr1_clk_dp(1)"
					( attribute "PN" "T55"
						( Origin gPackager )
					)
					( objectStatus "U5D1.T55" )
				)
				( pin "ddr1_clk_dp(2)"
					( attribute "PN" "M57"
						( Origin gPackager )
					)
					( objectStatus "U5D1.M57" )
				)
				( pin "ddr1_clk_dp(3)"
					( attribute "PN" "T57"
						( Origin gPackager )
					)
					( objectStatus "U5D1.T57" )
				)
				( pin "ddr1_cs_n(0)"
					( attribute "PN" "K51"
						( Origin gPackager )
					)
					( objectStatus "U5D1.K51" )
				)
				( pin "ddr1_cs_n(1)"
					( attribute "PN" "R50"
						( Origin gPackager )
					)
					( objectStatus "U5D1.R50" )
				)
				( pin "ddr1_cs_n(2)"
					( attribute "PN" "N46"
						( Origin gPackager )
					)
					( objectStatus "U5D1.N46" )
				)
				( pin "ddr1_cs_n(3)"
					( attribute "PN" "V47"
						( Origin gPackager )
					)
					( objectStatus "U5D1.V47" )
				)
				( pin "ddr1_cs_n(4)"
					( attribute "PN" "J50"
						( Origin gPackager )
					)
					( objectStatus "U5D1.J50" )
				)
				( pin "ddr1_cs_n(5)"
					( attribute "PN" "T49"
						( Origin gPackager )
					)
					( objectStatus "U5D1.T49" )
				)
				( pin "ddr1_cs_n(6)"
					( attribute "PN" "M45"
						( Origin gPackager )
					)
					( objectStatus "U5D1.M45" )
				)
				( pin "ddr1_cs_n(7)"
					( attribute "PN" "R46"
						( Origin gPackager )
					)
					( objectStatus "U5D1.R46" )
				)
				( pin "ddr1_dq(0)"
					( attribute "PN" "AV81"
						( Origin gPackager )
					)
					( objectStatus "U5D1.AV81" )
				)
				( pin "ddr1_dq(1)"
					( attribute "PN" "AT79"
						( Origin gPackager )
					)
					( objectStatus "U5D1.AT79" )
				)
				( pin "ddr1_dq(2)"
					( attribute "PN" "AN82"
						( Origin gPackager )
					)
					( objectStatus "U5D1.AN82" )
				)
				( pin "ddr1_dq(3)"
					( attribute "PN" "AM81"
						( Origin gPackager )
					)
					( objectStatus "U5D1.AM81" )
				)
				( pin "ddr1_dq(4)"
					( attribute "PN" "AW80"
						( Origin gPackager )
					)
					( objectStatus "U5D1.AW80" )
				)
				( pin "ddr1_dq(5)"
					( attribute "PN" "AV79"
						( Origin gPackager )
					)
					( objectStatus "U5D1.AV79" )
				)
				( pin "ddr1_dq(6)"
					( attribute "PN" "AR82"
						( Origin gPackager )
					)
					( objectStatus "U5D1.AR82" )
				)
				( pin "ddr1_dq(7)"
					( attribute "PN" "AN80"
						( Origin gPackager )
					)
					( objectStatus "U5D1.AN80" )
				)
				( pin "ddr1_dq(8)"
					( attribute "PN" "AH81"
						( Origin gPackager )
					)
					( objectStatus "U5D1.AH81" )
				)
				( pin "ddr1_dq(9)"
					( attribute "PN" "AF79"
						( Origin gPackager )
					)
					( objectStatus "U5D1.AF79" )
				)
				( pin "ddr1_dq(10)"
					( attribute "PN" "AC82"
						( Origin gPackager )
					)
					( objectStatus "U5D1.AC82" )
				)
				( pin "ddr1_dq(11)"
					( attribute "PN" "AB81"
						( Origin gPackager )
					)
					( objectStatus "U5D1.AB81" )
				)
				( pin "ddr1_dq(12)"
					( attribute "PN" "AJ80"
						( Origin gPackager )
					)
					( objectStatus "U5D1.AJ80" )
				)
				( pin "ddr1_dq(13)"
					( attribute "PN" "AH79"
						( Origin gPackager )
					)
					( objectStatus "U5D1.AH79" )
				)
				( pin "ddr1_dq(14)"
					( attribute "PN" "AE82"
						( Origin gPackager )
					)
					( objectStatus "U5D1.AE82" )
				)
				( pin "ddr1_dq(15)"
					( attribute "PN" "AC80"
						( Origin gPackager )
					)
					( objectStatus "U5D1.AC80" )
				)
				( pin "ddr1_dq(16)"
					( attribute "PN" "E80"
						( Origin gPackager )
					)
					( objectStatus "U5D1.E80" )
				)
				( pin "ddr1_dq(17)"
					( attribute "PN" "J80"
						( Origin gPackager )
					)
					( objectStatus "U5D1.J80" )
				)
				( pin "ddr1_dq(18)"
					( attribute "PN" "F77"
						( Origin gPackager )
					)
					( objectStatus "U5D1.F77" )
				)
				( pin "ddr1_dq(19)"
					( attribute "PN" "H77"
						( Origin gPackager )
					)
					( objectStatus "U5D1.H77" )
				)
				( pin "ddr1_dq(20)"
					( attribute "PN" "F81"
						( Origin gPackager )
					)
					( objectStatus "U5D1.F81" )
				)
				( pin "ddr1_dq(21)"
					( attribute "PN" "H81"
						( Origin gPackager )
					)
					( objectStatus "U5D1.H81" )
				)
				( pin "ddr1_dq(22)"
					( attribute "PN" "E78"
						( Origin gPackager )
					)
					( objectStatus "U5D1.E78" )
				)
				( pin "ddr1_dq(23)"
					( attribute "PN" "J78"
						( Origin gPackager )
					)
					( objectStatus "U5D1.J78" )
				)
				( pin "ddr1_dq(24)"
					( attribute "PN" "D75"
						( Origin gPackager )
					)
					( objectStatus "U5D1.D75" )
				)
				( pin "ddr1_dq(25)"
					( attribute "PN" "C74"
						( Origin gPackager )
					)
					( objectStatus "U5D1.C74" )
				)
				( pin "ddr1_dq(26)"
					( attribute "PN" "D71"
						( Origin gPackager )
					)
					( objectStatus "U5D1.D71" )
				)
				( pin "ddr1_dq(27)"
					( attribute "PN" "F71"
						( Origin gPackager )
					)
					( objectStatus "U5D1.F71" )
				)
				( pin "ddr1_dq(28)"
					( attribute "PN" "F75"
						( Origin gPackager )
					)
					( objectStatus "U5D1.F75" )
				)
				( pin "ddr1_dq(29)"
					( attribute "PN" "G74"
						( Origin gPackager )
					)
					( objectStatus "U5D1.G74" )
				)
				( pin "ddr1_dq(30)"
					( attribute "PN" "C72"
						( Origin gPackager )
					)
					( objectStatus "U5D1.C72" )
				)
				( pin "ddr1_dq(31)"
					( attribute "PN" "G72"
						( Origin gPackager )
					)
					( objectStatus "U5D1.G72" )
				)
				( pin "ddr1_dq(32)"
					( attribute "PN" "K43"
						( Origin gPackager )
					)
					( objectStatus "U5D1.K43" )
				)
				( pin "ddr1_dq(33)"
					( attribute "PN" "H43"
						( Origin gPackager )
					)
					( objectStatus "U5D1.H43" )
				)
				( pin "ddr1_dq(34)"
					( attribute "PN" "L40"
						( Origin gPackager )
					)
					( objectStatus "U5D1.L40" )
				)
				( pin "ddr1_dq(35)"
					( attribute "PN" "N40"
						( Origin gPackager )
					)
					( objectStatus "U5D1.N40" )
				)
				( pin "ddr1_dq(36)"
					( attribute "PN" "P43"
						( Origin gPackager )
					)
					( objectStatus "U5D1.P43" )
				)
				( pin "ddr1_dq(37)"
					( attribute "PN" "T43"
						( Origin gPackager )
					)
					( objectStatus "U5D1.T43" )
				)
				( pin "ddr1_dq(38)"
					( attribute "PN" "K41"
						( Origin gPackager )
					)
					( objectStatus "U5D1.K41" )
				)
				( pin "ddr1_dq(39)"
					( attribute "PN" "P41"
						( Origin gPackager )
					)
					( objectStatus "U5D1.P41" )
				)
				( pin "ddr1_dq(40)"
					( attribute "PN" "C36"
						( Origin gPackager )
					)
					( objectStatus "U5D1.C36" )
				)
				( pin "ddr1_dq(41)"
					( attribute "PN" "B35"
						( Origin gPackager )
					)
					( objectStatus "U5D1.B35" )
				)
				( pin "ddr1_dq(42)"
					( attribute "PN" "C32"
						( Origin gPackager )
					)
					( objectStatus "U5D1.C32" )
				)
				( pin "ddr1_dq(43)"
					( attribute "PN" "E32"
						( Origin gPackager )
					)
					( objectStatus "U5D1.E32" )
				)
				( pin "ddr1_dq(44)"
					( attribute "PN" "E36"
						( Origin gPackager )
					)
					( objectStatus "U5D1.E36" )
				)
				( pin "ddr1_dq(45)"
					( attribute "PN" "F35"
						( Origin gPackager )
					)
					( objectStatus "U5D1.F35" )
				)
				( pin "ddr1_dq(46)"
					( attribute "PN" "B33"
						( Origin gPackager )
					)
					( objectStatus "U5D1.B33" )
				)
				( pin "ddr1_dq(47)"
					( attribute "PN" "F33"
						( Origin gPackager )
					)
					( objectStatus "U5D1.F33" )
				)
				( pin "ddr1_dq(48)"
					( attribute "PN" "C30"
						( Origin gPackager )
					)
					( objectStatus "U5D1.C30" )
				)
				( pin "ddr1_dq(49)"
					( attribute "PN" "B29"
						( Origin gPackager )
					)
					( objectStatus "U5D1.B29" )
				)
				( pin "ddr1_dq(50)"
					( attribute "PN" "C26"
						( Origin gPackager )
					)
					( objectStatus "U5D1.C26" )
				)
				( pin "ddr1_dq(51)"
					( attribute "PN" "E26"
						( Origin gPackager )
					)
					( objectStatus "U5D1.E26" )
				)
				( pin "ddr1_dq(52)"
					( attribute "PN" "E30"
						( Origin gPackager )
					)
					( objectStatus "U5D1.E30" )
				)
				( pin "ddr1_dq(53)"
					( attribute "PN" "F29"
						( Origin gPackager )
					)
					( objectStatus "U5D1.F29" )
				)
				( pin "ddr1_dq(54)"
					( attribute "PN" "B27"
						( Origin gPackager )
					)
					( objectStatus "U5D1.B27" )
				)
				( pin "ddr1_dq(55)"
					( attribute "PN" "F27"
						( Origin gPackager )
					)
					( objectStatus "U5D1.F27" )
				)
				( pin "ddr1_dq(56)"
					( attribute "PN" "U28"
						( Origin gPackager )
					)
					( objectStatus "U5D1.U28" )
				)
				( pin "ddr1_dq(57)"
					( attribute "PN" "AA28"
						( Origin gPackager )
					)
					( objectStatus "U5D1.AA28" )
				)
				( pin "ddr1_dq(58)"
					( attribute "PN" "V25"
						( Origin gPackager )
					)
					( objectStatus "U5D1.V25" )
				)
				( pin "ddr1_dq(59)"
					( attribute "PN" "Y25"
						( Origin gPackager )
					)
					( objectStatus "U5D1.Y25" )
				)
				( pin "ddr1_dq(60)"
					( attribute "PN" "V29"
						( Origin gPackager )
					)
					( objectStatus "U5D1.V29" )
				)
				( pin "ddr1_dq(61)"
					( attribute "PN" "Y29"
						( Origin gPackager )
					)
					( objectStatus "U5D1.Y29" )
				)
				( pin "ddr1_dq(62)"
					( attribute "PN" "U26"
						( Origin gPackager )
					)
					( objectStatus "U5D1.U26" )
				)
				( pin "ddr1_dq(63)"
					( attribute "PN" "AA26"
						( Origin gPackager )
					)
					( objectStatus "U5D1.AA26" )
				)
				( pin "ddr1_dqs_dn(0)"
					( attribute "PN" "AP79"
						( Origin gPackager )
					)
					( objectStatus "U5D1.AP79" )
				)
				( pin "ddr1_dqs_dn(1)"
					( attribute "PN" "AD79"
						( Origin gPackager )
					)
					( objectStatus "U5D1.AD79" )
				)
				( pin "ddr1_dqs_dn(2)"
					( attribute "PN" "K79"
						( Origin gPackager )
					)
					( objectStatus "U5D1.K79" )
				)
				( pin "ddr1_dqs_dn(3)"
					( attribute "PN" "H73"
						( Origin gPackager )
					)
					( objectStatus "U5D1.H73" )
				)
				( pin "ddr1_dqs_dn(4)"
					( attribute "PN" "N42"
						( Origin gPackager )
					)
					( objectStatus "U5D1.N42" )
				)
				( pin "ddr1_dqs_dn(5)"
					( attribute "PN" "G34"
						( Origin gPackager )
					)
					( objectStatus "U5D1.G34" )
				)
				( pin "ddr1_dqs_dn(6)"
					( attribute "PN" "G28"
						( Origin gPackager )
					)
					( objectStatus "U5D1.G28" )
				)
				( pin "ddr1_dqs_dn(7)"
					( attribute "PN" "AB27"
						( Origin gPackager )
					)
					( objectStatus "U5D1.AB27" )
				)
				( pin "ddr1_dqs_dn(8)"
					( attribute "PN" "N68"
						( Origin gPackager )
					)
					( objectStatus "U5D1.N68" )
				)
				( pin "ddr1_dqs_dn(9)"
					( attribute "PN" "AU82"
						( Origin gPackager )
					)
					( objectStatus "U5D1.AU82" )
				)
				( pin "ddr1_dqs_dn(10)"
					( attribute "PN" "AG82"
						( Origin gPackager )
					)
					( objectStatus "U5D1.AG82" )
				)
				( pin "ddr1_dqs_dn(11)"
					( attribute "PN" "D79"
						( Origin gPackager )
					)
					( objectStatus "U5D1.D79" )
				)
				( pin "ddr1_dqs_dn(12)"
					( attribute "PN" "B73"
						( Origin gPackager )
					)
					( objectStatus "U5D1.B73" )
				)
				( pin "ddr1_dqs_dn(13)"
					( attribute "PN" "J42"
						( Origin gPackager )
					)
					( objectStatus "U5D1.J42" )
				)
				( pin "ddr1_dqs_dn(14)"
					( attribute "PN" "A34"
						( Origin gPackager )
					)
					( objectStatus "U5D1.A34" )
				)
				( pin "ddr1_dqs_dn(15)"
					( attribute "PN" "A28"
						( Origin gPackager )
					)
					( objectStatus "U5D1.A28" )
				)
				( pin "ddr1_dqs_dn(16)"
					( attribute "PN" "T27"
						( Origin gPackager )
					)
					( objectStatus "U5D1.T27" )
				)
				( pin "ddr1_dqs_dn(17)"
					( attribute "PN" "G68"
						( Origin gPackager )
					)
					( objectStatus "U5D1.G68" )
				)
				( pin "ddr1_dqs_dp(0)"
					( attribute "PN" "AR80"
						( Origin gPackager )
					)
					( objectStatus "U5D1.AR80" )
				)
				( pin "ddr1_dqs_dp(1)"
					( attribute "PN" "AE80"
						( Origin gPackager )
					)
					( objectStatus "U5D1.AE80" )
				)
				( pin "ddr1_dqs_dp(2)"
					( attribute "PN" "H79"
						( Origin gPackager )
					)
					( objectStatus "U5D1.H79" )
				)
				( pin "ddr1_dqs_dp(3)"
					( attribute "PN" "F73"
						( Origin gPackager )
					)
					( objectStatus "U5D1.F73" )
				)
				( pin "ddr1_dqs_dp(4)"
					( attribute "PN" "R42"
						( Origin gPackager )
					)
					( objectStatus "U5D1.R42" )
				)
				( pin "ddr1_dqs_dp(5)"
					( attribute "PN" "E34"
						( Origin gPackager )
					)
					( objectStatus "U5D1.E34" )
				)
				( pin "ddr1_dqs_dp(6)"
					( attribute "PN" "E28"
						( Origin gPackager )
					)
					( objectStatus "U5D1.E28" )
				)
				( pin "ddr1_dqs_dp(7)"
					( attribute "PN" "Y27"
						( Origin gPackager )
					)
					( objectStatus "U5D1.Y27" )
				)
				( pin "ddr1_dqs_dp(8)"
					( attribute "PN" "L68"
						( Origin gPackager )
					)
					( objectStatus "U5D1.L68" )
				)
				( pin "ddr1_dqs_dp(9)"
					( attribute "PN" "AT81"
						( Origin gPackager )
					)
					( objectStatus "U5D1.AT81" )
				)
				( pin "ddr1_dqs_dp(10)"
					( attribute "PN" "AF81"
						( Origin gPackager )
					)
					( objectStatus "U5D1.AF81" )
				)
				( pin "ddr1_dqs_dp(11)"
					( attribute "PN" "F79"
						( Origin gPackager )
					)
					( objectStatus "U5D1.F79" )
				)
				( pin "ddr1_dqs_dp(12)"
					( attribute "PN" "D73"
						( Origin gPackager )
					)
					( objectStatus "U5D1.D73" )
				)
				( pin "ddr1_dqs_dp(13)"
					( attribute "PN" "L42"
						( Origin gPackager )
					)
					( objectStatus "U5D1.L42" )
				)
				( pin "ddr1_dqs_dp(14)"
					( attribute "PN" "C34"
						( Origin gPackager )
					)
					( objectStatus "U5D1.C34" )
				)
				( pin "ddr1_dqs_dp(15)"
					( attribute "PN" "C28"
						( Origin gPackager )
					)
					( objectStatus "U5D1.C28" )
				)
				( pin "ddr1_dqs_dp(16)"
					( attribute "PN" "V27"
						( Origin gPackager )
					)
					( objectStatus "U5D1.V27" )
				)
				( pin "ddr1_dqs_dp(17)"
					( attribute "PN" "J68"
						( Origin gPackager )
					)
					( objectStatus "U5D1.J68" )
				)
				( pin "ddr1_ecc(0)"
					( attribute "PN" "J70"
						( Origin gPackager )
					)
					( objectStatus "U5D1.J70" )
				)
				( pin "ddr1_ecc(1)"
					( attribute "PN" "H69"
						( Origin gPackager )
					)
					( objectStatus "U5D1.H69" )
				)
				( pin "ddr1_ecc(2)"
					( attribute "PN" "J66"
						( Origin gPackager )
					)
					( objectStatus "U5D1.J66" )
				)
				( pin "ddr1_ecc(3)"
					( attribute "PN" "L66"
						( Origin gPackager )
					)
					( objectStatus "U5D1.L66" )
				)
				( pin "ddr1_ecc(4)"
					( attribute "PN" "L70"
						( Origin gPackager )
					)
					( objectStatus "U5D1.L70" )
				)
				( pin "ddr1_ecc(5)"
					( attribute "PN" "M69"
						( Origin gPackager )
					)
					( objectStatus "U5D1.M69" )
				)
				( pin "ddr1_ecc(6)"
					( attribute "PN" "H67"
						( Origin gPackager )
					)
					( objectStatus "U5D1.H67" )
				)
				( pin "ddr1_ecc(7)"
					( attribute "PN" "M67"
						( Origin gPackager )
					)
					( objectStatus "U5D1.M67" )
				)
				( pin "ddr1_ma(0)"
					( attribute "PN" "J52"
						( Origin gPackager )
					)
					( objectStatus "U5D1.J52" )
				)
				( pin "ddr1_ma(1)"
					( attribute "PN" "J58"
						( Origin gPackager )
					)
					( objectStatus "U5D1.J58" )
				)
				( pin "ddr1_ma(2)"
					( attribute "PN" "K57"
						( Origin gPackager )
					)
					( objectStatus "U5D1.K57" )
				)
				( pin "ddr1_ma(3)"
					( attribute "PN" "N58"
						( Origin gPackager )
					)
					( objectStatus "U5D1.N58" )
				)
				( pin "ddr1_ma(4)"
					( attribute "PN" "M59"
						( Origin gPackager )
					)
					( objectStatus "U5D1.M59" )
				)
				( pin "ddr1_ma(5)"
					( attribute "PN" "R58"
						( Origin gPackager )
					)
					( objectStatus "U5D1.R58" )
				)
				( pin "ddr1_ma(6)"
					( attribute "PN" "T59"
						( Origin gPackager )
					)
					( objectStatus "U5D1.T59" )
				)
				( pin "ddr1_ma(7)"
					( attribute "PN" "V61"
						( Origin gPackager )
					)
					( objectStatus "U5D1.V61" )
				)
				( pin "ddr1_ma(8)"
					( attribute "PN" "W60"
						( Origin gPackager )
					)
					( objectStatus "U5D1.W60" )
				)
				( pin "ddr1_ma(9)"
					( attribute "PN" "K59"
						( Origin gPackager )
					)
					( objectStatus "U5D1.K59" )
				)
				( pin "ddr1_ma(10)"
					( attribute "PN" "M55"
						( Origin gPackager )
					)
					( objectStatus "U5D1.M55" )
				)
				( pin "ddr1_ma(11)"
					( attribute "PN" "R60"
						( Origin gPackager )
					)
					( objectStatus "U5D1.R60" )
				)
				( pin "ddr1_ma(12)"
					( attribute "PN" "T61"
						( Origin gPackager )
					)
					( objectStatus "U5D1.T61" )
				)
				( pin "ddr1_ma(13)"
					( attribute "PN" "M51"
						( Origin gPackager )
					)
					( objectStatus "U5D1.M51" )
				)
				( pin "ddr1_ma(14)"
					( attribute "PN" "T51"
						( Origin gPackager )
					)
					( objectStatus "U5D1.T51" )
				)
				( pin "ddr1_ma(15)"
					( attribute "PN" "N52"
						( Origin gPackager )
					)
					( objectStatus "U5D1.N52" )
				)
				( pin "ddr1_ma(16)"
					( attribute "PN" "R52"
						( Origin gPackager )
					)
					( objectStatus "U5D1.R52" )
				)
				( pin "ddr1_ma(17)"
					( attribute "PN" "N48"
						( Origin gPackager )
					)
					( objectStatus "U5D1.N48" )
				)
				( pin "ddr1_odt(0)"
					( attribute "PN" "N50"
						( Origin gPackager )
					)
					( objectStatus "U5D1.N50" )
				)
				( pin "ddr1_odt(1)"
					( attribute "PN" "R48"
						( Origin gPackager )
					)
					( objectStatus "U5D1.R48" )
				)
				( pin "ddr1_odt(2)"
					( attribute "PN" "M49"
						( Origin gPackager )
					)
					( objectStatus "U5D1.M49" )
				)
				( pin "ddr1_odt(3)"
					( attribute "PN" "T47"
						( Origin gPackager )
					)
					( objectStatus "U5D1.T47" )
				)
				( pin "ddr1_par"
					( attribute "PN" "K53"
						( Origin gPackager )
					)
					( objectStatus "U5D1.K53" )
				)
			)
			( gate "@baseboard_fab2_lib.baseboard_fab2(sch_1):page25_i172"
				( attribute "CDS_LIB" "chpset_lib"
					( Origin gPackager )
				)
				( attribute "CDS_LOCATION" "U5D1"
					( Origin gPackager )
				)
				( attribute "CDS_SEC" "5"
					( Origin gPackager )
				)
				( attribute "LOCATION" "U5D1"
					( Origin gFrontEnd )
				)
				( attribute "MATERIAL" "IC"
					( Origin gFrontEnd )
				)
				( attribute "PACK_TYPE" "BGA1"
					( Origin gFrontEnd )
				)
				( attribute "PART_NUMBER" "TBD"
					( Origin gFrontEnd )
				)
				( attribute "PHYS_PAGE" "25"
					( Origin gFrontEnd )
				)
				( attribute "ROOM" "CPU0"
					( Origin gFrontEnd )
				)
				( attribute "ROT" "0"
					( Origin gFrontEnd )
				)
				( attribute "SEC" "5"
					( Origin gFrontEnd )
				)
				( attribute "SEC_TYPE" "BGA1"
					( Origin gFrontEnd )
				)
				( attribute "VER" "5"
					( Origin gFrontEnd )
				)
				( attribute "XY" "(-4175,2600)"
					( Origin gFrontEnd )
				)
				( attribute "CHIPS_PART_NAME" "SKX_EXT_B"
					( Origin gPackager )
				)
				( attribute "CDS_PART_NAME" "SKX_EXT_B_BGA1-IC,TBD"
					( Origin gPackager )
				)
				( objectStatus "U5D1" )
				( pin "ddr2_act_n"
					( attribute "PN" "AB61"
						( Origin gPackager )
					)
					( objectStatus "U5D1.AB61" )
				)
				( pin "ddr2_alert_n"
					( attribute "PN" "AD61"
						( Origin gPackager )
					)
					( objectStatus "U5D1.AD61" )
				)
				( pin "ddr2_ba(0)"
					( attribute "PN" "W52"
						( Origin gPackager )
					)
					( objectStatus "U5D1.W52" )
				)
				( pin "ddr2_ba(1)"
					( attribute "PN" "AE56"
						( Origin gPackager )
					)
					( objectStatus "U5D1.AE56" )
				)
				( pin "ddr2_bg(0)"
					( attribute "PN" "AA60"
						( Origin gPackager )
					)
					( objectStatus "U5D1.AA60" )
				)
				( pin "ddr2_bg(1)"
					( attribute "PN" "AE62"
						( Origin gPackager )
					)
					( objectStatus "U5D1.AE62" )
				)
				( pin "ddr2_cid(2)"
					( attribute "PN" "AB45"
						( Origin gPackager )
					)
					( objectStatus "U5D1.AB45" )
				)
				( pin "ddr2_cke(0)"
					( attribute "PN" "AA62"
						( Origin gPackager )
					)
					( objectStatus "U5D1.AA62" )
				)
				( pin "ddr2_cke(1)"
					( attribute "PN" "AD63"
						( Origin gPackager )
					)
					( objectStatus "U5D1.AD63" )
				)
				( pin "ddr2_cke(2)"
					( attribute "PN" "V63"
						( Origin gPackager )
					)
					( objectStatus "U5D1.V63" )
				)
				( pin "ddr2_cke(3)"
					( attribute "PN" "AB63"
						( Origin gPackager )
					)
					( objectStatus "U5D1.AB63" )
				)
				( pin "ddr2_clk_dn(0)"
					( attribute "PN" "AA54"
						( Origin gPackager )
					)
					( objectStatus "U5D1.AA54" )
				)
				( pin "ddr2_clk_dn(1)"
					( attribute "PN" "W54"
						( Origin gPackager )
					)
					( objectStatus "U5D1.W54" )
				)
				( pin "ddr2_clk_dn(2)"
					( attribute "PN" "AA56"
						( Origin gPackager )
					)
					( objectStatus "U5D1.AA56" )
				)
				( pin "ddr2_clk_dn(3)"
					( attribute "PN" "W56"
						( Origin gPackager )
					)
					( objectStatus "U5D1.W56" )
				)
				( pin "ddr2_clk_dp(0)"
					( attribute "PN" "AB55"
						( Origin gPackager )
					)
					( objectStatus "U5D1.AB55" )
				)
				( pin "ddr2_clk_dp(1)"
					( attribute "PN" "V55"
						( Origin gPackager )
					)
					( objectStatus "U5D1.V55" )
				)
				( pin "ddr2_clk_dp(2)"
					( attribute "PN" "AB57"
						( Origin gPackager )
					)
					( objectStatus "U5D1.AB57" )
				)
				( pin "ddr2_clk_dp(3)"
					( attribute "PN" "V57"
						( Origin gPackager )
					)
					( objectStatus "U5D1.V57" )
				)
				( pin "ddr2_cs_n(0)"
					( attribute "PN" "V51"
						( Origin gPackager )
					)
					( objectStatus "U5D1.V51" )
				)
				( pin "ddr2_cs_n(1)"
					( attribute "PN" "AB49"
						( Origin gPackager )
					)
					( objectStatus "U5D1.AB49" )
				)
				( pin "ddr2_cs_n(2)"
					( attribute "PN" "W46"
						( Origin gPackager )
					)
					( objectStatus "U5D1.W46" )
				)
				( pin "ddr2_cs_n(3)"
					( attribute "PN" "AA46"
						( Origin gPackager )
					)
					( objectStatus "U5D1.AA46" )
				)
				( pin "ddr2_cs_n(4)"
					( attribute "PN" "AB51"
						( Origin gPackager )
					)
					( objectStatus "U5D1.AB51" )
				)
				( pin "ddr2_cs_n(5)"
					( attribute "PN" "W48"
						( Origin gPackager )
					)
					( objectStatus "U5D1.W48" )
				)
				( pin "ddr2_cs_n(6)"
					( attribute "PN" "T45"
						( Origin gPackager )
					)
					( objectStatus "U5D1.T45" )
				)
				( pin "ddr2_cs_n(7)"
					( attribute "PN" "V45"
						( Origin gPackager )
					)
					( objectStatus "U5D1.V45" )
				)
				( pin "ddr2_dq(0)"
					( attribute "PN" "AR76"
						( Origin gPackager )
					)
					( objectStatus "U5D1.AR76" )
				)
				( pin "ddr2_dq(1)"
					( attribute "PN" "AN74"
						( Origin gPackager )
					)
					( objectStatus "U5D1.AN74" )
				)
				( pin "ddr2_dq(2)"
					( attribute "PN" "AK77"
						( Origin gPackager )
					)
					( objectStatus "U5D1.AK77" )
				)
				( pin "ddr2_dq(3)"
					( attribute "PN" "AJ76"
						( Origin gPackager )
					)
					( objectStatus "U5D1.AJ76" )
				)
				( pin "ddr2_dq(4)"
					( attribute "PN" "AT75"
						( Origin gPackager )
					)
					( objectStatus "U5D1.AT75" )
				)
				( pin "ddr2_dq(5)"
					( attribute "PN" "AR74"
						( Origin gPackager )
					)
					( objectStatus "U5D1.AR74" )
				)
				( pin "ddr2_dq(6)"
					( attribute "PN" "AM77"
						( Origin gPackager )
					)
					( objectStatus "U5D1.AM77" )
				)
				( pin "ddr2_dq(7)"
					( attribute "PN" "AK75"
						( Origin gPackager )
					)
					( objectStatus "U5D1.AK75" )
				)
				( pin "ddr2_dq(8)"
					( attribute "PN" "AE76"
						( Origin gPackager )
					)
					( objectStatus "U5D1.AE76" )
				)
				( pin "ddr2_dq(9)"
					( attribute "PN" "AC74"
						( Origin gPackager )
					)
					( objectStatus "U5D1.AC74" )
				)
				( pin "ddr2_dq(10)"
					( attribute "PN" "Y77"
						( Origin gPackager )
					)
					( objectStatus "U5D1.Y77" )
				)
				( pin "ddr2_dq(11)"
					( attribute "PN" "W76"
						( Origin gPackager )
					)
					( objectStatus "U5D1.W76" )
				)
				( pin "ddr2_dq(12)"
					( attribute "PN" "AF75"
						( Origin gPackager )
					)
					( objectStatus "U5D1.AF75" )
				)
				( pin "ddr2_dq(13)"
					( attribute "PN" "AE74"
						( Origin gPackager )
					)
					( objectStatus "U5D1.AE74" )
				)
				( pin "ddr2_dq(14)"
					( attribute "PN" "AB77"
						( Origin gPackager )
					)
					( objectStatus "U5D1.AB77" )
				)
				( pin "ddr2_dq(15)"
					( attribute "PN" "Y75"
						( Origin gPackager )
					)
					( objectStatus "U5D1.Y75" )
				)
				( pin "ddr2_dq(16)"
					( attribute "PN" "W72"
						( Origin gPackager )
					)
					( objectStatus "U5D1.W72" )
				)
				( pin "ddr2_dq(17)"
					( attribute "PN" "AA70"
						( Origin gPackager )
					)
					( objectStatus "U5D1.AA70" )
				)
				( pin "ddr2_dq(18)"
					( attribute "PN" "R70"
						( Origin gPackager )
					)
					( objectStatus "U5D1.R70" )
				)
				( pin "ddr2_dq(19)"
					( attribute "PN" "T69"
						( Origin gPackager )
					)
					( objectStatus "U5D1.T69" )
				)
				( pin "ddr2_dq(20)"
					( attribute "PN" "AA72"
						( Origin gPackager )
					)
					( objectStatus "U5D1.AA72" )
				)
				( pin "ddr2_dq(21)"
					( attribute "PN" "AB71"
						( Origin gPackager )
					)
					( objectStatus "U5D1.AB71" )
				)
				( pin "ddr2_dq(22)"
					( attribute "PN" "T71"
						( Origin gPackager )
					)
					( objectStatus "U5D1.T71" )
				)
				( pin "ddr2_dq(23)"
					( attribute "PN" "V69"
						( Origin gPackager )
					)
					( objectStatus "U5D1.V69" )
				)
				( pin "ddr2_dq(24)"
					( attribute "PN" "AM67"
						( Origin gPackager )
					)
					( objectStatus "U5D1.AM67" )
				)
				( pin "ddr2_dq(25)"
					( attribute "PN" "AT67"
						( Origin gPackager )
					)
					( objectStatus "U5D1.AT67" )
				)
				( pin "ddr2_dq(26)"
					( attribute "PN" "AN64"
						( Origin gPackager )
					)
					( objectStatus "U5D1.AN64" )
				)
				( pin "ddr2_dq(27)"
					( attribute "PN" "AR64"
						( Origin gPackager )
					)
					( objectStatus "U5D1.AR64" )
				)
				( pin "ddr2_dq(28)"
					( attribute "PN" "AN68"
						( Origin gPackager )
					)
					( objectStatus "U5D1.AN68" )
				)
				( pin "ddr2_dq(29)"
					( attribute "PN" "AR68"
						( Origin gPackager )
					)
					( objectStatus "U5D1.AR68" )
				)
				( pin "ddr2_dq(30)"
					( attribute "PN" "AM65"
						( Origin gPackager )
					)
					( objectStatus "U5D1.AM65" )
				)
				( pin "ddr2_dq(31)"
					( attribute "PN" "AT65"
						( Origin gPackager )
					)
					( objectStatus "U5D1.AT65" )
				)
				( pin "ddr2_dq(32)"
					( attribute "PN" "U40"
						( Origin gPackager )
					)
					( objectStatus "U5D1.U40" )
				)
				( pin "ddr2_dq(33)"
					( attribute "PN" "AA40"
						( Origin gPackager )
					)
					( objectStatus "U5D1.AA40" )
				)
				( pin "ddr2_dq(34)"
					( attribute "PN" "V37"
						( Origin gPackager )
					)
					( objectStatus "U5D1.V37" )
				)
				( pin "ddr2_dq(35)"
					( attribute "PN" "Y37"
						( Origin gPackager )
					)
					( objectStatus "U5D1.Y37" )
				)
				( pin "ddr2_dq(36)"
					( attribute "PN" "V41"
						( Origin gPackager )
					)
					( objectStatus "U5D1.V41" )
				)
				( pin "ddr2_dq(37)"
					( attribute "PN" "Y41"
						( Origin gPackager )
					)
					( objectStatus "U5D1.Y41" )
				)
				( pin "ddr2_dq(38)"
					( attribute "PN" "U38"
						( Origin gPackager )
					)
					( objectStatus "U5D1.U38" )
				)
				( pin "ddr2_dq(39)"
					( attribute "PN" "AA38"
						( Origin gPackager )
					)
					( objectStatus "U5D1.AA38" )
				)
				( pin "ddr2_dq(40)"
					( attribute "PN" "U34"
						( Origin gPackager )
					)
					( objectStatus "U5D1.U34" )
				)
				( pin "ddr2_dq(41)"
					( attribute "PN" "AA34"
						( Origin gPackager )
					)
					( objectStatus "U5D1.AA34" )
				)
				( pin "ddr2_dq(42)"
					( attribute "PN" "V31"
						( Origin gPackager )
					)
					( objectStatus "U5D1.V31" )
				)
				( pin "ddr2_dq(43)"
					( attribute "PN" "Y31"
						( Origin gPackager )
					)
					( objectStatus "U5D1.Y31" )
				)
				( pin "ddr2_dq(44)"
					( attribute "PN" "V35"
						( Origin gPackager )
					)
					( objectStatus "U5D1.V35" )
				)
				( pin "ddr2_dq(45)"
					( attribute "PN" "Y35"
						( Origin gPackager )
					)
					( objectStatus "U5D1.Y35" )
				)
				( pin "ddr2_dq(46)"
					( attribute "PN" "U32"
						( Origin gPackager )
					)
					( objectStatus "U5D1.U32" )
				)
				( pin "ddr2_dq(47)"
					( attribute "PN" "AA32"
						( Origin gPackager )
					)
					( objectStatus "U5D1.AA32" )
				)
				( pin "ddr2_dq(48)"
					( attribute "PN" "AD31"
						( Origin gPackager )
					)
					( objectStatus "U5D1.AD31" )
				)
				( pin "ddr2_dq(49)"
					( attribute "PN" "AH31"
						( Origin gPackager )
					)
					( objectStatus "U5D1.AH31" )
				)
				( pin "ddr2_dq(50)"
					( attribute "PN" "AE28"
						( Origin gPackager )
					)
					( objectStatus "U5D1.AE28" )
				)
				( pin "ddr2_dq(51)"
					( attribute "PN" "AG28"
						( Origin gPackager )
					)
					( objectStatus "U5D1.AG28" )
				)
				( pin "ddr2_dq(52)"
					( attribute "PN" "AE32"
						( Origin gPackager )
					)
					( objectStatus "U5D1.AE32" )
				)
				( pin "ddr2_dq(53)"
					( attribute "PN" "AG32"
						( Origin gPackager )
					)
					( objectStatus "U5D1.AG32" )
				)
				( pin "ddr2_dq(54)"
					( attribute "PN" "AD29"
						( Origin gPackager )
					)
					( objectStatus "U5D1.AD29" )
				)
				( pin "ddr2_dq(55)"
					( attribute "PN" "AH29"
						( Origin gPackager )
					)
					( objectStatus "U5D1.AH29" )
				)
				( pin "ddr2_dq(56)"
					( attribute "PN" "AD25"
						( Origin gPackager )
					)
					( objectStatus "U5D1.AD25" )
				)
				( pin "ddr2_dq(57)"
					( attribute "PN" "AH25"
						( Origin gPackager )
					)
					( objectStatus "U5D1.AH25" )
				)
				( pin "ddr2_dq(58)"
					( attribute "PN" "AE22"
						( Origin gPackager )
					)
					( objectStatus "U5D1.AE22" )
				)
				( pin "ddr2_dq(59)"
					( attribute "PN" "AG22"
						( Origin gPackager )
					)
					( objectStatus "U5D1.AG22" )
				)
				( pin "ddr2_dq(60)"
					( attribute "PN" "AE26"
						( Origin gPackager )
					)
					( objectStatus "U5D1.AE26" )
				)
				( pin "ddr2_dq(61)"
					( attribute "PN" "AG26"
						( Origin gPackager )
					)
					( objectStatus "U5D1.AG26" )
				)
				( pin "ddr2_dq(62)"
					( attribute "PN" "AD23"
						( Origin gPackager )
					)
					( objectStatus "U5D1.AD23" )
				)
				( pin "ddr2_dq(63)"
					( attribute "PN" "AH23"
						( Origin gPackager )
					)
					( objectStatus "U5D1.AH23" )
				)
				( pin "ddr2_dqs_dn(0)"
					( attribute "PN" "AL74"
						( Origin gPackager )
					)
					( objectStatus "U5D1.AL74" )
				)
				( pin "ddr2_dqs_dn(1)"
					( attribute "PN" "AA74"
						( Origin gPackager )
					)
					( objectStatus "U5D1.AA74" )
				)
				( pin "ddr2_dqs_dn(2)"
					( attribute "PN" "Y69"
						( Origin gPackager )
					)
					( objectStatus "U5D1.Y69" )
				)
				( pin "ddr2_dqs_dn(3)"
					( attribute "PN" "AU66"
						( Origin gPackager )
					)
					( objectStatus "U5D1.AU66" )
				)
				( pin "ddr2_dqs_dn(4)"
					( attribute "PN" "AB39"
						( Origin gPackager )
					)
					( objectStatus "U5D1.AB39" )
				)
				( pin "ddr2_dqs_dn(5)"
					( attribute "PN" "AB33"
						( Origin gPackager )
					)
					( objectStatus "U5D1.AB33" )
				)
				( pin "ddr2_dqs_dn(6)"
					( attribute "PN" "AJ30"
						( Origin gPackager )
					)
					( objectStatus "U5D1.AJ30" )
				)
				( pin "ddr2_dqs_dn(7)"
					( attribute "PN" "AJ24"
						( Origin gPackager )
					)
					( objectStatus "U5D1.AJ24" )
				)
				( pin "ddr2_dqs_dn(8)"
					( attribute "PN" "BB71"
						( Origin gPackager )
					)
					( objectStatus "U5D1.BB71" )
				)
				( pin "ddr2_dqs_dn(9)"
					( attribute "PN" "AP77"
						( Origin gPackager )
					)
					( objectStatus "U5D1.AP77" )
				)
				( pin "ddr2_dqs_dn(10)"
					( attribute "PN" "AD77"
						( Origin gPackager )
					)
					( objectStatus "U5D1.AD77" )
				)
				( pin "ddr2_dqs_dn(11)"
					( attribute "PN" "U72"
						( Origin gPackager )
					)
					( objectStatus "U5D1.U72" )
				)
				( pin "ddr2_dqs_dn(12)"
					( attribute "PN" "AL66"
						( Origin gPackager )
					)
					( objectStatus "U5D1.AL66" )
				)
				( pin "ddr2_dqs_dn(13)"
					( attribute "PN" "T39"
						( Origin gPackager )
					)
					( objectStatus "U5D1.T39" )
				)
				( pin "ddr2_dqs_dn(14)"
					( attribute "PN" "T33"
						( Origin gPackager )
					)
					( objectStatus "U5D1.T33" )
				)
				( pin "ddr2_dqs_dn(15)"
					( attribute "PN" "AC30"
						( Origin gPackager )
					)
					( objectStatus "U5D1.AC30" )
				)
				( pin "ddr2_dqs_dn(16)"
					( attribute "PN" "AC24"
						( Origin gPackager )
					)
					( objectStatus "U5D1.AC24" )
				)
				( pin "ddr2_dqs_dn(17)"
					( attribute "PN" "AT71"
						( Origin gPackager )
					)
					( objectStatus "U5D1.AT71" )
				)
				( pin "ddr2_dqs_dp(0)"
					( attribute "PN" "AM75"
						( Origin gPackager )
					)
					( objectStatus "U5D1.AM75" )
				)
				( pin "ddr2_dqs_dp(1)"
					( attribute "PN" "AB75"
						( Origin gPackager )
					)
					( objectStatus "U5D1.AB75" )
				)
				( pin "ddr2_dqs_dp(2)"
					( attribute "PN" "W70"
						( Origin gPackager )
					)
					( objectStatus "U5D1.W70" )
				)
				( pin "ddr2_dqs_dp(3)"
					( attribute "PN" "AR66"
						( Origin gPackager )
					)
					( objectStatus "U5D1.AR66" )
				)
				( pin "ddr2_dqs_dp(4)"
					( attribute "PN" "Y39"
						( Origin gPackager )
					)
					( objectStatus "U5D1.Y39" )
				)
				( pin "ddr2_dqs_dp(5)"
					( attribute "PN" "Y33"
						( Origin gPackager )
					)
					( objectStatus "U5D1.Y33" )
				)
				( pin "ddr2_dqs_dp(6)"
					( attribute "PN" "AG30"
						( Origin gPackager )
					)
					( objectStatus "U5D1.AG30" )
				)
				( pin "ddr2_dqs_dp(7)"
					( attribute "PN" "AG24"
						( Origin gPackager )
					)
					( objectStatus "U5D1.AG24" )
				)
				( pin "ddr2_dqs_dp(8)"
					( attribute "PN" "AY71"
						( Origin gPackager )
					)
					( objectStatus "U5D1.AY71" )
				)
				( pin "ddr2_dqs_dp(9)"
					( attribute "PN" "AN76"
						( Origin gPackager )
					)
					( objectStatus "U5D1.AN76" )
				)
				( pin "ddr2_dqs_dp(10)"
					( attribute "PN" "AC76"
						( Origin gPackager )
					)
					( objectStatus "U5D1.AC76" )
				)
				( pin "ddr2_dqs_dp(11)"
					( attribute "PN" "V71"
						( Origin gPackager )
					)
					( objectStatus "U5D1.V71" )
				)
				( pin "ddr2_dqs_dp(12)"
					( attribute "PN" "AN66"
						( Origin gPackager )
					)
					( objectStatus "U5D1.AN66" )
				)
				( pin "ddr2_dqs_dp(13)"
					( attribute "PN" "V39"
						( Origin gPackager )
					)
					( objectStatus "U5D1.V39" )
				)
				( pin "ddr2_dqs_dp(14)"
					( attribute "PN" "V33"
						( Origin gPackager )
					)
					( objectStatus "U5D1.V33" )
				)
				( pin "ddr2_dqs_dp(15)"
					( attribute "PN" "AE30"
						( Origin gPackager )
					)
					( objectStatus "U5D1.AE30" )
				)
				( pin "ddr2_dqs_dp(16)"
					( attribute "PN" "AE24"
						( Origin gPackager )
					)
					( objectStatus "U5D1.AE24" )
				)
				( pin "ddr2_dqs_dp(17)"
					( attribute "PN" "AV71"
						( Origin gPackager )
					)
					( objectStatus "U5D1.AV71" )
				)
				( pin "ddr2_ecc(0)"
					( attribute "PN" "AU72"
						( Origin gPackager )
					)
					( objectStatus "U5D1.AU72" )
				)
				( pin "ddr2_ecc(1)"
					( attribute "PN" "BA72"
						( Origin gPackager )
					)
					( objectStatus "U5D1.BA72" )
				)
				( pin "ddr2_ecc(2)"
					( attribute "PN" "AV69"
						( Origin gPackager )
					)
					( objectStatus "U5D1.AV69" )
				)
				( pin "ddr2_ecc(3)"
					( attribute "PN" "AY69"
						( Origin gPackager )
					)
					( objectStatus "U5D1.AY69" )
				)
				( pin "ddr2_ecc(4)"
					( attribute "PN" "AV73"
						( Origin gPackager )
					)
					( objectStatus "U5D1.AV73" )
				)
				( pin "ddr2_ecc(5)"
					( attribute "PN" "AY73"
						( Origin gPackager )
					)
					( objectStatus "U5D1.AY73" )
				)
				( pin "ddr2_ecc(6)"
					( attribute "PN" "AU70"
						( Origin gPackager )
					)
					( objectStatus "U5D1.AU70" )
				)
				( pin "ddr2_ecc(7)"
					( attribute "PN" "BA70"
						( Origin gPackager )
					)
					( objectStatus "U5D1.BA70" )
				)
				( pin "ddr2_ma(0)"
					( attribute "PN" "AB53"
						( Origin gPackager )
					)
					( objectStatus "U5D1.AB53" )
				)
				( pin "ddr2_ma(1)"
					( attribute "PN" "AE58"
						( Origin gPackager )
					)
					( objectStatus "U5D1.AE58" )
				)
				( pin "ddr2_ma(2)"
					( attribute "PN" "AD57"
						( Origin gPackager )
					)
					( objectStatus "U5D1.AD57" )
				)
				( pin "ddr2_ma(3)"
					( attribute "PN" "W58"
						( Origin gPackager )
					)
					( objectStatus "U5D1.W58" )
				)
				( pin "ddr2_ma(4)"
					( attribute "PN" "AA58"
						( Origin gPackager )
					)
					( objectStatus "U5D1.AA58" )
				)
				( pin "ddr2_ma(5)"
					( attribute "PN" "V59"
						( Origin gPackager )
					)
					( objectStatus "U5D1.V59" )
				)
				( pin "ddr2_ma(6)"
					( attribute "PN" "AB59"
						( Origin gPackager )
					)
					( objectStatus "U5D1.AB59" )
				)
				( pin "ddr2_ma(7)"
					( attribute "PN" "AE60"
						( Origin gPackager )
					)
					( objectStatus "U5D1.AE60" )
				)
				( pin "ddr2_ma(8)"
					( attribute "PN" "AD59"
						( Origin gPackager )
					)
					( objectStatus "U5D1.AD59" )
				)
				( pin "ddr2_ma(9)"
					( attribute "PN" "AG58"
						( Origin gPackager )
					)
					( objectStatus "U5D1.AG58" )
				)
				( pin "ddr2_ma(10)"
					( attribute "PN" "AD55"
						( Origin gPackager )
					)
					( objectStatus "U5D1.AD55" )
				)
				( pin "ddr2_ma(11)"
					( attribute "PN" "AG60"
						( Origin gPackager )
					)
					( objectStatus "U5D1.AG60" )
				)
				( pin "ddr2_ma(12)"
					( attribute "PN" "AG62"
						( Origin gPackager )
					)
					( objectStatus "U5D1.AG62" )
				)
				( pin "ddr2_ma(13)"
					( attribute "PN" "AD53"
						( Origin gPackager )
					)
					( objectStatus "U5D1.AD53" )
				)
				( pin "ddr2_ma(14)"
					( attribute "PN" "W50"
						( Origin gPackager )
					)
					( objectStatus "U5D1.W50" )
				)
				( pin "ddr2_ma(15)"
					( attribute "PN" "AE54"
						( Origin gPackager )
					)
					( objectStatus "U5D1.AE54" )
				)
				( pin "ddr2_ma(16)"
					( attribute "PN" "AA52"
						( Origin gPackager )
					)
					( objectStatus "U5D1.AA52" )
				)
				( pin "ddr2_ma(17)"
					( attribute "PN" "AC46"
						( Origin gPackager )
					)
					( objectStatus "U5D1.AC46" )
				)
				( pin "ddr2_odt(0)"
					( attribute "PN" "AA50"
						( Origin gPackager )
					)
					( objectStatus "U5D1.AA50" )
				)
				( pin "ddr2_odt(1)"
					( attribute "PN" "AA48"
						( Origin gPackager )
					)
					( objectStatus "U5D1.AA48" )
				)
				( pin "ddr2_odt(2)"
					( attribute "PN" "V49"
						( Origin gPackager )
					)
					( objectStatus "U5D1.V49" )
				)
				( pin "ddr2_odt(3)"
					( attribute "PN" "AB47"
						( Origin gPackager )
					)
					( objectStatus "U5D1.AB47" )
				)
				( pin "ddr2_par"
					( attribute "PN" "V53"
						( Origin gPackager )
					)
					( objectStatus "U5D1.V53" )
				)
			)
			( gate "@baseboard_fab2_lib.baseboard_fab2(sch_1):page26_i172"
				( attribute "CDS_LIB" "chpset_lib"
					( Origin gPackager )
				)
				( attribute "CDS_LOCATION" "U5D1"
					( Origin gPackager )
				)
				( attribute "CDS_SEC" "6"
					( Origin gPackager )
				)
				( attribute "LOCATION" "U5D1"
					( Origin gFrontEnd )
				)
				( attribute "MATERIAL" "IC"
					( Origin gFrontEnd )
				)
				( attribute "PACK_TYPE" "BGA1"
					( Origin gFrontEnd )
				)
				( attribute "PART_NUMBER" "TBD"
					( Origin gFrontEnd )
				)
				( attribute "PHYS_PAGE" "26"
					( Origin gFrontEnd )
				)
				( attribute "ROOM" "CPU0"
					( Origin gFrontEnd )
				)
				( attribute "ROT" "0"
					( Origin gFrontEnd )
				)
				( attribute "SEC" "6"
					( Origin gFrontEnd )
				)
				( attribute "SEC_TYPE" "BGA1"
					( Origin gFrontEnd )
				)
				( attribute "VER" "6"
					( Origin gFrontEnd )
				)
				( attribute "XY" "(-4100,2575)"
					( Origin gFrontEnd )
				)
				( attribute "CHIPS_PART_NAME" "SKX_EXT_B"
					( Origin gPackager )
				)
				( attribute "CDS_PART_NAME" "SKX_EXT_B_BGA1-IC,TBD"
					( Origin gPackager )
				)
				( objectStatus "U5D1" )
				( pin "ddr3_act_n"
					( attribute "PN" "DW60"
						( Origin gPackager )
					)
					( objectStatus "U5D1.DW60" )
				)
				( pin "ddr3_alert_n"
					( attribute "PN" "ED63"
						( Origin gPackager )
					)
					( objectStatus "U5D1.ED63" )
				)
				( pin "ddr3_ba(0)"
					( attribute "PN" "EE52"
						( Origin gPackager )
					)
					( objectStatus "U5D1.EE52" )
				)
				( pin "ddr3_ba(1)"
					( attribute "PN" "EA54"
						( Origin gPackager )
					)
					( objectStatus "U5D1.EA54" )
				)
				( pin "ddr3_bg(0)"
					( attribute "PN" "ED61"
						( Origin gPackager )
					)
					( objectStatus "U5D1.ED61" )
				)
				( pin "ddr3_bg(1)"
					( attribute "PN" "DW62"
						( Origin gPackager )
					)
					( objectStatus "U5D1.DW62" )
				)
				( pin "ddr3_cid(2)"
					( attribute "PN" "DV47"
						( Origin gPackager )
					)
					( objectStatus "U5D1.DV47" )
				)
				( pin "ddr3_cke(0)"
					( attribute "PN" "EE62"
						( Origin gPackager )
					)
					( objectStatus "U5D1.EE62" )
				)
				( pin "ddr3_cke(1)"
					( attribute "PN" "EF63"
						( Origin gPackager )
					)
					( objectStatus "U5D1.EF63" )
				)
				( pin "ddr3_cke(2)"
					( attribute "PN" "EA62"
						( Origin gPackager )
					)
					( objectStatus "U5D1.EA62" )
				)
				( pin "ddr3_cke(3)"
					( attribute "PN" "EB63"
						( Origin gPackager )
					)
					( objectStatus "U5D1.EB63" )
				)
				( pin "ddr3_clk_dn(0)"
					( attribute "PN" "ED55"
						( Origin gPackager )
					)
					( objectStatus "U5D1.ED55" )
				)
				( pin "ddr3_clk_dn(1)"
					( attribute "PN" "EF55"
						( Origin gPackager )
					)
					( objectStatus "U5D1.EF55" )
				)
				( pin "ddr3_clk_dn(2)"
					( attribute "PN" "DW56"
						( Origin gPackager )
					)
					( objectStatus "U5D1.DW56" )
				)
				( pin "ddr3_clk_dn(3)"
					( attribute "PN" "EF57"
						( Origin gPackager )
					)
					( objectStatus "U5D1.EF57" )
				)
				( pin "ddr3_clk_dp(0)"
					( attribute "PN" "EB55"
						( Origin gPackager )
					)
					( objectStatus "U5D1.EB55" )
				)
				( pin "ddr3_clk_dp(1)"
					( attribute "PN" "EE54"
						( Origin gPackager )
					)
					( objectStatus "U5D1.EE54" )
				)
				( pin "ddr3_clk_dp(2)"
					( attribute "PN" "EA56"
						( Origin gPackager )
					)
					( objectStatus "U5D1.EA56" )
				)
				( pin "ddr3_clk_dp(3)"
					( attribute "PN" "EE56"
						( Origin gPackager )
					)
					( objectStatus "U5D1.EE56" )
				)
				( pin "ddr3_cs_n(0)"
					( attribute "PN" "EF51"
						( Origin gPackager )
					)
					( objectStatus "U5D1.EF51" )
				)
				( pin "ddr3_cs_n(1)"
					( attribute "PN" "ED49"
						( Origin gPackager )
					)
					( objectStatus "U5D1.ED49" )
				)
				( pin "ddr3_cs_n(2)"
					( attribute "PN" "ED47"
						( Origin gPackager )
					)
					( objectStatus "U5D1.ED47" )
				)
				( pin "ddr3_cs_n(3)"
					( attribute "PN" "EB47"
						( Origin gPackager )
					)
					( objectStatus "U5D1.EB47" )
				)
				( pin "ddr3_cs_n(4)"
					( attribute "PN" "EB51"
						( Origin gPackager )
					)
					( objectStatus "U5D1.EB51" )
				)
				( pin "ddr3_cs_n(5)"
					( attribute "PN" "EB49"
						( Origin gPackager )
					)
					( objectStatus "U5D1.EB49" )
				)
				( pin "ddr3_cs_n(6)"
					( attribute "PN" "DV45"
						( Origin gPackager )
					)
					( objectStatus "U5D1.DV45" )
				)
				( pin "ddr3_cs_n(7)"
					( attribute "PN" "EB45"
						( Origin gPackager )
					)
					( objectStatus "U5D1.EB45" )
				)
				( pin "ddr3_dq(0)"
					( attribute "PN" "CN84"
						( Origin gPackager )
					)
					( objectStatus "U5D1.CN84" )
				)
				( pin "ddr3_dq(1)"
					( attribute "PN" "CN86"
						( Origin gPackager )
					)
					( objectStatus "U5D1.CN86" )
				)
				( pin "ddr3_dq(2)"
					( attribute "PN" "DA86"
						( Origin gPackager )
					)
					( objectStatus "U5D1.DA86" )
				)
				( pin "ddr3_dq(3)"
					( attribute "PN" "DA84"
						( Origin gPackager )
					)
					( objectStatus "U5D1.DA84" )
				)
				( pin "ddr3_dq(4)"
					( attribute "PN" "CL84"
						( Origin gPackager )
					)
					( objectStatus "U5D1.CL84" )
				)
				( pin "ddr3_dq(5)"
					( attribute "PN" "CL86"
						( Origin gPackager )
					)
					( objectStatus "U5D1.CL86" )
				)
				( pin "ddr3_dq(6)"
					( attribute "PN" "CW86"
						( Origin gPackager )
					)
					( objectStatus "U5D1.CW86" )
				)
				( pin "ddr3_dq(7)"
					( attribute "PN" "CW84"
						( Origin gPackager )
					)
					( objectStatus "U5D1.CW84" )
				)
				( pin "ddr3_dq(8)"
					( attribute "PN" "DG84"
						( Origin gPackager )
					)
					( objectStatus "U5D1.DG84" )
				)
				( pin "ddr3_dq(9)"
					( attribute "PN" "DH85"
						( Origin gPackager )
					)
					( objectStatus "U5D1.DH85" )
				)
				( pin "ddr3_dq(10)"
					( attribute "PN" "DV83"
						( Origin gPackager )
					)
					( objectStatus "U5D1.DV83" )
				)
				( pin "ddr3_dq(11)"
					( attribute "PN" "DY83"
						( Origin gPackager )
					)
					( objectStatus "U5D1.DY83" )
				)
				( pin "ddr3_dq(12)"
					( attribute "PN" "DD85"
						( Origin gPackager )
					)
					( objectStatus "U5D1.DD85" )
				)
				( pin "ddr3_dq(13)"
					( attribute "PN" "DE84"
						( Origin gPackager )
					)
					( objectStatus "U5D1.DE84" )
				)
				( pin "ddr3_dq(14)"
					( attribute "PN" "DR84"
						( Origin gPackager )
					)
					( objectStatus "U5D1.DR84" )
				)
				( pin "ddr3_dq(15)"
					( attribute "PN" "DV85"
						( Origin gPackager )
					)
					( objectStatus "U5D1.DV85" )
				)
				( pin "ddr3_dq(16)"
					( attribute "PN" "DM79"
						( Origin gPackager )
					)
					( objectStatus "U5D1.DM79" )
				)
				( pin "ddr3_dq(17)"
					( attribute "PN" "DK81"
						( Origin gPackager )
					)
					( objectStatus "U5D1.DK81" )
				)
				( pin "ddr3_dq(18)"
					( attribute "PN" "DT81"
						( Origin gPackager )
					)
					( objectStatus "U5D1.DT81" )
				)
				( pin "ddr3_dq(19)"
					( attribute "PN" "DR82"
						( Origin gPackager )
					)
					( objectStatus "U5D1.DR82" )
				)
				( pin "ddr3_dq(20)"
					( attribute "PN" "DK79"
						( Origin gPackager )
					)
					( objectStatus "U5D1.DK79" )
				)
				( pin "ddr3_dq(21)"
					( attribute "PN" "DJ80"
						( Origin gPackager )
					)
					( objectStatus "U5D1.DJ80" )
				)
				( pin "ddr3_dq(22)"
					( attribute "PN" "DR80"
						( Origin gPackager )
					)
					( objectStatus "U5D1.DR80" )
				)
				( pin "ddr3_dq(23)"
					( attribute "PN" "DN82"
						( Origin gPackager )
					)
					( objectStatus "U5D1.DN82" )
				)
				( pin "ddr3_dq(24)"
					( attribute "PN" "DN76"
						( Origin gPackager )
					)
					( objectStatus "U5D1.DN76" )
				)
				( pin "ddr3_dq(25)"
					( attribute "PN" "DU76"
						( Origin gPackager )
					)
					( objectStatus "U5D1.DU76" )
				)
				( pin "ddr3_dq(26)"
					( attribute "PN" "DP73"
						( Origin gPackager )
					)
					( objectStatus "U5D1.DP73" )
				)
				( pin "ddr3_dq(27)"
					( attribute "PN" "DT73"
						( Origin gPackager )
					)
					( objectStatus "U5D1.DT73" )
				)
				( pin "ddr3_dq(28)"
					( attribute "PN" "DP77"
						( Origin gPackager )
					)
					( objectStatus "U5D1.DP77" )
				)
				( pin "ddr3_dq(29)"
					( attribute "PN" "DT77"
						( Origin gPackager )
					)
					( objectStatus "U5D1.DT77" )
				)
				( pin "ddr3_dq(30)"
					( attribute "PN" "DN74"
						( Origin gPackager )
					)
					( objectStatus "U5D1.DN74" )
				)
				( pin "ddr3_dq(31)"
					( attribute "PN" "DU74"
						( Origin gPackager )
					)
					( objectStatus "U5D1.DU74" )
				)
				( pin "ddr3_dq(32)"
					( attribute "PN" "EC40"
						( Origin gPackager )
					)
					( objectStatus "U5D1.EC40" )
				)
				( pin "ddr3_dq(33)"
					( attribute "PN" "ED39"
						( Origin gPackager )
					)
					( objectStatus "U5D1.ED39" )
				)
				( pin "ddr3_dq(34)"
					( attribute "PN" "EA36"
						( Origin gPackager )
					)
					( objectStatus "U5D1.EA36" )
				)
				( pin "ddr3_dq(35)"
					( attribute "PN" "EC36"
						( Origin gPackager )
					)
					( objectStatus "U5D1.EC36" )
				)
				( pin "ddr3_dq(36)"
					( attribute "PN" "DY39"
						( Origin gPackager )
					)
					( objectStatus "U5D1.DY39" )
				)
				( pin "ddr3_dq(37)"
					( attribute "PN" "EA40"
						( Origin gPackager )
					)
					( objectStatus "U5D1.EA40" )
				)
				( pin "ddr3_dq(38)"
					( attribute "PN" "DY37"
						( Origin gPackager )
					)
					( objectStatus "U5D1.DY37" )
				)
				( pin "ddr3_dq(39)"
					( attribute "PN" "ED37"
						( Origin gPackager )
					)
					( objectStatus "U5D1.ED37" )
				)
				( pin "ddr3_dq(40)"
					( attribute "PN" "DN36"
						( Origin gPackager )
					)
					( objectStatus "U5D1.DN36" )
				)
				( pin "ddr3_dq(41)"
					( attribute "PN" "DU36"
						( Origin gPackager )
					)
					( objectStatus "U5D1.DU36" )
				)
				( pin "ddr3_dq(42)"
					( attribute "PN" "DP33"
						( Origin gPackager )
					)
					( objectStatus "U5D1.DP33" )
				)
				( pin "ddr3_dq(43)"
					( attribute "PN" "DT33"
						( Origin gPackager )
					)
					( objectStatus "U5D1.DT33" )
				)
				( pin "ddr3_dq(44)"
					( attribute "PN" "DP37"
						( Origin gPackager )
					)
					( objectStatus "U5D1.DP37" )
				)
				( pin "ddr3_dq(45)"
					( attribute "PN" "DT37"
						( Origin gPackager )
					)
					( objectStatus "U5D1.DT37" )
				)
				( pin "ddr3_dq(46)"
					( attribute "PN" "DN34"
						( Origin gPackager )
					)
					( objectStatus "U5D1.DN34" )
				)
				( pin "ddr3_dq(47)"
					( attribute "PN" "DU34"
						( Origin gPackager )
					)
					( objectStatus "U5D1.DU34" )
				)
				( pin "ddr3_dq(48)"
					( attribute "PN" "DN30"
						( Origin gPackager )
					)
					( objectStatus "U5D1.DN30" )
				)
				( pin "ddr3_dq(49)"
					( attribute "PN" "DU30"
						( Origin gPackager )
					)
					( objectStatus "U5D1.DU30" )
				)
				( pin "ddr3_dq(50)"
					( attribute "PN" "DP27"
						( Origin gPackager )
					)
					( objectStatus "U5D1.DP27" )
				)
				( pin "ddr3_dq(51)"
					( attribute "PN" "DT27"
						( Origin gPackager )
					)
					( objectStatus "U5D1.DT27" )
				)
				( pin "ddr3_dq(52)"
					( attribute "PN" "DP31"
						( Origin gPackager )
					)
					( objectStatus "U5D1.DP31" )
				)
				( pin "ddr3_dq(53)"
					( attribute "PN" "DT31"
						( Origin gPackager )
					)
					( objectStatus "U5D1.DT31" )
				)
				( pin "ddr3_dq(54)"
					( attribute "PN" "DN28"
						( Origin gPackager )
					)
					( objectStatus "U5D1.DN28" )
				)
				( pin "ddr3_dq(55)"
					( attribute "PN" "DU28"
						( Origin gPackager )
					)
					( objectStatus "U5D1.DU28" )
				)
				( pin "ddr3_dq(56)"
					( attribute "PN" "DN24"
						( Origin gPackager )
					)
					( objectStatus "U5D1.DN24" )
				)
				( pin "ddr3_dq(57)"
					( attribute "PN" "DU24"
						( Origin gPackager )
					)
					( objectStatus "U5D1.DU24" )
				)
				( pin "ddr3_dq(58)"
					( attribute "PN" "DY21"
						( Origin gPackager )
					)
					( objectStatus "U5D1.DY21" )
				)
				( pin "ddr3_dq(59)"
					( attribute "PN" "EB21"
						( Origin gPackager )
					)
					( objectStatus "U5D1.EB21" )
				)
				( pin "ddr3_dq(60)"
					( attribute "PN" "DP25"
						( Origin gPackager )
					)
					( objectStatus "U5D1.DP25" )
				)
				( pin "ddr3_dq(61)"
					( attribute "PN" "DT25"
						( Origin gPackager )
					)
					( objectStatus "U5D1.DT25" )
				)
				( pin "ddr3_dq(62)"
					( attribute "PN" "EC22"
						( Origin gPackager )
					)
					( objectStatus "U5D1.EC22" )
				)
				( pin "ddr3_dq(63)"
					( attribute "PN" "DW22"
						( Origin gPackager )
					)
					( objectStatus "U5D1.DW22" )
				)
				( pin "ddr3_dqs_dn(0)"
					( attribute "PN" "CU84"
						( Origin gPackager )
					)
					( objectStatus "U5D1.CU84" )
				)
				( pin "ddr3_dqs_dn(1)"
					( attribute "PN" "DN84"
						( Origin gPackager )
					)
					( objectStatus "U5D1.DN84" )
				)
				( pin "ddr3_dqs_dn(2)"
					( attribute "PN" "DL82"
						( Origin gPackager )
					)
					( objectStatus "U5D1.DL82" )
				)
				( pin "ddr3_dqs_dn(3)"
					( attribute "PN" "DV75"
						( Origin gPackager )
					)
					( objectStatus "U5D1.DV75" )
				)
				( pin "ddr3_dqs_dn(4)"
					( attribute "PN" "EE38"
						( Origin gPackager )
					)
					( objectStatus "U5D1.EE38" )
				)
				( pin "ddr3_dqs_dn(5)"
					( attribute "PN" "DV35"
						( Origin gPackager )
					)
					( objectStatus "U5D1.DV35" )
				)
				( pin "ddr3_dqs_dn(6)"
					( attribute "PN" "DV29"
						( Origin gPackager )
					)
					( objectStatus "U5D1.DV29" )
				)
				( pin "ddr3_dqs_dn(7)"
					( attribute "PN" "DV23"
						( Origin gPackager )
					)
					( objectStatus "U5D1.DV23" )
				)
				( pin "ddr3_dqs_dn(8)"
					( attribute "PN" "DF67"
						( Origin gPackager )
					)
					( objectStatus "U5D1.DF67" )
				)
				( pin "ddr3_dqs_dn(9)"
					( attribute "PN" "CR84"
						( Origin gPackager )
					)
					( objectStatus "U5D1.CR84" )
				)
				( pin "ddr3_dqs_dn(10)"
					( attribute "PN" "DM85"
						( Origin gPackager )
					)
					( objectStatus "U5D1.DM85" )
				)
				( pin "ddr3_dqs_dn(11)"
					( attribute "PN" "DN80"
						( Origin gPackager )
					)
					( objectStatus "U5D1.DN80" )
				)
				( pin "ddr3_dqs_dn(12)"
					( attribute "PN" "DP75"
						( Origin gPackager )
					)
					( objectStatus "U5D1.DP75" )
				)
				( pin "ddr3_dqs_dn(13)"
					( attribute "PN" "EA38"
						( Origin gPackager )
					)
					( objectStatus "U5D1.EA38" )
				)
				( pin "ddr3_dqs_dn(14)"
					( attribute "PN" "DP35"
						( Origin gPackager )
					)
					( objectStatus "U5D1.DP35" )
				)
				( pin "ddr3_dqs_dn(15)"
					( attribute "PN" "DM29"
						( Origin gPackager )
					)
					( objectStatus "U5D1.DM29" )
				)
				( pin "ddr3_dqs_dn(16)"
					( attribute "PN" "DM23"
						( Origin gPackager )
					)
					( objectStatus "U5D1.DM23" )
				)
				( pin "ddr3_dqs_dn(17)"
					( attribute "PN" "DB67"
						( Origin gPackager )
					)
					( objectStatus "U5D1.DB67" )
				)
				( pin "ddr3_dqs_dp(0)"
					( attribute "PN" "CV85"
						( Origin gPackager )
					)
					( objectStatus "U5D1.CV85" )
				)
				( pin "ddr3_dqs_dp(1)"
					( attribute "PN" "DP85"
						( Origin gPackager )
					)
					( objectStatus "U5D1.DP85" )
				)
				( pin "ddr3_dqs_dp(2)"
					( attribute "PN" "DM81"
						( Origin gPackager )
					)
					( objectStatus "U5D1.DM81" )
				)
				( pin "ddr3_dqs_dp(3)"
					( attribute "PN" "DT75"
						( Origin gPackager )
					)
					( objectStatus "U5D1.DT75" )
				)
				( pin "ddr3_dqs_dp(4)"
					( attribute "PN" "EC38"
						( Origin gPackager )
					)
					( objectStatus "U5D1.EC38" )
				)
				( pin "ddr3_dqs_dp(5)"
					( attribute "PN" "DT35"
						( Origin gPackager )
					)
					( objectStatus "U5D1.DT35" )
				)
				( pin "ddr3_dqs_dp(6)"
					( attribute "PN" "DT29"
						( Origin gPackager )
					)
					( objectStatus "U5D1.DT29" )
				)
				( pin "ddr3_dqs_dp(7)"
					( attribute "PN" "DT23"
						( Origin gPackager )
					)
					( objectStatus "U5D1.DT23" )
				)
				( pin "ddr3_dqs_dp(8)"
					( attribute "PN" "DD67"
						( Origin gPackager )
					)
					( objectStatus "U5D1.DD67" )
				)
				( pin "ddr3_dqs_dp(9)"
					( attribute "PN" "CP85"
						( Origin gPackager )
					)
					( objectStatus "U5D1.CP85" )
				)
				( pin "ddr3_dqs_dp(10)"
					( attribute "PN" "DL84"
						( Origin gPackager )
					)
					( objectStatus "U5D1.DL84" )
				)
				( pin "ddr3_dqs_dp(11)"
					( attribute "PN" "DP79"
						( Origin gPackager )
					)
					( objectStatus "U5D1.DP79" )
				)
				( pin "ddr3_dqs_dp(12)"
					( attribute "PN" "DM75"
						( Origin gPackager )
					)
					( objectStatus "U5D1.DM75" )
				)
				( pin "ddr3_dqs_dp(13)"
					( attribute "PN" "DW38"
						( Origin gPackager )
					)
					( objectStatus "U5D1.DW38" )
				)
				( pin "ddr3_dqs_dp(14)"
					( attribute "PN" "DM35"
						( Origin gPackager )
					)
					( objectStatus "U5D1.DM35" )
				)
				( pin "ddr3_dqs_dp(15)"
					( attribute "PN" "DP29"
						( Origin gPackager )
					)
					( objectStatus "U5D1.DP29" )
				)
				( pin "ddr3_dqs_dp(16)"
					( attribute "PN" "DP23"
						( Origin gPackager )
					)
					( objectStatus "U5D1.DP23" )
				)
				( pin "ddr3_dqs_dp(17)"
					( attribute "PN" "CY67"
						( Origin gPackager )
					)
					( objectStatus "U5D1.CY67" )
				)
				( pin "ddr3_ecc(0)"
					( attribute "PN" "DA68"
						( Origin gPackager )
					)
					( objectStatus "U5D1.DA68" )
				)
				( pin "ddr3_ecc(1)"
					( attribute "PN" "DE68"
						( Origin gPackager )
					)
					( objectStatus "U5D1.DE68" )
				)
				( pin "ddr3_ecc(2)"
					( attribute "PN" "DB65"
						( Origin gPackager )
					)
					( objectStatus "U5D1.DB65" )
				)
				( pin "ddr3_ecc(3)"
					( attribute "PN" "DD65"
						( Origin gPackager )
					)
					( objectStatus "U5D1.DD65" )
				)
				( pin "ddr3_ecc(4)"
					( attribute "PN" "DB69"
						( Origin gPackager )
					)
					( objectStatus "U5D1.DB69" )
				)
				( pin "ddr3_ecc(5)"
					( attribute "PN" "DD69"
						( Origin gPackager )
					)
					( objectStatus "U5D1.DD69" )
				)
				( pin "ddr3_ecc(6)"
					( attribute "PN" "DA66"
						( Origin gPackager )
					)
					( objectStatus "U5D1.DA66" )
				)
				( pin "ddr3_ecc(7)"
					( attribute "PN" "DE66"
						( Origin gPackager )
					)
					( objectStatus "U5D1.DE66" )
				)
				( pin "ddr3_ma(0)"
					( attribute "PN" "EB53"
						( Origin gPackager )
					)
					( objectStatus "U5D1.EB53" )
				)
				( pin "ddr3_ma(1)"
					( attribute "PN" "ED57"
						( Origin gPackager )
					)
					( objectStatus "U5D1.ED57" )
				)
				( pin "ddr3_ma(2)"
					( attribute "PN" "EE58"
						( Origin gPackager )
					)
					( objectStatus "U5D1.EE58" )
				)
				( pin "ddr3_ma(3)"
					( attribute "PN" "EB57"
						( Origin gPackager )
					)
					( objectStatus "U5D1.EB57" )
				)
				( pin "ddr3_ma(4)"
					( attribute "PN" "ED59"
						( Origin gPackager )
					)
					( objectStatus "U5D1.ED59" )
				)
				( pin "ddr3_ma(5)"
					( attribute "PN" "EA58"
						( Origin gPackager )
					)
					( objectStatus "U5D1.EA58" )
				)
				( pin "ddr3_ma(6)"
					( attribute "PN" "EE60"
						( Origin gPackager )
					)
					( objectStatus "U5D1.EE60" )
				)
				( pin "ddr3_ma(7)"
					( attribute "PN" "EA60"
						( Origin gPackager )
					)
					( objectStatus "U5D1.EA60" )
				)
				( pin "ddr3_ma(8)"
					( attribute "PN" "EB59"
						( Origin gPackager )
					)
					( objectStatus "U5D1.EB59" )
				)
				( pin "ddr3_ma(9)"
					( attribute "PN" "EF61"
						( Origin gPackager )
					)
					( objectStatus "U5D1.EF61" )
				)
				( pin "ddr3_ma(10)"
					( attribute "PN" "DW54"
						( Origin gPackager )
					)
					( objectStatus "U5D1.DW54" )
				)
				( pin "ddr3_ma(11)"
					( attribute "PN" "EB61"
						( Origin gPackager )
					)
					( objectStatus "U5D1.EB61" )
				)
				( pin "ddr3_ma(12)"
					( attribute "PN" "DT63"
						( Origin gPackager )
					)
					( objectStatus "U5D1.DT63" )
				)
				( pin "ddr3_ma(13)"
					( attribute "PN" "DW48"
						( Origin gPackager )
					)
					( objectStatus "U5D1.DW48" )
				)
				( pin "ddr3_ma(14)"
					( attribute "PN" "ED51"
						( Origin gPackager )
					)
					( objectStatus "U5D1.ED51" )
				)
				( pin "ddr3_ma(15)"
					( attribute "PN" "DV49"
						( Origin gPackager )
					)
					( objectStatus "U5D1.DV49" )
				)
				( pin "ddr3_ma(16)"
					( attribute "PN" "EA52"
						( Origin gPackager )
					)
					( objectStatus "U5D1.EA52" )
				)
				( pin "ddr3_ma(17)"
					( attribute "PN" "EA46"
						( Origin gPackager )
					)
					( objectStatus "U5D1.EA46" )
				)
				( pin "ddr3_odt(0)"
					( attribute "PN" "EE50"
						( Origin gPackager )
					)
					( objectStatus "U5D1.EE50" )
				)
				( pin "ddr3_odt(1)"
					( attribute "PN" "EE48"
						( Origin gPackager )
					)
					( objectStatus "U5D1.EE48" )
				)
				( pin "ddr3_odt(2)"
					( attribute "PN" "EA50"
						( Origin gPackager )
					)
					( objectStatus "U5D1.EA50" )
				)
				( pin "ddr3_odt(3)"
					( attribute "PN" "EA48"
						( Origin gPackager )
					)
					( objectStatus "U5D1.EA48" )
				)
				( pin "ddr3_par"
					( attribute "PN" "ED53"
						( Origin gPackager )
					)
					( objectStatus "U5D1.ED53" )
				)
			)
			( gate "@baseboard_fab2_lib.baseboard_fab2(sch_1):page27_i172"
				( attribute "CDS_LIB" "chpset_lib"
					( Origin gPackager )
				)
				( attribute "CDS_LOCATION" "U5D1"
					( Origin gPackager )
				)
				( attribute "CDS_SEC" "7"
					( Origin gPackager )
				)
				( attribute "LOCATION" "U5D1"
					( Origin gFrontEnd )
				)
				( attribute "MATERIAL" "IC"
					( Origin gFrontEnd )
				)
				( attribute "PACK_TYPE" "BGA1"
					( Origin gFrontEnd )
				)
				( attribute "PART_NUMBER" "TBD"
					( Origin gFrontEnd )
				)
				( attribute "PHYS_PAGE" "27"
					( Origin gFrontEnd )
				)
				( attribute "ROOM" "CPU0"
					( Origin gFrontEnd )
				)
				( attribute "ROT" "0"
					( Origin gFrontEnd )
				)
				( attribute "SEC" "7"
					( Origin gFrontEnd )
				)
				( attribute "SEC_TYPE" "BGA1"
					( Origin gFrontEnd )
				)
				( attribute "VER" "7"
					( Origin gFrontEnd )
				)
				( attribute "XY" "(-4175,2550)"
					( Origin gFrontEnd )
				)
				( attribute "CHIPS_PART_NAME" "SKX_EXT_B"
					( Origin gPackager )
				)
				( attribute "CDS_PART_NAME" "SKX_EXT_B_BGA1-IC,TBD"
					( Origin gPackager )
				)
				( objectStatus "U5D1" )
				( pin "ddr4_act_n"
					( attribute "PN" "DR62"
						( Origin gPackager )
					)
					( objectStatus "U5D1.DR62" )
				)
				( pin "ddr4_alert_n"
					( attribute "PN" "DT61"
						( Origin gPackager )
					)
					( objectStatus "U5D1.DT61" )
				)
				( pin "ddr4_ba(0)"
					( attribute "PN" "DM53"
						( Origin gPackager )
					)
					( objectStatus "U5D1.DM53" )
				)
				( pin "ddr4_ba(1)"
					( attribute "PN" "DV55"
						( Origin gPackager )
					)
					( objectStatus "U5D1.DV55" )
				)
				( pin "ddr4_bg(0)"
					( attribute "PN" "DJ62"
						( Origin gPackager )
					)
					( objectStatus "U5D1.DJ62" )
				)
				( pin "ddr4_bg(1)"
					( attribute "PN" "DM61"
						( Origin gPackager )
					)
					( objectStatus "U5D1.DM61" )
				)
				( pin "ddr4_cid(2)"
					( attribute "PN" "DT47"
						( Origin gPackager )
					)
					( objectStatus "U5D1.DT47" )
				)
				( pin "ddr4_cke(0)"
					( attribute "PN" "DM63"
						( Origin gPackager )
					)
					( objectStatus "U5D1.DM63" )
				)
				( pin "ddr4_cke(1)"
					( attribute "PN" "DN64"
						( Origin gPackager )
					)
					( objectStatus "U5D1.DN64" )
				)
				( pin "ddr4_cke(2)"
					( attribute "PN" "DL64"
						( Origin gPackager )
					)
					( objectStatus "U5D1.DL64" )
				)
				( pin "ddr4_cke(3)"
					( attribute "PN" "DR64"
						( Origin gPackager )
					)
					( objectStatus "U5D1.DR64" )
				)
				( pin "ddr4_clk_dn(0)"
					( attribute "PN" "DM55"
						( Origin gPackager )
					)
					( objectStatus "U5D1.DM55" )
				)
				( pin "ddr4_clk_dn(1)"
					( attribute "PN" "DR54"
						( Origin gPackager )
					)
					( objectStatus "U5D1.DR54" )
				)
				( pin "ddr4_clk_dn(2)"
					( attribute "PN" "DM57"
						( Origin gPackager )
					)
					( objectStatus "U5D1.DM57" )
				)
				( pin "ddr4_clk_dn(3)"
					( attribute "PN" "DT57"
						( Origin gPackager )
					)
					( objectStatus "U5D1.DT57" )
				)
				( pin "ddr4_clk_dp(0)"
					( attribute "PN" "DN54"
						( Origin gPackager )
					)
					( objectStatus "U5D1.DN54" )
				)
				( pin "ddr4_clk_dp(1)"
					( attribute "PN" "DT53"
						( Origin gPackager )
					)
					( objectStatus "U5D1.DT53" )
				)
				( pin "ddr4_clk_dp(2)"
					( attribute "PN" "DN56"
						( Origin gPackager )
					)
					( objectStatus "U5D1.DN56" )
				)
				( pin "ddr4_clk_dp(3)"
					( attribute "PN" "DR56"
						( Origin gPackager )
					)
					( objectStatus "U5D1.DR56" )
				)
				( pin "ddr4_cs_n(0)"
					( attribute "PN" "DV51"
						( Origin gPackager )
					)
					( objectStatus "U5D1.DV51" )
				)
				( pin "ddr4_cs_n(1)"
					( attribute "PN" "DN50"
						( Origin gPackager )
					)
					( objectStatus "U5D1.DN50" )
				)
				( pin "ddr4_cs_n(2)"
					( attribute "PN" "DR46"
						( Origin gPackager )
					)
					( objectStatus "U5D1.DR46" )
				)
				( pin "ddr4_cs_n(3)"
					( attribute "PN" "DK47"
						( Origin gPackager )
					)
					( objectStatus "U5D1.DK47" )
				)
				( pin "ddr4_cs_n(4)"
					( attribute "PN" "DW50"
						( Origin gPackager )
					)
					( objectStatus "U5D1.DW50" )
				)
				( pin "ddr4_cs_n(5)"
					( attribute "PN" "DM49"
						( Origin gPackager )
					)
					( objectStatus "U5D1.DM49" )
				)
				( pin "ddr4_cs_n(6)"
					( attribute "PN" "DT45"
						( Origin gPackager )
					)
					( objectStatus "U5D1.DT45" )
				)
				( pin "ddr4_cs_n(7)"
					( attribute "PN" "DN46"
						( Origin gPackager )
					)
					( objectStatus "U5D1.DN46" )
				)
				( pin "ddr4_dq(0)"
					( attribute "PN" "CM79"
						( Origin gPackager )
					)
					( objectStatus "U5D1.CM79" )
				)
				( pin "ddr4_dq(1)"
					( attribute "PN" "CK81"
						( Origin gPackager )
					)
					( objectStatus "U5D1.CK81" )
				)
				( pin "ddr4_dq(2)"
					( attribute "PN" "CT81"
						( Origin gPackager )
					)
					( objectStatus "U5D1.CT81" )
				)
				( pin "ddr4_dq(3)"
					( attribute "PN" "CR82"
						( Origin gPackager )
					)
					( objectStatus "U5D1.CR82" )
				)
				( pin "ddr4_dq(4)"
					( attribute "PN" "CK79"
						( Origin gPackager )
					)
					( objectStatus "U5D1.CK79" )
				)
				( pin "ddr4_dq(5)"
					( attribute "PN" "CJ80"
						( Origin gPackager )
					)
					( objectStatus "U5D1.CJ80" )
				)
				( pin "ddr4_dq(6)"
					( attribute "PN" "CR80"
						( Origin gPackager )
					)
					( objectStatus "U5D1.CR80" )
				)
				( pin "ddr4_dq(7)"
					( attribute "PN" "CN82"
						( Origin gPackager )
					)
					( objectStatus "U5D1.CN82" )
				)
				( pin "ddr4_dq(8)"
					( attribute "PN" "DB79"
						( Origin gPackager )
					)
					( objectStatus "U5D1.DB79" )
				)
				( pin "ddr4_dq(9)"
					( attribute "PN" "CY81"
						( Origin gPackager )
					)
					( objectStatus "U5D1.CY81" )
				)
				( pin "ddr4_dq(10)"
					( attribute "PN" "DE80"
						( Origin gPackager )
					)
					( objectStatus "U5D1.DE80" )
				)
				( pin "ddr4_dq(11)"
					( attribute "PN" "DF81"
						( Origin gPackager )
					)
					( objectStatus "U5D1.DF81" )
				)
				( pin "ddr4_dq(12)"
					( attribute "PN" "CY79"
						( Origin gPackager )
					)
					( objectStatus "U5D1.CY79" )
				)
				( pin "ddr4_dq(13)"
					( attribute "PN" "CW80"
						( Origin gPackager )
					)
					( objectStatus "U5D1.CW80" )
				)
				( pin "ddr4_dq(14)"
					( attribute "PN" "DC82"
						( Origin gPackager )
					)
					( objectStatus "U5D1.DC82" )
				)
				( pin "ddr4_dq(15)"
					( attribute "PN" "DE82"
						( Origin gPackager )
					)
					( objectStatus "U5D1.DE82" )
				)
				( pin "ddr4_dq(16)"
					( attribute "PN" "DW80"
						( Origin gPackager )
					)
					( objectStatus "U5D1.DW80" )
				)
				( pin "ddr4_dq(17)"
					( attribute "PN" "EC80"
						( Origin gPackager )
					)
					( objectStatus "U5D1.EC80" )
				)
				( pin "ddr4_dq(18)"
					( attribute "PN" "DY77"
						( Origin gPackager )
					)
					( objectStatus "U5D1.DY77" )
				)
				( pin "ddr4_dq(19)"
					( attribute "PN" "EB77"
						( Origin gPackager )
					)
					( objectStatus "U5D1.EB77" )
				)
				( pin "ddr4_dq(20)"
					( attribute "PN" "DY81"
						( Origin gPackager )
					)
					( objectStatus "U5D1.DY81" )
				)
				( pin "ddr4_dq(21)"
					( attribute "PN" "EB81"
						( Origin gPackager )
					)
					( objectStatus "U5D1.EB81" )
				)
				( pin "ddr4_dq(22)"
					( attribute "PN" "DW78"
						( Origin gPackager )
					)
					( objectStatus "U5D1.DW78" )
				)
				( pin "ddr4_dq(23)"
					( attribute "PN" "EC78"
						( Origin gPackager )
					)
					( objectStatus "U5D1.EC78" )
				)
				( pin "ddr4_dq(24)"
					( attribute "PN" "ED75"
						( Origin gPackager )
					)
					( objectStatus "U5D1.ED75" )
				)
				( pin "ddr4_dq(25)"
					( attribute "PN" "EE74"
						( Origin gPackager )
					)
					( objectStatus "U5D1.EE74" )
				)
				( pin "ddr4_dq(26)"
					( attribute "PN" "EB71"
						( Origin gPackager )
					)
					( objectStatus "U5D1.EB71" )
				)
				( pin "ddr4_dq(27)"
					( attribute "PN" "ED71"
						( Origin gPackager )
					)
					( objectStatus "U5D1.ED71" )
				)
				( pin "ddr4_dq(28)"
					( attribute "PN" "EA74"
						( Origin gPackager )
					)
					( objectStatus "U5D1.EA74" )
				)
				( pin "ddr4_dq(29)"
					( attribute "PN" "EB75"
						( Origin gPackager )
					)
					( objectStatus "U5D1.EB75" )
				)
				( pin "ddr4_dq(30)"
					( attribute "PN" "EA72"
						( Origin gPackager )
					)
					( objectStatus "U5D1.EA72" )
				)
				( pin "ddr4_dq(31)"
					( attribute "PN" "EE72"
						( Origin gPackager )
					)
					( objectStatus "U5D1.EE72" )
				)
				( pin "ddr4_dq(32)"
					( attribute "PN" "DU42"
						( Origin gPackager )
					)
					( objectStatus "U5D1.DU42" )
				)
				( pin "ddr4_dq(33)"
					( attribute "PN" "DW42"
						( Origin gPackager )
					)
					( objectStatus "U5D1.DW42" )
				)
				( pin "ddr4_dq(34)"
					( attribute "PN" "DP39"
						( Origin gPackager )
					)
					( objectStatus "U5D1.DP39" )
				)
				( pin "ddr4_dq(35)"
					( attribute "PN" "DT39"
						( Origin gPackager )
					)
					( objectStatus "U5D1.DT39" )
				)
				( pin "ddr4_dq(36)"
					( attribute "PN" "DL42"
						( Origin gPackager )
					)
					( objectStatus "U5D1.DL42" )
				)
				( pin "ddr4_dq(37)"
					( attribute "PN" "DN42"
						( Origin gPackager )
					)
					( objectStatus "U5D1.DN42" )
				)
				( pin "ddr4_dq(38)"
					( attribute "PN" "DN40"
						( Origin gPackager )
					)
					( objectStatus "U5D1.DN40" )
				)
				( pin "ddr4_dq(39)"
					( attribute "PN" "DU40"
						( Origin gPackager )
					)
					( objectStatus "U5D1.DU40" )
				)
				( pin "ddr4_dq(40)"
					( attribute "PN" "EC34"
						( Origin gPackager )
					)
					( objectStatus "U5D1.EC34" )
				)
				( pin "ddr4_dq(41)"
					( attribute "PN" "ED33"
						( Origin gPackager )
					)
					( objectStatus "U5D1.ED33" )
				)
				( pin "ddr4_dq(42)"
					( attribute "PN" "EA30"
						( Origin gPackager )
					)
					( objectStatus "U5D1.EA30" )
				)
				( pin "ddr4_dq(43)"
					( attribute "PN" "EC30"
						( Origin gPackager )
					)
					( objectStatus "U5D1.EC30" )
				)
				( pin "ddr4_dq(44)"
					( attribute "PN" "DY33"
						( Origin gPackager )
					)
					( objectStatus "U5D1.DY33" )
				)
				( pin "ddr4_dq(45)"
					( attribute "PN" "EA34"
						( Origin gPackager )
					)
					( objectStatus "U5D1.EA34" )
				)
				( pin "ddr4_dq(46)"
					( attribute "PN" "DY31"
						( Origin gPackager )
					)
					( objectStatus "U5D1.DY31" )
				)
				( pin "ddr4_dq(47)"
					( attribute "PN" "ED31"
						( Origin gPackager )
					)
					( objectStatus "U5D1.ED31" )
				)
				( pin "ddr4_dq(48)"
					( attribute "PN" "EC28"
						( Origin gPackager )
					)
					( objectStatus "U5D1.EC28" )
				)
				( pin "ddr4_dq(49)"
					( attribute "PN" "ED27"
						( Origin gPackager )
					)
					( objectStatus "U5D1.ED27" )
				)
				( pin "ddr4_dq(50)"
					( attribute "PN" "EA24"
						( Origin gPackager )
					)
					( objectStatus "U5D1.EA24" )
				)
				( pin "ddr4_dq(51)"
					( attribute "PN" "EC24"
						( Origin gPackager )
					)
					( objectStatus "U5D1.EC24" )
				)
				( pin "ddr4_dq(52)"
					( attribute "PN" "DY27"
						( Origin gPackager )
					)
					( objectStatus "U5D1.DY27" )
				)
				( pin "ddr4_dq(53)"
					( attribute "PN" "EA28"
						( Origin gPackager )
					)
					( objectStatus "U5D1.EA28" )
				)
				( pin "ddr4_dq(54)"
					( attribute "PN" "DY25"
						( Origin gPackager )
					)
					( objectStatus "U5D1.DY25" )
				)
				( pin "ddr4_dq(55)"
					( attribute "PN" "ED25"
						( Origin gPackager )
					)
					( objectStatus "U5D1.ED25" )
				)
				( pin "ddr4_dq(56)"
					( attribute "PN" "DF27"
						( Origin gPackager )
					)
					( objectStatus "U5D1.DF27" )
				)
				( pin "ddr4_dq(57)"
					( attribute "PN" "DK27"
						( Origin gPackager )
					)
					( objectStatus "U5D1.DK27" )
				)
				( pin "ddr4_dq(58)"
					( attribute "PN" "DD25"
						( Origin gPackager )
					)
					( objectStatus "U5D1.DD25" )
				)
				( pin "ddr4_dq(59)"
					( attribute "PN" "DJ24"
						( Origin gPackager )
					)
					( objectStatus "U5D1.DJ24" )
				)
				( pin "ddr4_dq(60)"
					( attribute "PN" "DG28"
						( Origin gPackager )
					)
					( objectStatus "U5D1.DG28" )
				)
				( pin "ddr4_dq(61)"
					( attribute "PN" "DJ28"
						( Origin gPackager )
					)
					( objectStatus "U5D1.DJ28" )
				)
				( pin "ddr4_dq(62)"
					( attribute "PN" "DF25"
						( Origin gPackager )
					)
					( objectStatus "U5D1.DF25" )
				)
				( pin "ddr4_dq(63)"
					( attribute "PN" "DK25"
						( Origin gPackager )
					)
					( objectStatus "U5D1.DK25" )
				)
				( pin "ddr4_dqs_dn(0)"
					( attribute "PN" "CL82"
						( Origin gPackager )
					)
					( objectStatus "U5D1.CL82" )
				)
				( pin "ddr4_dqs_dn(1)"
					( attribute "PN" "DA82"
						( Origin gPackager )
					)
					( objectStatus "U5D1.DA82" )
				)
				( pin "ddr4_dqs_dn(2)"
					( attribute "PN" "ED79"
						( Origin gPackager )
					)
					( objectStatus "U5D1.ED79" )
				)
				( pin "ddr4_dqs_dn(3)"
					( attribute "PN" "EF73"
						( Origin gPackager )
					)
					( objectStatus "U5D1.EF73" )
				)
				( pin "ddr4_dqs_dn(4)"
					( attribute "PN" "DV41"
						( Origin gPackager )
					)
					( objectStatus "U5D1.DV41" )
				)
				( pin "ddr4_dqs_dn(5)"
					( attribute "PN" "EE32"
						( Origin gPackager )
					)
					( objectStatus "U5D1.EE32" )
				)
				( pin "ddr4_dqs_dn(6)"
					( attribute "PN" "EE26"
						( Origin gPackager )
					)
					( objectStatus "U5D1.EE26" )
				)
				( pin "ddr4_dqs_dn(7)"
					( attribute "PN" "DL26"
						( Origin gPackager )
					)
					( objectStatus "U5D1.DL26" )
				)
				( pin "ddr4_dqs_dn(8)"
					( attribute "PN" "EB67"
						( Origin gPackager )
					)
					( objectStatus "U5D1.EB67" )
				)
				( pin "ddr4_dqs_dn(9)"
					( attribute "PN" "CN80"
						( Origin gPackager )
					)
					( objectStatus "U5D1.CN80" )
				)
				( pin "ddr4_dqs_dn(10)"
					( attribute "PN" "DC80"
						( Origin gPackager )
					)
					( objectStatus "U5D1.DC80" )
				)
				( pin "ddr4_dqs_dn(11)"
					( attribute "PN" "DY79"
						( Origin gPackager )
					)
					( objectStatus "U5D1.DY79" )
				)
				( pin "ddr4_dqs_dn(12)"
					( attribute "PN" "EB73"
						( Origin gPackager )
					)
					( objectStatus "U5D1.EB73" )
				)
				( pin "ddr4_dqs_dn(13)"
					( attribute "PN" "DP41"
						( Origin gPackager )
					)
					( objectStatus "U5D1.DP41" )
				)
				( pin "ddr4_dqs_dn(14)"
					( attribute "PN" "EA32"
						( Origin gPackager )
					)
					( objectStatus "U5D1.EA32" )
				)
				( pin "ddr4_dqs_dn(15)"
					( attribute "PN" "EA26"
						( Origin gPackager )
					)
					( objectStatus "U5D1.EA26" )
				)
				( pin "ddr4_dqs_dn(16)"
					( attribute "PN" "DG26"
						( Origin gPackager )
					)
					( objectStatus "U5D1.DG26" )
				)
				( pin "ddr4_dqs_dn(17)"
					( attribute "PN" "DV67"
						( Origin gPackager )
					)
					( objectStatus "U5D1.DV67" )
				)
				( pin "ddr4_dqs_dp(0)"
					( attribute "PN" "CM81"
						( Origin gPackager )
					)
					( objectStatus "U5D1.CM81" )
				)
				( pin "ddr4_dqs_dp(1)"
					( attribute "PN" "DB81"
						( Origin gPackager )
					)
					( objectStatus "U5D1.DB81" )
				)
				( pin "ddr4_dqs_dp(2)"
					( attribute "PN" "EB79"
						( Origin gPackager )
					)
					( objectStatus "U5D1.EB79" )
				)
				( pin "ddr4_dqs_dp(3)"
					( attribute "PN" "ED73"
						( Origin gPackager )
					)
					( objectStatus "U5D1.ED73" )
				)
				( pin "ddr4_dqs_dp(4)"
					( attribute "PN" "DT41"
						( Origin gPackager )
					)
					( objectStatus "U5D1.DT41" )
				)
				( pin "ddr4_dqs_dp(5)"
					( attribute "PN" "EC32"
						( Origin gPackager )
					)
					( objectStatus "U5D1.EC32" )
				)
				( pin "ddr4_dqs_dp(6)"
					( attribute "PN" "EC26"
						( Origin gPackager )
					)
					( objectStatus "U5D1.EC26" )
				)
				( pin "ddr4_dqs_dp(7)"
					( attribute "PN" "DJ26"
						( Origin gPackager )
					)
					( objectStatus "U5D1.DJ26" )
				)
				( pin "ddr4_dqs_dp(8)"
					( attribute "PN" "DY67"
						( Origin gPackager )
					)
					( objectStatus "U5D1.DY67" )
				)
				( pin "ddr4_dqs_dp(9)"
					( attribute "PN" "CP79"
						( Origin gPackager )
					)
					( objectStatus "U5D1.CP79" )
				)
				( pin "ddr4_dqs_dp(10)"
					( attribute "PN" "DD79"
						( Origin gPackager )
					)
					( objectStatus "U5D1.DD79" )
				)
				( pin "ddr4_dqs_dp(11)"
					( attribute "PN" "DV79"
						( Origin gPackager )
					)
					( objectStatus "U5D1.DV79" )
				)
				( pin "ddr4_dqs_dp(12)"
					( attribute "PN" "DY73"
						( Origin gPackager )
					)
					( objectStatus "U5D1.DY73" )
				)
				( pin "ddr4_dqs_dp(13)"
					( attribute "PN" "DM41"
						( Origin gPackager )
					)
					( objectStatus "U5D1.DM41" )
				)
				( pin "ddr4_dqs_dp(14)"
					( attribute "PN" "DW32"
						( Origin gPackager )
					)
					( objectStatus "U5D1.DW32" )
				)
				( pin "ddr4_dqs_dp(15)"
					( attribute "PN" "DW26"
						( Origin gPackager )
					)
					( objectStatus "U5D1.DW26" )
				)
				( pin "ddr4_dqs_dp(16)"
					( attribute "PN" "DE26"
						( Origin gPackager )
					)
					( objectStatus "U5D1.DE26" )
				)
				( pin "ddr4_dqs_dp(17)"
					( attribute "PN" "DT67"
						( Origin gPackager )
					)
					( objectStatus "U5D1.DT67" )
				)
				( pin "ddr4_ecc(0)"
					( attribute "PN" "DY69"
						( Origin gPackager )
					)
					( objectStatus "U5D1.DY69" )
				)
				( pin "ddr4_ecc(1)"
					( attribute "PN" "EA68"
						( Origin gPackager )
					)
					( objectStatus "U5D1.EA68" )
				)
				( pin "ddr4_ecc(2)"
					( attribute "PN" "DV65"
						( Origin gPackager )
					)
					( objectStatus "U5D1.DV65" )
				)
				( pin "ddr4_ecc(3)"
					( attribute "PN" "DY65"
						( Origin gPackager )
					)
					( objectStatus "U5D1.DY65" )
				)
				( pin "ddr4_ecc(4)"
					( attribute "PN" "DU68"
						( Origin gPackager )
					)
					( objectStatus "U5D1.DU68" )
				)
				( pin "ddr4_ecc(5)"
					( attribute "PN" "DV69"
						( Origin gPackager )
					)
					( objectStatus "U5D1.DV69" )
				)
				( pin "ddr4_ecc(6)"
					( attribute "PN" "DU66"
						( Origin gPackager )
					)
					( objectStatus "U5D1.DU66" )
				)
				( pin "ddr4_ecc(7)"
					( attribute "PN" "EA66"
						( Origin gPackager )
					)
					( objectStatus "U5D1.EA66" )
				)
				( pin "ddr4_ma(0)"
					( attribute "PN" "DW52"
						( Origin gPackager )
					)
					( objectStatus "U5D1.DW52" )
				)
				( pin "ddr4_ma(1)"
					( attribute "PN" "DW58"
						( Origin gPackager )
					)
					( objectStatus "U5D1.DW58" )
				)
				( pin "ddr4_ma(2)"
					( attribute "PN" "DV57"
						( Origin gPackager )
					)
					( objectStatus "U5D1.DV57" )
				)
				( pin "ddr4_ma(3)"
					( attribute "PN" "DR58"
						( Origin gPackager )
					)
					( objectStatus "U5D1.DR58" )
				)
				( pin "ddr4_ma(4)"
					( attribute "PN" "DT59"
						( Origin gPackager )
					)
					( objectStatus "U5D1.DT59" )
				)
				( pin "ddr4_ma(5)"
					( attribute "PN" "DN58"
						( Origin gPackager )
					)
					( objectStatus "U5D1.DN58" )
				)
				( pin "ddr4_ma(6)"
					( attribute "PN" "DM59"
						( Origin gPackager )
					)
					( objectStatus "U5D1.DM59" )
				)
				( pin "ddr4_ma(7)"
					( attribute "PN" "DK61"
						( Origin gPackager )
					)
					( objectStatus "U5D1.DK61" )
				)
				( pin "ddr4_ma(8)"
					( attribute "PN" "DJ60"
						( Origin gPackager )
					)
					( objectStatus "U5D1.DJ60" )
				)
				( pin "ddr4_ma(9)"
					( attribute "PN" "DV59"
						( Origin gPackager )
					)
					( objectStatus "U5D1.DV59" )
				)
				( pin "ddr4_ma(10)"
					( attribute "PN" "DT55"
						( Origin gPackager )
					)
					( objectStatus "U5D1.DT55" )
				)
				( pin "ddr4_ma(11)"
					( attribute "PN" "DR60"
						( Origin gPackager )
					)
					( objectStatus "U5D1.DR60" )
				)
				( pin "ddr4_ma(12)"
					( attribute "PN" "DN60"
						( Origin gPackager )
					)
					( objectStatus "U5D1.DN60" )
				)
				( pin "ddr4_ma(13)"
					( attribute "PN" "DT51"
						( Origin gPackager )
					)
					( objectStatus "U5D1.DT51" )
				)
				( pin "ddr4_ma(14)"
					( attribute "PN" "DM51"
						( Origin gPackager )
					)
					( objectStatus "U5D1.DM51" )
				)
				( pin "ddr4_ma(15)"
					( attribute "PN" "DR52"
						( Origin gPackager )
					)
					( objectStatus "U5D1.DR52" )
				)
				( pin "ddr4_ma(16)"
					( attribute "PN" "DN52"
						( Origin gPackager )
					)
					( objectStatus "U5D1.DN52" )
				)
				( pin "ddr4_ma(17)"
					( attribute "PN" "DR48"
						( Origin gPackager )
					)
					( objectStatus "U5D1.DR48" )
				)
				( pin "ddr4_odt(0)"
					( attribute "PN" "DR50"
						( Origin gPackager )
					)
					( objectStatus "U5D1.DR50" )
				)
				( pin "ddr4_odt(1)"
					( attribute "PN" "DN48"
						( Origin gPackager )
					)
					( objectStatus "U5D1.DN48" )
				)
				( pin "ddr4_odt(2)"
					( attribute "PN" "DT49"
						( Origin gPackager )
					)
					( objectStatus "U5D1.DT49" )
				)
				( pin "ddr4_odt(3)"
					( attribute "PN" "DM47"
						( Origin gPackager )
					)
					( objectStatus "U5D1.DM47" )
				)
				( pin "ddr4_par"
					( attribute "PN" "DV53"
						( Origin gPackager )
					)
					( objectStatus "U5D1.DV53" )
				)
			)
			( gate "@baseboard_fab2_lib.baseboard_fab2(sch_1):page28_i172"
				( attribute "CDS_LIB" "chpset_lib"
					( Origin gPackager )
				)
				( attribute "CDS_LOCATION" "U5D1"
					( Origin gPackager )
				)
				( attribute "CDS_SEC" "8"
					( Origin gPackager )
				)
				( attribute "LOCATION" "U5D1"
					( Origin gFrontEnd )
				)
				( attribute "MATERIAL" "IC"
					( Origin gFrontEnd )
				)
				( attribute "PACK_TYPE" "BGA1"
					( Origin gFrontEnd )
				)
				( attribute "PART_NUMBER" "TBD"
					( Origin gFrontEnd )
				)
				( attribute "PHYS_PAGE" "28"
					( Origin gFrontEnd )
				)
				( attribute "ROOM" "CPU0"
					( Origin gFrontEnd )
				)
				( attribute "ROT" "0"
					( Origin gFrontEnd )
				)
				( attribute "SEC" "8"
					( Origin gFrontEnd )
				)
				( attribute "SEC_TYPE" "BGA1"
					( Origin gFrontEnd )
				)
				( attribute "VER" "8"
					( Origin gFrontEnd )
				)
				( attribute "XY" "(-4175,2575)"
					( Origin gFrontEnd )
				)
				( attribute "CHIPS_PART_NAME" "SKX_EXT_B"
					( Origin gPackager )
				)
				( attribute "CDS_PART_NAME" "SKX_EXT_B_BGA1-IC,TBD"
					( Origin gPackager )
				)
				( objectStatus "U5D1" )
				( pin "ddr5_act_n"
					( attribute "PN" "DC62"
						( Origin gPackager )
					)
					( objectStatus "U5D1.DC62" )
				)
				( pin "ddr5_alert_n"
					( attribute "PN" "DD61"
						( Origin gPackager )
					)
					( objectStatus "U5D1.DD61" )
				)
				( pin "ddr5_ba(0)"
					( attribute "PN" "DJ52"
						( Origin gPackager )
					)
					( objectStatus "U5D1.DJ52" )
				)
				( pin "ddr5_ba(1)"
					( attribute "PN" "DC56"
						( Origin gPackager )
					)
					( objectStatus "U5D1.DC56" )
				)
				( pin "ddr5_bg(0)"
					( attribute "PN" "DA62"
						( Origin gPackager )
					)
					( objectStatus "U5D1.DA62" )
				)
				( pin "ddr5_bg(1)"
					( attribute "PN" "DF61"
						( Origin gPackager )
					)
					( objectStatus "U5D1.DF61" )
				)
				( pin "ddr5_cid(2)"
					( attribute "PN" "DF45"
						( Origin gPackager )
					)
					( objectStatus "U5D1.DF45" )
				)
				( pin "ddr5_cke(0)"
					( attribute "PN" "DG62"
						( Origin gPackager )
					)
					( objectStatus "U5D1.DG62" )
				)
				( pin "ddr5_cke(1)"
					( attribute "PN" "DD63"
						( Origin gPackager )
					)
					( objectStatus "U5D1.DD63" )
				)
				( pin "ddr5_cke(2)"
					( attribute "PN" "DK63"
						( Origin gPackager )
					)
					( objectStatus "U5D1.DK63" )
				)
				( pin "ddr5_cke(3)"
					( attribute "PN" "DF63"
						( Origin gPackager )
					)
					( objectStatus "U5D1.DF63" )
				)
				( pin "ddr5_clk_dn(0)"
					( attribute "PN" "DK55"
						( Origin gPackager )
					)
					( objectStatus "U5D1.DK55" )
				)
				( pin "ddr5_clk_dn(1)"
					( attribute "PN" "DF55"
						( Origin gPackager )
					)
					( objectStatus "U5D1.DF55" )
				)
				( pin "ddr5_clk_dn(2)"
					( attribute "PN" "DK57"
						( Origin gPackager )
					)
					( objectStatus "U5D1.DK57" )
				)
				( pin "ddr5_clk_dn(3)"
					( attribute "PN" "DF57"
						( Origin gPackager )
					)
					( objectStatus "U5D1.DF57" )
				)
				( pin "ddr5_clk_dp(0)"
					( attribute "PN" "DJ54"
						( Origin gPackager )
					)
					( objectStatus "U5D1.DJ54" )
				)
				( pin "ddr5_clk_dp(1)"
					( attribute "PN" "DG54"
						( Origin gPackager )
					)
					( objectStatus "U5D1.DG54" )
				)
				( pin "ddr5_clk_dp(2)"
					( attribute "PN" "DJ56"
						( Origin gPackager )
					)
					( objectStatus "U5D1.DJ56" )
				)
				( pin "ddr5_clk_dp(3)"
					( attribute "PN" "DG56"
						( Origin gPackager )
					)
					( objectStatus "U5D1.DG56" )
				)
				( pin "ddr5_cs_n(0)"
					( attribute "PN" "DK51"
						( Origin gPackager )
					)
					( objectStatus "U5D1.DK51" )
				)
				( pin "ddr5_cs_n(1)"
					( attribute "PN" "DF49"
						( Origin gPackager )
					)
					( objectStatus "U5D1.DF49" )
				)
				( pin "ddr5_cs_n(2)"
					( attribute "PN" "DJ46"
						( Origin gPackager )
					)
					( objectStatus "U5D1.DJ46" )
				)
				( pin "ddr5_cs_n(3)"
					( attribute "PN" "DG46"
						( Origin gPackager )
					)
					( objectStatus "U5D1.DG46" )
				)
				( pin "ddr5_cs_n(4)"
					( attribute "PN" "DF51"
						( Origin gPackager )
					)
					( objectStatus "U5D1.DF51" )
				)
				( pin "ddr5_cs_n(5)"
					( attribute "PN" "DJ48"
						( Origin gPackager )
					)
					( objectStatus "U5D1.DJ48" )
				)
				( pin "ddr5_cs_n(6)"
					( attribute "PN" "DM45"
						( Origin gPackager )
					)
					( objectStatus "U5D1.DM45" )
				)
				( pin "ddr5_cs_n(7)"
					( attribute "PN" "DK45"
						( Origin gPackager )
					)
					( objectStatus "U5D1.DK45" )
				)
				( pin "ddr5_dq(0)"
					( attribute "PN" "CR74"
						( Origin gPackager )
					)
					( objectStatus "U5D1.CR74" )
				)
				( pin "ddr5_dq(1)"
					( attribute "PN" "CN76"
						( Origin gPackager )
					)
					( objectStatus "U5D1.CN76" )
				)
				( pin "ddr5_dq(2)"
					( attribute "PN" "CW76"
						( Origin gPackager )
					)
					( objectStatus "U5D1.CW76" )
				)
				( pin "ddr5_dq(3)"
					( attribute "PN" "CV77"
						( Origin gPackager )
					)
					( objectStatus "U5D1.CV77" )
				)
				( pin "ddr5_dq(4)"
					( attribute "PN" "CN74"
						( Origin gPackager )
					)
					( objectStatus "U5D1.CN74" )
				)
				( pin "ddr5_dq(5)"
					( attribute "PN" "CM75"
						( Origin gPackager )
					)
					( objectStatus "U5D1.CM75" )
				)
				( pin "ddr5_dq(6)"
					( attribute "PN" "CV75"
						( Origin gPackager )
					)
					( objectStatus "U5D1.CV75" )
				)
				( pin "ddr5_dq(7)"
					( attribute "PN" "CT77"
						( Origin gPackager )
					)
					( objectStatus "U5D1.CT77" )
				)
				( pin "ddr5_dq(8)"
					( attribute "PN" "DE74"
						( Origin gPackager )
					)
					( objectStatus "U5D1.DE74" )
				)
				( pin "ddr5_dq(9)"
					( attribute "PN" "DC76"
						( Origin gPackager )
					)
					( objectStatus "U5D1.DC76" )
				)
				( pin "ddr5_dq(10)"
					( attribute "PN" "DH75"
						( Origin gPackager )
					)
					( objectStatus "U5D1.DH75" )
				)
				( pin "ddr5_dq(11)"
					( attribute "PN" "DJ76"
						( Origin gPackager )
					)
					( objectStatus "U5D1.DJ76" )
				)
				( pin "ddr5_dq(12)"
					( attribute "PN" "DC74"
						( Origin gPackager )
					)
					( objectStatus "U5D1.DC74" )
				)
				( pin "ddr5_dq(13)"
					( attribute "PN" "DB75"
						( Origin gPackager )
					)
					( objectStatus "U5D1.DB75" )
				)
				( pin "ddr5_dq(14)"
					( attribute "PN" "DF77"
						( Origin gPackager )
					)
					( objectStatus "U5D1.DF77" )
				)
				( pin "ddr5_dq(15)"
					( attribute "PN" "DH77"
						( Origin gPackager )
					)
					( objectStatus "U5D1.DH77" )
				)
				( pin "ddr5_dq(16)"
					( attribute "PN" "DG70"
						( Origin gPackager )
					)
					( objectStatus "U5D1.DG70" )
				)
				( pin "ddr5_dq(17)"
					( attribute "PN" "DJ72"
						( Origin gPackager )
					)
					( objectStatus "U5D1.DJ72" )
				)
				( pin "ddr5_dq(18)"
					( attribute "PN" "DM69"
						( Origin gPackager )
					)
					( objectStatus "U5D1.DM69" )
				)
				( pin "ddr5_dq(19)"
					( attribute "PN" "DN70"
						( Origin gPackager )
					)
					( objectStatus "U5D1.DN70" )
				)
				( pin "ddr5_dq(20)"
					( attribute "PN" "DF71"
						( Origin gPackager )
					)
					( objectStatus "U5D1.DF71" )
				)
				( pin "ddr5_dq(21)"
					( attribute "PN" "DG72"
						( Origin gPackager )
					)
					( objectStatus "U5D1.DG72" )
				)
				( pin "ddr5_dq(22)"
					( attribute "PN" "DK69"
						( Origin gPackager )
					)
					( objectStatus "U5D1.DK69" )
				)
				( pin "ddr5_dq(23)"
					( attribute "PN" "DM71"
						( Origin gPackager )
					)
					( objectStatus "U5D1.DM71" )
				)
				( pin "ddr5_dq(24)"
					( attribute "PN" "CN66"
						( Origin gPackager )
					)
					( objectStatus "U5D1.CN66" )
				)
				( pin "ddr5_dq(25)"
					( attribute "PN" "CU66"
						( Origin gPackager )
					)
					( objectStatus "U5D1.CU66" )
				)
				( pin "ddr5_dq(26)"
					( attribute "PN" "CP63"
						( Origin gPackager )
					)
					( objectStatus "U5D1.CP63" )
				)
				( pin "ddr5_dq(27)"
					( attribute "PN" "CT63"
						( Origin gPackager )
					)
					( objectStatus "U5D1.CT63" )
				)
				( pin "ddr5_dq(28)"
					( attribute "PN" "CP67"
						( Origin gPackager )
					)
					( objectStatus "U5D1.CP67" )
				)
				( pin "ddr5_dq(29)"
					( attribute "PN" "CT67"
						( Origin gPackager )
					)
					( objectStatus "U5D1.CT67" )
				)
				( pin "ddr5_dq(30)"
					( attribute "PN" "CN64"
						( Origin gPackager )
					)
					( objectStatus "U5D1.CN64" )
				)
				( pin "ddr5_dq(31)"
					( attribute "PN" "CU64"
						( Origin gPackager )
					)
					( objectStatus "U5D1.CU64" )
				)
				( pin "ddr5_dq(32)"
					( attribute "PN" "DD41"
						( Origin gPackager )
					)
					( objectStatus "U5D1.DD41" )
				)
				( pin "ddr5_dq(33)"
					( attribute "PN" "DG42"
						( Origin gPackager )
					)
					( objectStatus "U5D1.DG42" )
				)
				( pin "ddr5_dq(34)"
					( attribute "PN" "DE38"
						( Origin gPackager )
					)
					( objectStatus "U5D1.DE38" )
				)
				( pin "ddr5_dq(35)"
					( attribute "PN" "DG38"
						( Origin gPackager )
					)
					( objectStatus "U5D1.DG38" )
				)
				( pin "ddr5_dq(36)"
					( attribute "PN" "DA42"
						( Origin gPackager )
					)
					( objectStatus "U5D1.DA42" )
				)
				( pin "ddr5_dq(37)"
					( attribute "PN" "DE42"
						( Origin gPackager )
					)
					( objectStatus "U5D1.DE42" )
				)
				( pin "ddr5_dq(38)"
					( attribute "PN" "DD39"
						( Origin gPackager )
					)
					( objectStatus "U5D1.DD39" )
				)
				( pin "ddr5_dq(39)"
					( attribute "PN" "DH39"
						( Origin gPackager )
					)
					( objectStatus "U5D1.DH39" )
				)
				( pin "ddr5_dq(40)"
					( attribute "PN" "DF33"
						( Origin gPackager )
					)
					( objectStatus "U5D1.DF33" )
				)
				( pin "ddr5_dq(41)"
					( attribute "PN" "DK33"
						( Origin gPackager )
					)
					( objectStatus "U5D1.DK33" )
				)
				( pin "ddr5_dq(42)"
					( attribute "PN" "DG30"
						( Origin gPackager )
					)
					( objectStatus "U5D1.DG30" )
				)
				( pin "ddr5_dq(43)"
					( attribute "PN" "DJ30"
						( Origin gPackager )
					)
					( objectStatus "U5D1.DJ30" )
				)
				( pin "ddr5_dq(44)"
					( attribute "PN" "DG34"
						( Origin gPackager )
					)
					( objectStatus "U5D1.DG34" )
				)
				( pin "ddr5_dq(45)"
					( attribute "PN" "DJ34"
						( Origin gPackager )
					)
					( objectStatus "U5D1.DJ34" )
				)
				( pin "ddr5_dq(46)"
					( attribute "PN" "DF31"
						( Origin gPackager )
					)
					( objectStatus "U5D1.DF31" )
				)
				( pin "ddr5_dq(47)"
					( attribute "PN" "DK31"
						( Origin gPackager )
					)
					( objectStatus "U5D1.DK31" )
				)
				( pin "ddr5_dq(48)"
					( attribute "PN" "CW36"
						( Origin gPackager )
					)
					( objectStatus "U5D1.CW36" )
				)
				( pin "ddr5_dq(49)"
					( attribute "PN" "DC36"
						( Origin gPackager )
					)
					( objectStatus "U5D1.DC36" )
				)
				( pin "ddr5_dq(50)"
					( attribute "PN" "CY33"
						( Origin gPackager )
					)
					( objectStatus "U5D1.CY33" )
				)
				( pin "ddr5_dq(51)"
					( attribute "PN" "DB33"
						( Origin gPackager )
					)
					( objectStatus "U5D1.DB33" )
				)
				( pin "ddr5_dq(52)"
					( attribute "PN" "CY37"
						( Origin gPackager )
					)
					( objectStatus "U5D1.CY37" )
				)
				( pin "ddr5_dq(53)"
					( attribute "PN" "DB37"
						( Origin gPackager )
					)
					( objectStatus "U5D1.DB37" )
				)
				( pin "ddr5_dq(54)"
					( attribute "PN" "CW34"
						( Origin gPackager )
					)
					( objectStatus "U5D1.CW34" )
				)
				( pin "ddr5_dq(55)"
					( attribute "PN" "DC34"
						( Origin gPackager )
					)
					( objectStatus "U5D1.DC34" )
				)
				( pin "ddr5_dq(56)"
					( attribute "PN" "CW30"
						( Origin gPackager )
					)
					( objectStatus "U5D1.CW30" )
				)
				( pin "ddr5_dq(57)"
					( attribute "PN" "DC30"
						( Origin gPackager )
					)
					( objectStatus "U5D1.DC30" )
				)
				( pin "ddr5_dq(58)"
					( attribute "PN" "CY27"
						( Origin gPackager )
					)
					( objectStatus "U5D1.CY27" )
				)
				( pin "ddr5_dq(59)"
					( attribute "PN" "DB27"
						( Origin gPackager )
					)
					( objectStatus "U5D1.DB27" )
				)
				( pin "ddr5_dq(60)"
					( attribute "PN" "CY31"
						( Origin gPackager )
					)
					( objectStatus "U5D1.CY31" )
				)
				( pin "ddr5_dq(61)"
					( attribute "PN" "DB31"
						( Origin gPackager )
					)
					( objectStatus "U5D1.DB31" )
				)
				( pin "ddr5_dq(62)"
					( attribute "PN" "CW28"
						( Origin gPackager )
					)
					( objectStatus "U5D1.CW28" )
				)
				( pin "ddr5_dq(63)"
					( attribute "PN" "DC28"
						( Origin gPackager )
					)
					( objectStatus "U5D1.DC28" )
				)
				( pin "ddr5_dqs_dn(0)"
					( attribute "PN" "CP77"
						( Origin gPackager )
					)
					( objectStatus "U5D1.CP77" )
				)
				( pin "ddr5_dqs_dn(1)"
					( attribute "PN" "DD77"
						( Origin gPackager )
					)
					( objectStatus "U5D1.DD77" )
				)
				( pin "ddr5_dqs_dn(2)"
					( attribute "PN" "DL72"
						( Origin gPackager )
					)
					( objectStatus "U5D1.DL72" )
				)
				( pin "ddr5_dqs_dn(3)"
					( attribute "PN" "CV65"
						( Origin gPackager )
					)
					( objectStatus "U5D1.CV65" )
				)
				( pin "ddr5_dqs_dn(4)"
					( attribute "PN" "DG40"
						( Origin gPackager )
					)
					( objectStatus "U5D1.DG40" )
				)
				( pin "ddr5_dqs_dn(5)"
					( attribute "PN" "DL32"
						( Origin gPackager )
					)
					( objectStatus "U5D1.DL32" )
				)
				( pin "ddr5_dqs_dn(6)"
					( attribute "PN" "DD35"
						( Origin gPackager )
					)
					( objectStatus "U5D1.DD35" )
				)
				( pin "ddr5_dqs_dn(7)"
					( attribute "PN" "DD29"
						( Origin gPackager )
					)
					( objectStatus "U5D1.DD29" )
				)
				( pin "ddr5_dqs_dn(8)"
					( attribute "PN" "CN70"
						( Origin gPackager )
					)
					( objectStatus "U5D1.CN70" )
				)
				( pin "ddr5_dqs_dn(9)"
					( attribute "PN" "CT75"
						( Origin gPackager )
					)
					( objectStatus "U5D1.CT75" )
				)
				( pin "ddr5_dqs_dn(10)"
					( attribute "PN" "DF75"
						( Origin gPackager )
					)
					( objectStatus "U5D1.DF75" )
				)
				( pin "ddr5_dqs_dn(11)"
					( attribute "PN" "DJ70"
						( Origin gPackager )
					)
					( objectStatus "U5D1.DJ70" )
				)
				( pin "ddr5_dqs_dn(12)"
					( attribute "PN" "CP65"
						( Origin gPackager )
					)
					( objectStatus "U5D1.CP65" )
				)
				( pin "ddr5_dqs_dn(13)"
					( attribute "PN" "DE40"
						( Origin gPackager )
					)
					( objectStatus "U5D1.DE40" )
				)
				( pin "ddr5_dqs_dn(14)"
					( attribute "PN" "DG32"
						( Origin gPackager )
					)
					( objectStatus "U5D1.DG32" )
				)
				( pin "ddr5_dqs_dn(15)"
					( attribute "PN" "CY35"
						( Origin gPackager )
					)
					( objectStatus "U5D1.CY35" )
				)
				( pin "ddr5_dqs_dn(16)"
					( attribute "PN" "CY29"
						( Origin gPackager )
					)
					( objectStatus "U5D1.CY29" )
				)
				( pin "ddr5_dqs_dn(17)"
					( attribute "PN" "CJ70"
						( Origin gPackager )
					)
					( objectStatus "U5D1.CJ70" )
				)
				( pin "ddr5_dqs_dp(0)"
					( attribute "PN" "CR76"
						( Origin gPackager )
					)
					( objectStatus "U5D1.CR76" )
				)
				( pin "ddr5_dqs_dp(1)"
					( attribute "PN" "DE76"
						( Origin gPackager )
					)
					( objectStatus "U5D1.DE76" )
				)
				( pin "ddr5_dqs_dp(2)"
					( attribute "PN" "DK71"
						( Origin gPackager )
					)
					( objectStatus "U5D1.DK71" )
				)
				( pin "ddr5_dqs_dp(3)"
					( attribute "PN" "CT65"
						( Origin gPackager )
					)
					( objectStatus "U5D1.CT65" )
				)
				( pin "ddr5_dqs_dp(4)"
					( attribute "PN" "DJ40"
						( Origin gPackager )
					)
					( objectStatus "U5D1.DJ40" )
				)
				( pin "ddr5_dqs_dp(5)"
					( attribute "PN" "DJ32"
						( Origin gPackager )
					)
					( objectStatus "U5D1.DJ32" )
				)
				( pin "ddr5_dqs_dp(6)"
					( attribute "PN" "DB35"
						( Origin gPackager )
					)
					( objectStatus "U5D1.DB35" )
				)
				( pin "ddr5_dqs_dp(7)"
					( attribute "PN" "DB29"
						( Origin gPackager )
					)
					( objectStatus "U5D1.DB29" )
				)
				( pin "ddr5_dqs_dp(8)"
					( attribute "PN" "CL70"
						( Origin gPackager )
					)
					( objectStatus "U5D1.CL70" )
				)
				( pin "ddr5_dqs_dp(9)"
					( attribute "PN" "CU74"
						( Origin gPackager )
					)
					( objectStatus "U5D1.CU74" )
				)
				( pin "ddr5_dqs_dp(10)"
					( attribute "PN" "DG74"
						( Origin gPackager )
					)
					( objectStatus "U5D1.DG74" )
				)
				( pin "ddr5_dqs_dp(11)"
					( attribute "PN" "DH69"
						( Origin gPackager )
					)
					( objectStatus "U5D1.DH69" )
				)
				( pin "ddr5_dqs_dp(12)"
					( attribute "PN" "CM65"
						( Origin gPackager )
					)
					( objectStatus "U5D1.CM65" )
				)
				( pin "ddr5_dqs_dp(13)"
					( attribute "PN" "DC40"
						( Origin gPackager )
					)
					( objectStatus "U5D1.DC40" )
				)
				( pin "ddr5_dqs_dp(14)"
					( attribute "PN" "DE32"
						( Origin gPackager )
					)
					( objectStatus "U5D1.DE32" )
				)
				( pin "ddr5_dqs_dp(15)"
					( attribute "PN" "CV35"
						( Origin gPackager )
					)
					( objectStatus "U5D1.CV35" )
				)
				( pin "ddr5_dqs_dp(16)"
					( attribute "PN" "CV29"
						( Origin gPackager )
					)
					( objectStatus "U5D1.CV29" )
				)
				( pin "ddr5_dqs_dp(17)"
					( attribute "PN" "CG70"
						( Origin gPackager )
					)
					( objectStatus "U5D1.CG70" )
				)
				( pin "ddr5_ecc(0)"
					( attribute "PN" "CH71"
						( Origin gPackager )
					)
					( objectStatus "U5D1.CH71" )
				)
				( pin "ddr5_ecc(1)"
					( attribute "PN" "CM71"
						( Origin gPackager )
					)
					( objectStatus "U5D1.CM71" )
				)
				( pin "ddr5_ecc(2)"
					( attribute "PN" "CJ68"
						( Origin gPackager )
					)
					( objectStatus "U5D1.CJ68" )
				)
				( pin "ddr5_ecc(3)"
					( attribute "PN" "CL68"
						( Origin gPackager )
					)
					( objectStatus "U5D1.CL68" )
				)
				( pin "ddr5_ecc(4)"
					( attribute "PN" "CJ72"
						( Origin gPackager )
					)
					( objectStatus "U5D1.CJ72" )
				)
				( pin "ddr5_ecc(5)"
					( attribute "PN" "CL72"
						( Origin gPackager )
					)
					( objectStatus "U5D1.CL72" )
				)
				( pin "ddr5_ecc(6)"
					( attribute "PN" "CH69"
						( Origin gPackager )
					)
					( objectStatus "U5D1.CH69" )
				)
				( pin "ddr5_ecc(7)"
					( attribute "PN" "CM69"
						( Origin gPackager )
					)
					( objectStatus "U5D1.CM69" )
				)
				( pin "ddr5_ma(0)"
					( attribute "PN" "DF53"
						( Origin gPackager )
					)
					( objectStatus "U5D1.DF53" )
				)
				( pin "ddr5_ma(1)"
					( attribute "PN" "DC58"
						( Origin gPackager )
					)
					( objectStatus "U5D1.DC58" )
				)
				( pin "ddr5_ma(2)"
					( attribute "PN" "DD57"
						( Origin gPackager )
					)
					( objectStatus "U5D1.DD57" )
				)
				( pin "ddr5_ma(3)"
					( attribute "PN" "DG58"
						( Origin gPackager )
					)
					( objectStatus "U5D1.DG58" )
				)
				( pin "ddr5_ma(4)"
					( attribute "PN" "DJ58"
						( Origin gPackager )
					)
					( objectStatus "U5D1.DJ58" )
				)
				( pin "ddr5_ma(5)"
					( attribute "PN" "DF59"
						( Origin gPackager )
					)
					( objectStatus "U5D1.DF59" )
				)
				( pin "ddr5_ma(6)"
					( attribute "PN" "DK59"
						( Origin gPackager )
					)
					( objectStatus "U5D1.DK59" )
				)
				( pin "ddr5_ma(7)"
					( attribute "PN" "DC60"
						( Origin gPackager )
					)
					( objectStatus "U5D1.DC60" )
				)
				( pin "ddr5_ma(8)"
					( attribute "PN" "DD59"
						( Origin gPackager )
					)
					( objectStatus "U5D1.DD59" )
				)
				( pin "ddr5_ma(9)"
					( attribute "PN" "DA58"
						( Origin gPackager )
					)
					( objectStatus "U5D1.DA58" )
				)
				( pin "ddr5_ma(10)"
					( attribute "PN" "DD55"
						( Origin gPackager )
					)
					( objectStatus "U5D1.DD55" )
				)
				( pin "ddr5_ma(11)"
					( attribute "PN" "DA60"
						( Origin gPackager )
					)
					( objectStatus "U5D1.DA60" )
				)
				( pin "ddr5_ma(12)"
					( attribute "PN" "DG60"
						( Origin gPackager )
					)
					( objectStatus "U5D1.DG60" )
				)
				( pin "ddr5_ma(13)"
					( attribute "PN" "DD53"
						( Origin gPackager )
					)
					( objectStatus "U5D1.DD53" )
				)
				( pin "ddr5_ma(14)"
					( attribute "PN" "DJ50"
						( Origin gPackager )
					)
					( objectStatus "U5D1.DJ50" )
				)
				( pin "ddr5_ma(15)"
					( attribute "PN" "DC54"
						( Origin gPackager )
					)
					( objectStatus "U5D1.DC54" )
				)
				( pin "ddr5_ma(16)"
					( attribute "PN" "DG52"
						( Origin gPackager )
					)
					( objectStatus "U5D1.DG52" )
				)
				( pin "ddr5_ma(17)"
					( attribute "PN" "DE46"
						( Origin gPackager )
					)
					( objectStatus "U5D1.DE46" )
				)
				( pin "ddr5_odt(0)"
					( attribute "PN" "DG50"
						( Origin gPackager )
					)
					( objectStatus "U5D1.DG50" )
				)
				( pin "ddr5_odt(1)"
					( attribute "PN" "DG48"
						( Origin gPackager )
					)
					( objectStatus "U5D1.DG48" )
				)
				( pin "ddr5_odt(2)"
					( attribute "PN" "DK49"
						( Origin gPackager )
					)
					( objectStatus "U5D1.DK49" )
				)
				( pin "ddr5_odt(3)"
					( attribute "PN" "DF47"
						( Origin gPackager )
					)
					( objectStatus "U5D1.DF47" )
				)
				( pin "ddr5_par"
					( attribute "PN" "DK53"
						( Origin gPackager )
					)
					( objectStatus "U5D1.DK53" )
				)
			)
			( gate "@baseboard_fab2_lib.baseboard_fab2(sch_1):page29_i61"
				( attribute "CDS_LIB" "chpset_lib"
					( Origin gPackager )
				)
				( attribute "CDS_LOCATION" "U5D1"
					( Origin gPackager )
				)
				( attribute "CDS_SEC" "9"
					( Origin gPackager )
				)
				( attribute "LOCATION" "U5D1"
					( Origin gFrontEnd )
				)
				( attribute "MATERIAL" "IC"
					( Origin gFrontEnd )
				)
				( attribute "PACK_TYPE" "BGA1"
					( Origin gFrontEnd )
				)
				( attribute "PART_NUMBER" "TBD"
					( Origin gFrontEnd )
				)
				( attribute "PHYS_PAGE" "29"
					( Origin gFrontEnd )
				)
				( attribute "ROOM" "CPU0"
					( Origin gFrontEnd )
				)
				( attribute "ROT" "0"
					( Origin gFrontEnd )
				)
				( attribute "SEC" "9"
					( Origin gFrontEnd )
				)
				( attribute "SEC_TYPE" "BGA1"
					( Origin gFrontEnd )
				)
				( attribute "VER" "9"
					( Origin gFrontEnd )
				)
				( attribute "XY" "(-3925,2550)"
					( Origin gFrontEnd )
				)
				( attribute "CHIPS_PART_NAME" "SKX_EXT_B"
					( Origin gPackager )
				)
				( attribute "CDS_PART_NAME" "SKX_EXT_B_BGA1-IC,TBD"
					( Origin gPackager )
				)
				( objectStatus "U5D1" )
				( pin "cd_hfi0_i2cclk"
					( attribute "PN" "BN22"
						( Origin gPackager )
					)
					( objectStatus "U5D1.BN22" )
				)
				( pin "cd_hfi0_i2cdat"
					( attribute "PN" "BP23"
						( Origin gPackager )
					)
					( objectStatus "U5D1.BP23" )
				)
				( pin "cd_hfi0_int_n"
					( attribute "PN" "BP19"
						( Origin gPackager )
					)
					( objectStatus "U5D1.BP19" )
				)
				( pin "cd_hfi0_led_n"
					( attribute "PN" "BK21"
						( Origin gPackager )
					)
					( objectStatus "U5D1.BK21" )
				)
				( pin "cd_hfi0_modprst_n"
					( attribute "PN" "BR20"
						( Origin gPackager )
					)
					( objectStatus "U5D1.BR20" )
				)
				( pin "cd_hfi0_reset_n"
					( attribute "PN" "BN24"
						( Origin gPackager )
					)
					( objectStatus "U5D1.BN24" )
				)
				( pin "cd_hfi1_i2cclk"
					( attribute "PN" "BJ22"
						( Origin gPackager )
					)
					( objectStatus "U5D1.BJ22" )
				)
				( pin "cd_hfi1_i2cdat"
					( attribute "PN" "BH23"
						( Origin gPackager )
					)
					( objectStatus "U5D1.BH23" )
				)
				( pin "cd_hfi1_int_n"
					( attribute "PN" "BM21"
						( Origin gPackager )
					)
					( objectStatus "U5D1.BM21" )
				)
				( pin "cd_hfi1_led_n"
					( attribute "PN" "BM23"
						( Origin gPackager )
					)
					( objectStatus "U5D1.BM23" )
				)
				( pin "cd_hfi1_modprst_n"
					( attribute "PN" "BT19"
						( Origin gPackager )
					)
					( objectStatus "U5D1.BT19" )
				)
				( pin "cd_hfi1_reset_n"
					( attribute "PN" "BK23"
						( Origin gPackager )
					)
					( objectStatus "U5D1.BK23" )
				)
				( pin "cd_hfi_refclk_dn"
					( attribute "PN" "BE16"
						( Origin gPackager )
					)
					( objectStatus "U5D1.BE16" )
				)
				( pin "cd_hfi_refclk_dp"
					( attribute "PN" "BG16"
						( Origin gPackager )
					)
					( objectStatus "U5D1.BG16" )
				)
				( pin "cd_pe_refclk_dn"
					( attribute "PN" "BU24"
						( Origin gPackager )
					)
					( objectStatus "U5D1.BU24" )
				)
				( pin "cd_pe_refclk_dp"
					( attribute "PN" "BW24"
						( Origin gPackager )
					)
					( objectStatus "U5D1.BW24" )
				)
				( pin "cd_por_n"
					( attribute "PN" "CF25"
						( Origin gPackager )
					)
					( objectStatus "U5D1.CF25" )
				)
				( pin "cd_tclk"
					( attribute "PN" "CB23"
						( Origin gPackager )
					)
					( objectStatus "U5D1.CB23" )
				)
				( pin "cd_tdi"
					( attribute "PN" "BY21"
						( Origin gPackager )
					)
					( objectStatus "U5D1.BY21" )
				)
				( pin "cd_tdo"
					( attribute "PN" "CC22"
						( Origin gPackager )
					)
					( objectStatus "U5D1.CC22" )
				)
				( pin "cd_tms"
					( attribute "PN" "CE24"
						( Origin gPackager )
					)
					( objectStatus "U5D1.CE24" )
				)
				( pin "cd_trst_n"
					( attribute "PN" "CD23"
						( Origin gPackager )
					)
					( objectStatus "U5D1.CD23" )
				)
				( pin "dmi_rx_dn(0)"
					( attribute "PN" "CK9"
						( Origin gPackager )
					)
					( objectStatus "U5D1.CK9" )
				)
				( pin "dmi_rx_dn(1)"
					( attribute "PN" "CM11"
						( Origin gPackager )
					)
					( objectStatus "U5D1.CM11" )
				)
				( pin "dmi_rx_dn(2)"
					( attribute "PN" "CR12"
						( Origin gPackager )
					)
					( objectStatus "U5D1.CR12" )
				)
				( pin "dmi_rx_dn(3)"
					( attribute "PN" "CT11"
						( Origin gPackager )
					)
					( objectStatus "U5D1.CT11" )
				)
				( pin "dmi_rx_dp(0)"
					( attribute "PN" "CL10"
						( Origin gPackager )
					)
					( objectStatus "U5D1.CL10" )
				)
				( pin "dmi_rx_dp(1)"
					( attribute "PN" "CN10"
						( Origin gPackager )
					)
					( objectStatus "U5D1.CN10" )
				)
				( pin "dmi_rx_dp(2)"
					( attribute "PN" "CP11"
						( Origin gPackager )
					)
					( objectStatus "U5D1.CP11" )
				)
				( pin "dmi_rx_dp(3)"
					( attribute "PN" "CV11"
						( Origin gPackager )
					)
					( objectStatus "U5D1.CV11" )
				)
				( pin "dmi_tx_dn(0)"
					( attribute "PN" "CG4"
						( Origin gPackager )
					)
					( objectStatus "U5D1.CG4" )
				)
				( pin "dmi_tx_dn(1)"
					( attribute "PN" "CJ4"
						( Origin gPackager )
					)
					( objectStatus "U5D1.CJ4" )
				)
				( pin "dmi_tx_dn(2)"
					( attribute "PN" "CN4"
						( Origin gPackager )
					)
					( objectStatus "U5D1.CN4" )
				)
				( pin "dmi_tx_dn(3)"
					( attribute "PN" "CP5"
						( Origin gPackager )
					)
					( objectStatus "U5D1.CP5" )
				)
				( pin "dmi_tx_dp(0)"
					( attribute "PN" "CH5"
						( Origin gPackager )
					)
					( objectStatus "U5D1.CH5" )
				)
				( pin "dmi_tx_dp(1)"
					( attribute "PN" "CL4"
						( Origin gPackager )
					)
					( objectStatus "U5D1.CL4" )
				)
				( pin "dmi_tx_dp(2)"
					( attribute "PN" "CM3"
						( Origin gPackager )
					)
					( objectStatus "U5D1.CM3" )
				)
				( pin "dmi_tx_dp(3)"
					( attribute "PN" "CR4"
						( Origin gPackager )
					)
					( objectStatus "U5D1.CR4" )
				)
				( pin "rsvd(172)"
					( attribute "PN" "BA76"
						( Origin gPackager )
					)
					( objectStatus "U5D1.BA76" )
				)
				( pin "rsvd(173)"
					( attribute "PN" "BA66"
						( Origin gPackager )
					)
					( objectStatus "U5D1.BA66" )
				)
				( pin "rsvd(174)"
					( attribute "PN" "BA64"
						( Origin gPackager )
					)
					( objectStatus "U5D1.BA64" )
				)
				( pin "rsvd(175)"
					( attribute "PN" "BA22"
						( Origin gPackager )
					)
					( objectStatus "U5D1.BA22" )
				)
				( pin "rsvd(176)"
					( attribute "PN" "BA18"
						( Origin gPackager )
					)
					( objectStatus "U5D1.BA18" )
				)
				( pin "rsvd(177)"
					( attribute "PN" "BA16"
						( Origin gPackager )
					)
					( objectStatus "U5D1.BA16" )
				)
				( pin "rsvd(178)"
					( attribute "PN" "BA14"
						( Origin gPackager )
					)
					( objectStatus "U5D1.BA14" )
				)
				( pin "rsvd(179)"
					( attribute "PN" "AY77"
						( Origin gPackager )
					)
					( objectStatus "U5D1.AY77" )
				)
				( pin "rsvd(180)"
					( attribute "PN" "AY75"
						( Origin gPackager )
					)
					( objectStatus "U5D1.AY75" )
				)
				( pin "rsvd(181)"
					( attribute "PN" "AY67"
						( Origin gPackager )
					)
					( objectStatus "U5D1.AY67" )
				)
				( pin "rsvd(182)"
					( attribute "PN" "AY65"
						( Origin gPackager )
					)
					( objectStatus "U5D1.AY65" )
				)
				( pin "rsvd(183)"
					( attribute "PN" "AW76"
						( Origin gPackager )
					)
					( objectStatus "U5D1.AW76" )
				)
				( pin "rsvd(184)"
					( attribute "PN" "AW64"
						( Origin gPackager )
					)
					( objectStatus "U5D1.AW64" )
				)
				( pin "rsvd(185)"
					( attribute "CDS_NOT_ON_SYM" "TRUE"
						( Origin gFrontEnd )
					)
				)
				( pin "rsvd(186)"
					( attribute "PN" "AV77"
						( Origin gPackager )
					)
					( objectStatus "U5D1.AV77" )
				)
				( pin "rsvd(187)"
					( attribute "PN" "AT25"
						( Origin gPackager )
					)
					( objectStatus "U5D1.AT25" )
				)
				( pin "rsvd(188)"
					( attribute "PN" "AT23"
						( Origin gPackager )
					)
					( objectStatus "U5D1.AT23" )
				)
				( pin "rsvd(189)"
					( attribute "PN" "AT13"
						( Origin gPackager )
					)
					( objectStatus "U5D1.AT13" )
				)
				( pin "rsvd(190)"
					( attribute "PN" "AR62"
						( Origin gPackager )
					)
					( objectStatus "U5D1.AR62" )
				)
				( pin "rsvd(191)"
					( attribute "PN" "AR26"
						( Origin gPackager )
					)
					( objectStatus "U5D1.AR26" )
				)
				( pin "rsvd(192)"
					( attribute "PN" "AR22"
						( Origin gPackager )
					)
					( objectStatus "U5D1.AR22" )
				)
				( pin "rsvd(193)"
					( attribute "PN" "AR20"
						( Origin gPackager )
					)
					( objectStatus "U5D1.AR20" )
				)
			)
			( gate "@baseboard_fab2_lib.baseboard_fab2(sch_1):page30_i84"
				( attribute "CDS_LIB" "chpset_lib"
					( Origin gPackager )
				)
				( attribute "CDS_LOCATION" "U5D1"
					( Origin gPackager )
				)
				( attribute "CDS_SEC" "10"
					( Origin gPackager )
				)
				( attribute "LOCATION" "U5D1"
					( Origin gFrontEnd )
				)
				( attribute "MATERIAL" "IC"
					( Origin gFrontEnd )
				)
				( attribute "PACK_TYPE" "BGA1"
					( Origin gFrontEnd )
				)
				( attribute "PART_NUMBER" "TBD"
					( Origin gFrontEnd )
				)
				( attribute "PHYS_PAGE" "30"
					( Origin gFrontEnd )
				)
				( attribute "ROOM" "CPU0"
					( Origin gFrontEnd )
				)
				( attribute "ROT" "0"
					( Origin gFrontEnd )
				)
				( attribute "SEC" "10"
					( Origin gFrontEnd )
				)
				( attribute "SEC_TYPE" "BGA1"
					( Origin gFrontEnd )
				)
				( attribute "VER" "10"
					( Origin gFrontEnd )
				)
				( attribute "XY" "(-4100,2550)"
					( Origin gFrontEnd )
				)
				( attribute "CHIPS_PART_NAME" "SKX_EXT_B"
					( Origin gPackager )
				)
				( attribute "CDS_PART_NAME" "SKX_EXT_B_BGA1-IC,TBD"
					( Origin gPackager )
				)
				( objectStatus "U5D1" )
				( pin "pe1_rx_dn(0)"
					( attribute "PN" "CW8"
						( Origin gPackager )
					)
					( objectStatus "U5D1.CW8" )
				)
				( pin "pe1_rx_dn(1)"
					( attribute "PN" "DA8"
						( Origin gPackager )
					)
					( objectStatus "U5D1.DA8" )
				)
				( pin "pe1_rx_dn(2)"
					( attribute "PN" "DC8"
						( Origin gPackager )
					)
					( objectStatus "U5D1.DC8" )
				)
				( pin "pe1_rx_dn(3)"
					( attribute "PN" "DC10"
						( Origin gPackager )
					)
					( objectStatus "U5D1.DC10" )
				)
				( pin "pe1_rx_dn(4)"
					( attribute "PN" "DE10"
						( Origin gPackager )
					)
					( objectStatus "U5D1.DE10" )
				)
				( pin "pe1_rx_dn(5)"
					( attribute "PN" "DH9"
						( Origin gPackager )
					)
					( objectStatus "U5D1.DH9" )
				)
				( pin "pe1_rx_dn(6)"
					( attribute "PN" "DK9"
						( Origin gPackager )
					)
					( objectStatus "U5D1.DK9" )
				)
				( pin "pe1_rx_dn(7)"
					( attribute "PN" "DM9"
						( Origin gPackager )
					)
					( objectStatus "U5D1.DM9" )
				)
				( pin "pe1_rx_dn(8)"
					( attribute "PN" "DM11"
						( Origin gPackager )
					)
					( objectStatus "U5D1.DM11" )
				)
				( pin "pe1_rx_dn(9)"
					( attribute "PN" "DP11"
						( Origin gPackager )
					)
					( objectStatus "U5D1.DP11" )
				)
				( pin "pe1_rx_dn(10)"
					( attribute "PN" "DT11"
						( Origin gPackager )
					)
					( objectStatus "U5D1.DT11" )
				)
				( pin "pe1_rx_dn(11)"
					( attribute "PN" "DT13"
						( Origin gPackager )
					)
					( objectStatus "U5D1.DT13" )
				)
				( pin "pe1_rx_dn(12)"
					( attribute "PN" "DV13"
						( Origin gPackager )
					)
					( objectStatus "U5D1.DV13" )
				)
				( pin "pe1_rx_dn(13)"
					( attribute "PN" "DW14"
						( Origin gPackager )
					)
					( objectStatus "U5D1.DW14" )
				)
				( pin "pe1_rx_dn(14)"
					( attribute "PN" "DY15"
						( Origin gPackager )
					)
					( objectStatus "U5D1.DY15" )
				)
				( pin "pe1_rx_dn(15)"
					( attribute "PN" "DU16"
						( Origin gPackager )
					)
					( objectStatus "U5D1.DU16" )
				)
				( pin "pe1_rx_dp(0)"
					( attribute "PN" "CU8"
						( Origin gPackager )
					)
					( objectStatus "U5D1.CU8" )
				)
				( pin "pe1_rx_dp(1)"
					( attribute "PN" "CY7"
						( Origin gPackager )
					)
					( objectStatus "U5D1.CY7" )
				)
				( pin "pe1_rx_dp(2)"
					( attribute "PN" "DB9"
						( Origin gPackager )
					)
					( objectStatus "U5D1.DB9" )
				)
				( pin "pe1_rx_dp(3)"
					( attribute "PN" "DA10"
						( Origin gPackager )
					)
					( objectStatus "U5D1.DA10" )
				)
				( pin "pe1_rx_dp(4)"
					( attribute "PN" "DD9"
						( Origin gPackager )
					)
					( objectStatus "U5D1.DD9" )
				)
				( pin "pe1_rx_dp(5)"
					( attribute "PN" "DF9"
						( Origin gPackager )
					)
					( objectStatus "U5D1.DF9" )
				)
				( pin "pe1_rx_dp(6)"
					( attribute "PN" "DJ8"
						( Origin gPackager )
					)
					( objectStatus "U5D1.DJ8" )
				)
				( pin "pe1_rx_dp(7)"
					( attribute "PN" "DL10"
						( Origin gPackager )
					)
					( objectStatus "U5D1.DL10" )
				)
				( pin "pe1_rx_dp(8)"
					( attribute "PN" "DK11"
						( Origin gPackager )
					)
					( objectStatus "U5D1.DK11" )
				)
				( pin "pe1_rx_dp(9)"
					( attribute "PN" "DN10"
						( Origin gPackager )
					)
					( objectStatus "U5D1.DN10" )
				)
				( pin "pe1_rx_dp(10)"
					( attribute "PN" "DR12"
						( Origin gPackager )
					)
					( objectStatus "U5D1.DR12" )
				)
				( pin "pe1_rx_dp(11)"
					( attribute "PN" "DP13"
						( Origin gPackager )
					)
					( objectStatus "U5D1.DP13" )
				)
				( pin "pe1_rx_dp(12)"
					( attribute "PN" "DU12"
						( Origin gPackager )
					)
					( objectStatus "U5D1.DU12" )
				)
				( pin "pe1_rx_dp(13)"
					( attribute "PN" "DY13"
						( Origin gPackager )
					)
					( objectStatus "U5D1.DY13" )
				)
				( pin "pe1_rx_dp(14)"
					( attribute "PN" "DV15"
						( Origin gPackager )
					)
					( objectStatus "U5D1.DV15" )
				)
				( pin "pe1_rx_dp(15)"
					( attribute "PN" "DT15"
						( Origin gPackager )
					)
					( objectStatus "U5D1.DT15" )
				)
				( pin "pe1_tx_dn(0)"
					( attribute "PN" "DA2"
						( Origin gPackager )
					)
					( objectStatus "U5D1.DA2" )
				)
				( pin "pe1_tx_dn(1)"
					( attribute "PN" "DC2"
						( Origin gPackager )
					)
					( objectStatus "U5D1.DC2" )
				)
				( pin "pe1_tx_dn(2)"
					( attribute "PN" "DE2"
						( Origin gPackager )
					)
					( objectStatus "U5D1.DE2" )
				)
				( pin "pe1_tx_dn(3)"
					( attribute "PN" "DE4"
						( Origin gPackager )
					)
					( objectStatus "U5D1.DE4" )
				)
				( pin "pe1_tx_dn(4)"
					( attribute "PN" "DG4"
						( Origin gPackager )
					)
					( objectStatus "U5D1.DG4" )
				)
				( pin "pe1_tx_dn(5)"
					( attribute "PN" "DK3"
						( Origin gPackager )
					)
					( objectStatus "U5D1.DK3" )
				)
				( pin "pe1_tx_dn(6)"
					( attribute "PN" "DM3"
						( Origin gPackager )
					)
					( objectStatus "U5D1.DM3" )
				)
				( pin "pe1_tx_dn(7)"
					( attribute "PN" "DN4"
						( Origin gPackager )
					)
					( objectStatus "U5D1.DN4" )
				)
				( pin "pe1_tx_dn(8)"
					( attribute "PN" "DT5"
						( Origin gPackager )
					)
					( objectStatus "U5D1.DT5" )
				)
				( pin "pe1_tx_dn(9)"
					( attribute "PN" "DV3"
						( Origin gPackager )
					)
					( objectStatus "U5D1.DV3" )
				)
				( pin "pe1_tx_dn(10)"
					( attribute "PN" "DW4"
						( Origin gPackager )
					)
					( objectStatus "U5D1.DW4" )
				)
				( pin "pe1_tx_dn(11)"
					( attribute "PN" "DU6"
						( Origin gPackager )
					)
					( objectStatus "U5D1.DU6" )
				)
				( pin "pe1_tx_dn(12)"
					( attribute "PN" "DV7"
						( Origin gPackager )
					)
					( objectStatus "U5D1.DV7" )
				)
				( pin "pe1_tx_dn(13)"
					( attribute "PN" "DY7"
						( Origin gPackager )
					)
					( objectStatus "U5D1.DY7" )
				)
				( pin "pe1_tx_dn(14)"
					( attribute "PN" "EA8"
						( Origin gPackager )
					)
					( objectStatus "U5D1.EA8" )
				)
				( pin "pe1_tx_dn(15)"
					( attribute "PN" "ED9"
						( Origin gPackager )
					)
					( objectStatus "U5D1.ED9" )
				)
				( pin "pe1_tx_dp(0)"
					( attribute "PN" "CW2"
						( Origin gPackager )
					)
					( objectStatus "U5D1.CW2" )
				)
				( pin "pe1_tx_dp(1)"
					( attribute "PN" "DB1"
						( Origin gPackager )
					)
					( objectStatus "U5D1.DB1" )
				)
				( pin "pe1_tx_dp(2)"
					( attribute "PN" "DD3"
						( Origin gPackager )
					)
					( objectStatus "U5D1.DD3" )
				)
				( pin "pe1_tx_dp(3)"
					( attribute "PN" "DC4"
						( Origin gPackager )
					)
					( objectStatus "U5D1.DC4" )
				)
				( pin "pe1_tx_dp(4)"
					( attribute "PN" "DF3"
						( Origin gPackager )
					)
					( objectStatus "U5D1.DF3" )
				)
				( pin "pe1_tx_dp(5)"
					( attribute "PN" "DH3"
						( Origin gPackager )
					)
					( objectStatus "U5D1.DH3" )
				)
				( pin "pe1_tx_dp(6)"
					( attribute "PN" "DL2"
						( Origin gPackager )
					)
					( objectStatus "U5D1.DL2" )
				)
				( pin "pe1_tx_dp(7)"
					( attribute "PN" "DP3"
						( Origin gPackager )
					)
					( objectStatus "U5D1.DP3" )
				)
				( pin "pe1_tx_dp(8)"
					( attribute "PN" "DR4"
						( Origin gPackager )
					)
					( objectStatus "U5D1.DR4" )
				)
				( pin "pe1_tx_dp(9)"
					( attribute "PN" "DU2"
						( Origin gPackager )
					)
					( objectStatus "U5D1.DU2" )
				)
				( pin "pe1_tx_dp(10)"
					( attribute "PN" "DU4"
						( Origin gPackager )
					)
					( objectStatus "U5D1.DU4" )
				)
				( pin "pe1_tx_dp(11)"
					( attribute "PN" "DV5"
						( Origin gPackager )
					)
					( objectStatus "U5D1.DV5" )
				)
				( pin "pe1_tx_dp(12)"
					( attribute "PN" "DT7"
						( Origin gPackager )
					)
					( objectStatus "U5D1.DT7" )
				)
				( pin "pe1_tx_dp(13)"
					( attribute "PN" "DW6"
						( Origin gPackager )
					)
					( objectStatus "U5D1.DW6" )
				)
				( pin "pe1_tx_dp(14)"
					( attribute "PN" "EB7"
						( Origin gPackager )
					)
					( objectStatus "U5D1.EB7" )
				)
				( pin "pe1_tx_dp(15)"
					( attribute "PN" "EC8"
						( Origin gPackager )
					)
					( objectStatus "U5D1.EC8" )
				)
			)
			( gate "@baseboard_fab2_lib.baseboard_fab2(sch_1):page31_i106"
				( attribute "CDS_LIB" "chpset_lib"
					( Origin gPackager )
				)
				( attribute "CDS_LOCATION" "U5D1"
					( Origin gPackager )
				)
				( attribute "CDS_SEC" "11"
					( Origin gPackager )
				)
				( attribute "LOCATION" "U5D1"
					( Origin gFrontEnd )
				)
				( attribute "MATERIAL" "IC"
					( Origin gFrontEnd )
				)
				( attribute "PACK_TYPE" "BGA1"
					( Origin gFrontEnd )
				)
				( attribute "PART_NUMBER" "TBD"
					( Origin gFrontEnd )
				)
				( attribute "PHYS_PAGE" "31"
					( Origin gFrontEnd )
				)
				( attribute "ROOM" "CPU0"
					( Origin gFrontEnd )
				)
				( attribute "ROT" "0"
					( Origin gFrontEnd )
				)
				( attribute "SEC" "11"
					( Origin gFrontEnd )
				)
				( attribute "SEC_TYPE" "BGA1"
					( Origin gFrontEnd )
				)
				( attribute "VER" "11"
					( Origin gFrontEnd )
				)
				( attribute "XY" "(-4025,2600)"
					( Origin gFrontEnd )
				)
				( attribute "CHIPS_PART_NAME" "SKX_EXT_B"
					( Origin gPackager )
				)
				( attribute "CDS_PART_NAME" "SKX_EXT_B_BGA1-IC,TBD"
					( Origin gPackager )
				)
				( objectStatus "U5D1" )
				( pin "pe2_rx_dn(0)"
					( attribute "PN" "CT9"
						( Origin gPackager )
					)
					( objectStatus "U5D1.CT9" )
				)
				( pin "pe2_rx_dn(1)"
					( attribute "PN" "CP9"
						( Origin gPackager )
					)
					( objectStatus "U5D1.CP9" )
				)
				( pin "pe2_rx_dn(2)"
					( attribute "PN" "CP7"
						( Origin gPackager )
					)
					( objectStatus "U5D1.CP7" )
				)
				( pin "pe2_rx_dn(3)"
					( attribute "PN" "CM7"
						( Origin gPackager )
					)
					( objectStatus "U5D1.CM7" )
				)
				( pin "pe2_rx_dn(4)"
					( attribute "PN" "CK7"
						( Origin gPackager )
					)
					( objectStatus "U5D1.CK7" )
				)
				( pin "pe2_rx_dn(5)"
					( attribute "PN" "CG8"
						( Origin gPackager )
					)
					( objectStatus "U5D1.CG8" )
				)
				( pin "pe2_rx_dn(6)"
					( attribute "PN" "CE6"
						( Origin gPackager )
					)
					( objectStatus "U5D1.CE6" )
				)
				( pin "pe2_rx_dn(7)"
					( attribute "PN" "CE8"
						( Origin gPackager )
					)
					( objectStatus "U5D1.CE8" )
				)
				( pin "pe2_rx_dn(8)"
					( attribute "PN" "BY9"
						( Origin gPackager )
					)
					( objectStatus "U5D1.BY9" )
				)
				( pin "pe2_rx_dn(9)"
					( attribute "PN" "BY7"
						( Origin gPackager )
					)
					( objectStatus "U5D1.BY7" )
				)
				( pin "pe2_rx_dn(10)"
					( attribute "PN" "BV7"
						( Origin gPackager )
					)
					( objectStatus "U5D1.BV7" )
				)
				( pin "pe2_rx_dn(11)"
					( attribute "PN" "BT7"
						( Origin gPackager )
					)
					( objectStatus "U5D1.BT7" )
				)
				( pin "pe2_rx_dn(12)"
					( attribute "PN" "BR8"
						( Origin gPackager )
					)
					( objectStatus "U5D1.BR8" )
				)
				( pin "pe2_rx_dn(13)"
					( attribute "PN" "BN8"
						( Origin gPackager )
					)
					( objectStatus "U5D1.BN8" )
				)
				( pin "pe2_rx_dn(14)"
					( attribute "PN" "BL8"
						( Origin gPackager )
					)
					( objectStatus "U5D1.BL8" )
				)
				( pin "pe2_rx_dn(15)"
					( attribute "PN" "BK9"
						( Origin gPackager )
					)
					( objectStatus "U5D1.BK9" )
				)
				( pin "pe2_rx_dp(0)"
					( attribute "PN" "CR8"
						( Origin gPackager )
					)
					( objectStatus "U5D1.CR8" )
				)
				( pin "pe2_rx_dp(1)"
					( attribute "PN" "CM9"
						( Origin gPackager )
					)
					( objectStatus "U5D1.CM9" )
				)
				( pin "pe2_rx_dp(2)"
					( attribute "PN" "CN8"
						( Origin gPackager )
					)
					( objectStatus "U5D1.CN8" )
				)
				( pin "pe2_rx_dp(3)"
					( attribute "PN" "CL6"
						( Origin gPackager )
					)
					( objectStatus "U5D1.CL6" )
				)
				( pin "pe2_rx_dp(4)"
					( attribute "PN" "CH7"
						( Origin gPackager )
					)
					( objectStatus "U5D1.CH7" )
				)
				( pin "pe2_rx_dp(5)"
					( attribute "PN" "CF7"
						( Origin gPackager )
					)
					( objectStatus "U5D1.CF7" )
				)
				( pin "pe2_rx_dp(6)"
					( attribute "PN" "CD7"
						( Origin gPackager )
					)
					( objectStatus "U5D1.CD7" )
				)
				( pin "pe2_rx_dp(7)"
					( attribute "PN" "CC8"
						( Origin gPackager )
					)
					( objectStatus "U5D1.CC8" )
				)
				( pin "pe2_rx_dp(8)"
					( attribute "PN" "BV9"
						( Origin gPackager )
					)
					( objectStatus "U5D1.BV9" )
				)
				( pin "pe2_rx_dp(9)"
					( attribute "PN" "BW8"
						( Origin gPackager )
					)
					( objectStatus "U5D1.BW8" )
				)
				( pin "pe2_rx_dp(10)"
					( attribute "PN" "BU6"
						( Origin gPackager )
					)
					( objectStatus "U5D1.BU6" )
				)
				( pin "pe2_rx_dp(11)"
					( attribute "PN" "BP7"
						( Origin gPackager )
					)
					( objectStatus "U5D1.BP7" )
				)
				( pin "pe2_rx_dp(12)"
					( attribute "PN" "BP9"
						( Origin gPackager )
					)
					( objectStatus "U5D1.BP9" )
				)
				( pin "pe2_rx_dp(13)"
					( attribute "PN" "BM7"
						( Origin gPackager )
					)
					( objectStatus "U5D1.BM7" )
				)
				( pin "pe2_rx_dp(14)"
					( attribute "PN" "BJ8"
						( Origin gPackager )
					)
					( objectStatus "U5D1.BJ8" )
				)
				( pin "pe2_rx_dp(15)"
					( attribute "PN" "BJ10"
						( Origin gPackager )
					)
					( objectStatus "U5D1.BJ10" )
				)
				( pin "pe2_tx_dn(0)"
					( attribute "PN" "CY3"
						( Origin gPackager )
					)
					( objectStatus "U5D1.CY3" )
				)
				( pin "pe2_tx_dn(1)"
					( attribute "PN" "CV3"
						( Origin gPackager )
					)
					( objectStatus "U5D1.CV3" )
				)
				( pin "pe2_tx_dn(2)"
					( attribute "PN" "CT1"
						( Origin gPackager )
					)
					( objectStatus "U5D1.CT1" )
				)
				( pin "pe2_tx_dn(3)"
					( attribute "PN" "CT3"
						( Origin gPackager )
					)
					( objectStatus "U5D1.CT3" )
				)
				( pin "pe2_tx_dn(4)"
					( attribute "PN" "CM1"
						( Origin gPackager )
					)
					( objectStatus "U5D1.CM1" )
				)
				( pin "pe2_tx_dn(5)"
					( attribute "PN" "CL2"
						( Origin gPackager )
					)
					( objectStatus "U5D1.CL2" )
				)
				( pin "pe2_tx_dn(6)"
					( attribute "PN" "CG2"
						( Origin gPackager )
					)
					( objectStatus "U5D1.CG2" )
				)
				( pin "pe2_tx_dn(7)"
					( attribute "PN" "CF3"
						( Origin gPackager )
					)
					( objectStatus "U5D1.CF3" )
				)
				( pin "pe2_tx_dn(8)"
					( attribute "PN" "CC2"
						( Origin gPackager )
					)
					( objectStatus "U5D1.CC2" )
				)
				( pin "pe2_tx_dn(9)"
					( attribute "PN" "CB3"
						( Origin gPackager )
					)
					( objectStatus "U5D1.CB3" )
				)
				( pin "pe2_tx_dn(10)"
					( attribute "PN" "CA4"
						( Origin gPackager )
					)
					( objectStatus "U5D1.CA4" )
				)
				( pin "pe2_tx_dn(11)"
					( attribute "PN" "BW4"
						( Origin gPackager )
					)
					( objectStatus "U5D1.BW4" )
				)
				( pin "pe2_tx_dn(12)"
					( attribute "PN" "BU4"
						( Origin gPackager )
					)
					( objectStatus "U5D1.BU4" )
				)
				( pin "pe2_tx_dn(13)"
					( attribute "PN" "BP5"
						( Origin gPackager )
					)
					( objectStatus "U5D1.BP5" )
				)
				( pin "pe2_tx_dn(14)"
					( attribute "PN" "BL4"
						( Origin gPackager )
					)
					( objectStatus "U5D1.BL4" )
				)
				( pin "pe2_tx_dn(15)"
					( attribute "PN" "BM5"
						( Origin gPackager )
					)
					( objectStatus "U5D1.BM5" )
				)
				( pin "pe2_tx_dp(0)"
					( attribute "PN" "CW4"
						( Origin gPackager )
					)
					( objectStatus "U5D1.CW4" )
				)
				( pin "pe2_tx_dp(1)"
					( attribute "PN" "CU2"
						( Origin gPackager )
					)
					( objectStatus "U5D1.CU2" )
				)
				( pin "pe2_tx_dp(2)"
					( attribute "PN" "CR2"
						( Origin gPackager )
					)
					( objectStatus "U5D1.CR2" )
				)
				( pin "pe2_tx_dp(3)"
					( attribute "PN" "CP3"
						( Origin gPackager )
					)
					( objectStatus "U5D1.CP3" )
				)
				( pin "pe2_tx_dp(4)"
					( attribute "PN" "CK1"
						( Origin gPackager )
					)
					( objectStatus "U5D1.CK1" )
				)
				( pin "pe2_tx_dp(5)"
					( attribute "PN" "CK3"
						( Origin gPackager )
					)
					( objectStatus "U5D1.CK3" )
				)
				( pin "pe2_tx_dp(6)"
					( attribute "PN" "CE2"
						( Origin gPackager )
					)
					( objectStatus "U5D1.CE2" )
				)
				( pin "pe2_tx_dp(7)"
					( attribute "PN" "CE4"
						( Origin gPackager )
					)
					( objectStatus "U5D1.CE4" )
				)
				( pin "pe2_tx_dp(8)"
					( attribute "PN" "CD3"
						( Origin gPackager )
					)
					( objectStatus "U5D1.CD3" )
				)
				( pin "pe2_tx_dp(9)"
					( attribute "PN" "BY3"
						( Origin gPackager )
					)
					( objectStatus "U5D1.BY3" )
				)
				( pin "pe2_tx_dp(10)"
					( attribute "PN" "BY5"
						( Origin gPackager )
					)
					( objectStatus "U5D1.BY5" )
				)
				( pin "pe2_tx_dp(11)"
					( attribute "PN" "BV3"
						( Origin gPackager )
					)
					( objectStatus "U5D1.BV3" )
				)
				( pin "pe2_tx_dp(12)"
					( attribute "PN" "BR4"
						( Origin gPackager )
					)
					( objectStatus "U5D1.BR4" )
				)
				( pin "pe2_tx_dp(13)"
					( attribute "PN" "BN4"
						( Origin gPackager )
					)
					( objectStatus "U5D1.BN4" )
				)
				( pin "pe2_tx_dp(14)"
					( attribute "PN" "BM3"
						( Origin gPackager )
					)
					( objectStatus "U5D1.BM3" )
				)
				( pin "pe2_tx_dp(15)"
					( attribute "PN" "BK5"
						( Origin gPackager )
					)
					( objectStatus "U5D1.BK5" )
				)
			)
			( gate "@baseboard_fab2_lib.baseboard_fab2(sch_1):page32_i89"
				( attribute "CDS_LIB" "chpset_lib"
					( Origin gPackager )
				)
				( attribute "CDS_LOCATION" "U5D1"
					( Origin gPackager )
				)
				( attribute "CDS_SEC" "12"
					( Origin gPackager )
				)
				( attribute "LOCATION" "U5D1"
					( Origin gFrontEnd )
				)
				( attribute "MATERIAL" "IC"
					( Origin gFrontEnd )
				)
				( attribute "PACK_TYPE" "BGA1"
					( Origin gFrontEnd )
				)
				( attribute "PART_NUMBER" "TBD"
					( Origin gFrontEnd )
				)
				( attribute "PHYS_PAGE" "32"
					( Origin gFrontEnd )
				)
				( attribute "ROT" "0"
					( Origin gFrontEnd )
				)
				( attribute "SEC" "12"
					( Origin gFrontEnd )
				)
				( attribute "SEC_TYPE" "BGA1"
					( Origin gFrontEnd )
				)
				( attribute "VER" "12"
					( Origin gFrontEnd )
				)
				( attribute "XY" "(-4200,2575)"
					( Origin gFrontEnd )
				)
				( attribute "CHIPS_PART_NAME" "SKX_EXT_B"
					( Origin gPackager )
				)
				( attribute "CDS_PART_NAME" "SKX_EXT_B_BGA1-IC,TBD"
					( Origin gPackager )
				)
				( objectStatus "U5D1" )
				( pin "pe3_rx_dn(0)"
					( attribute "PN" "EA18"
						( Origin gPackager )
					)
					( objectStatus "U5D1.EA18" )
				)
				( pin "pe3_rx_dn(1)"
					( attribute "PN" "DW18"
						( Origin gPackager )
					)
					( objectStatus "U5D1.DW18" )
				)
				( pin "pe3_rx_dn(2)"
					( attribute "PN" "DW16"
						( Origin gPackager )
					)
					( objectStatus "U5D1.DW16" )
				)
				( pin "pe3_rx_dn(3)"
					( attribute "PN" "DT19"
						( Origin gPackager )
					)
					( objectStatus "U5D1.DT19" )
				)
				( pin "pe3_rx_dn(4)"
					( attribute "PN" "DR16"
						( Origin gPackager )
					)
					( objectStatus "U5D1.DR16" )
				)
				( pin "pe3_rx_dn(5)"
					( attribute "PN" "DR14"
						( Origin gPackager )
					)
					( objectStatus "U5D1.DR14" )
				)
				( pin "pe3_rx_dn(6)"
					( attribute "PN" "DN14"
						( Origin gPackager )
					)
					( objectStatus "U5D1.DN14" )
				)
				( pin "pe3_rx_dn(7)"
					( attribute "PN" "DL14"
						( Origin gPackager )
					)
					( objectStatus "U5D1.DL14" )
				)
				( pin "pe3_rx_dn(8)"
					( attribute "PN" "DL12"
						( Origin gPackager )
					)
					( objectStatus "U5D1.DL12" )
				)
				( pin "pe3_rx_dn(9)"
					( attribute "PN" "DJ12"
						( Origin gPackager )
					)
					( objectStatus "U5D1.DJ12" )
				)
				( pin "pe3_rx_dn(10)"
					( attribute "PN" "DG12"
						( Origin gPackager )
					)
					( objectStatus "U5D1.DG12" )
				)
				( pin "pe3_rx_dn(11)"
					( attribute "PN" "DG10"
						( Origin gPackager )
					)
					( objectStatus "U5D1.DG10" )
				)
				( pin "pe3_rx_dn(12)"
					( attribute "PN" "DD13"
						( Origin gPackager )
					)
					( objectStatus "U5D1.DD13" )
				)
				( pin "pe3_rx_dn(13)"
					( attribute "PN" "DB11"
						( Origin gPackager )
					)
					( objectStatus "U5D1.DB11" )
				)
				( pin "pe3_rx_dn(14)"
					( attribute "PN" "CY11"
						( Origin gPackager )
					)
					( objectStatus "U5D1.CY11" )
				)
				( pin "pe3_rx_dn(15)"
					( attribute "PN" "CV9"
						( Origin gPackager )
					)
					( objectStatus "U5D1.CV9" )
				)
				( pin "pe3_rx_dp(0)"
					( attribute "PN" "DY17"
						( Origin gPackager )
					)
					( objectStatus "U5D1.DY17" )
				)
				( pin "pe3_rx_dp(1)"
					( attribute "PN" "DU18"
						( Origin gPackager )
					)
					( objectStatus "U5D1.DU18" )
				)
				( pin "pe3_rx_dp(2)"
					( attribute "PN" "DV17"
						( Origin gPackager )
					)
					( objectStatus "U5D1.DV17" )
				)
				( pin "pe3_rx_dp(3)"
					( attribute "PN" "DR18"
						( Origin gPackager )
					)
					( objectStatus "U5D1.DR18" )
				)
				( pin "pe3_rx_dp(4)"
					( attribute "PN" "DN16"
						( Origin gPackager )
					)
					( objectStatus "U5D1.DN16" )
				)
				( pin "pe3_rx_dp(5)"
					( attribute "PN" "DP15"
						( Origin gPackager )
					)
					( objectStatus "U5D1.DP15" )
				)
				( pin "pe3_rx_dp(6)"
					( attribute "PN" "DM13"
						( Origin gPackager )
					)
					( objectStatus "U5D1.DM13" )
				)
				( pin "pe3_rx_dp(7)"
					( attribute "PN" "DJ14"
						( Origin gPackager )
					)
					( objectStatus "U5D1.DJ14" )
				)
				( pin "pe3_rx_dp(8)"
					( attribute "PN" "DK13"
						( Origin gPackager )
					)
					( objectStatus "U5D1.DK13" )
				)
				( pin "pe3_rx_dp(9)"
					( attribute "PN" "DH11"
						( Origin gPackager )
					)
					( objectStatus "U5D1.DH11" )
				)
				( pin "pe3_rx_dp(10)"
					( attribute "PN" "DE12"
						( Origin gPackager )
					)
					( objectStatus "U5D1.DE12" )
				)
				( pin "pe3_rx_dp(11)"
					( attribute "PN" "DF11"
						( Origin gPackager )
					)
					( objectStatus "U5D1.DF11" )
				)
				( pin "pe3_rx_dp(12)"
					( attribute "PN" "DC12"
						( Origin gPackager )
					)
					( objectStatus "U5D1.DC12" )
				)
				( pin "pe3_rx_dp(13)"
					( attribute "PN" "DA12"
						( Origin gPackager )
					)
					( objectStatus "U5D1.DA12" )
				)
				( pin "pe3_rx_dp(14)"
					( attribute "PN" "CW10"
						( Origin gPackager )
					)
					( objectStatus "U5D1.CW10" )
				)
				( pin "pe3_rx_dp(15)"
					( attribute "PN" "CU10"
						( Origin gPackager )
					)
					( objectStatus "U5D1.CU10" )
				)
				( pin "pe3_tx_dn(0)"
					( attribute "PN" "EE14"
						( Origin gPackager )
					)
					( objectStatus "U5D1.EE14" )
				)
				( pin "pe3_tx_dn(1)"
					( attribute "PN" "EE12"
						( Origin gPackager )
					)
					( objectStatus "U5D1.EE12" )
				)
				( pin "pe3_tx_dn(2)"
					( attribute "PN" "EC12"
						( Origin gPackager )
					)
					( objectStatus "U5D1.EC12" )
				)
				( pin "pe3_tx_dn(3)"
					( attribute "PN" "DY11"
						( Origin gPackager )
					)
					( objectStatus "U5D1.DY11" )
				)
				( pin "pe3_tx_dn(4)"
					( attribute "PN" "EB9"
						( Origin gPackager )
					)
					( objectStatus "U5D1.EB9" )
				)
				( pin "pe3_tx_dn(5)"
					( attribute "PN" "DW10"
						( Origin gPackager )
					)
					( objectStatus "U5D1.DW10" )
				)
				( pin "pe3_tx_dn(6)"
					( attribute "PN" "DU8"
						( Origin gPackager )
					)
					( objectStatus "U5D1.DU8" )
				)
				( pin "pe3_tx_dn(7)"
					( attribute "PN" "DR8"
						( Origin gPackager )
					)
					( objectStatus "U5D1.DR8" )
				)
				( pin "pe3_tx_dn(8)"
					( attribute "PN" "DM7"
						( Origin gPackager )
					)
					( objectStatus "U5D1.DM7" )
				)
				( pin "pe3_tx_dn(9)"
					( attribute "PN" "DP5"
						( Origin gPackager )
					)
					( objectStatus "U5D1.DP5" )
				)
				( pin "pe3_tx_dn(10)"
					( attribute "PN" "DL6"
						( Origin gPackager )
					)
					( objectStatus "U5D1.DL6" )
				)
				( pin "pe3_tx_dn(11)"
					( attribute "PN" "DJ4"
						( Origin gPackager )
					)
					( objectStatus "U5D1.DJ4" )
				)
				( pin "pe3_tx_dn(12)"
					( attribute "PN" "DJ6"
						( Origin gPackager )
					)
					( objectStatus "U5D1.DJ6" )
				)
				( pin "pe3_tx_dn(13)"
					( attribute "PN" "DD5"
						( Origin gPackager )
					)
					( objectStatus "U5D1.DD5" )
				)
				( pin "pe3_tx_dn(14)"
					( attribute "PN" "DB5"
						( Origin gPackager )
					)
					( objectStatus "U5D1.DB5" )
				)
				( pin "pe3_tx_dn(15)"
					( attribute "PN" "CY5"
						( Origin gPackager )
					)
					( objectStatus "U5D1.CY5" )
				)
				( pin "pe3_tx_dp(0)"
					( attribute "PN" "EC14"
						( Origin gPackager )
					)
					( objectStatus "U5D1.EC14" )
				)
				( pin "pe3_tx_dp(1)"
					( attribute "PN" "ED13"
						( Origin gPackager )
					)
					( objectStatus "U5D1.ED13" )
				)
				( pin "pe3_tx_dp(2)"
					( attribute "PN" "EB11"
						( Origin gPackager )
					)
					( objectStatus "U5D1.EB11" )
				)
				( pin "pe3_tx_dp(3)"
					( attribute "PN" "EA10"
						( Origin gPackager )
					)
					( objectStatus "U5D1.EA10" )
				)
				( pin "pe3_tx_dp(4)"
					( attribute "PN" "DY9"
						( Origin gPackager )
					)
					( objectStatus "U5D1.DY9" )
				)
				( pin "pe3_tx_dp(5)"
					( attribute "PN" "DV9"
						( Origin gPackager )
					)
					( objectStatus "U5D1.DV9" )
				)
				( pin "pe3_tx_dp(6)"
					( attribute "PN" "DT9"
						( Origin gPackager )
					)
					( objectStatus "U5D1.DT9" )
				)
				( pin "pe3_tx_dp(7)"
					( attribute "PN" "DP7"
						( Origin gPackager )
					)
					( objectStatus "U5D1.DP7" )
				)
				( pin "pe3_tx_dp(8)"
					( attribute "PN" "DN6"
						( Origin gPackager )
					)
					( objectStatus "U5D1.DN6" )
				)
				( pin "pe3_tx_dp(9)"
					( attribute "PN" "DM5"
						( Origin gPackager )
					)
					( objectStatus "U5D1.DM5" )
				)
				( pin "pe3_tx_dp(10)"
					( attribute "PN" "DK5"
						( Origin gPackager )
					)
					( objectStatus "U5D1.DK5" )
				)
				( pin "pe3_tx_dp(11)"
					( attribute "PN" "DH5"
						( Origin gPackager )
					)
					( objectStatus "U5D1.DH5" )
				)
				( pin "pe3_tx_dp(12)"
					( attribute "PN" "DG6"
						( Origin gPackager )
					)
					( objectStatus "U5D1.DG6" )
				)
				( pin "pe3_tx_dp(13)"
					( attribute "PN" "DC6"
						( Origin gPackager )
					)
					( objectStatus "U5D1.DC6" )
				)
				( pin "pe3_tx_dp(14)"
					( attribute "PN" "DA4"
						( Origin gPackager )
					)
					( objectStatus "U5D1.DA4" )
				)
				( pin "pe3_tx_dp(15)"
					( attribute "PN" "CV5"
						( Origin gPackager )
					)
					( objectStatus "U5D1.CV5" )
				)
			)
			( gate "@baseboard_fab2_lib.baseboard_fab2(sch_1):page33_i86"
				( attribute "CDS_LIB" "chpset_lib"
					( Origin gPackager )
				)
				( attribute "CDS_LOCATION" "U5D1"
					( Origin gPackager )
				)
				( attribute "CDS_SEC" "13"
					( Origin gPackager )
				)
				( attribute "LOCATION" "U5D1"
					( Origin gFrontEnd )
				)
				( attribute "MATERIAL" "IC"
					( Origin gFrontEnd )
				)
				( attribute "PACK_TYPE" "BGA1"
					( Origin gFrontEnd )
				)
				( attribute "PART_NUMBER" "TBD"
					( Origin gFrontEnd )
				)
				( attribute "PHYS_PAGE" "33"
					( Origin gFrontEnd )
				)
				( attribute "ROOM" "CPU0"
					( Origin gFrontEnd )
				)
				( attribute "ROT" "0"
					( Origin gFrontEnd )
				)
				( attribute "SEC" "13"
					( Origin gFrontEnd )
				)
				( attribute "SEC_TYPE" "BGA1"
					( Origin gFrontEnd )
				)
				( attribute "VER" "13"
					( Origin gFrontEnd )
				)
				( attribute "XY" "(-4075,2600)"
					( Origin gFrontEnd )
				)
				( attribute "CHIPS_PART_NAME" "SKX_EXT_B"
					( Origin gPackager )
				)
				( attribute "CDS_PART_NAME" "SKX_EXT_B_BGA1-IC,TBD"
					( Origin gPackager )
				)
				( objectStatus "U5D1" )
				( pin "upi0_rx_dn(0)"
					( attribute "PN" "AC10"
						( Origin gPackager )
					)
					( objectStatus "U5D1.AC10" )
				)
				( pin "upi0_rx_dn(1)"
					( attribute "PN" "AA8"
						( Origin gPackager )
					)
					( objectStatus "U5D1.AA8" )
				)
				( pin "upi0_rx_dn(2)"
					( attribute "PN" "AB7"
						( Origin gPackager )
					)
					( objectStatus "U5D1.AB7" )
				)
				( pin "upi0_rx_dn(3)"
					( attribute "PN" "AD5"
						( Origin gPackager )
					)
					( objectStatus "U5D1.AD5" )
				)
				( pin "upi0_rx_dn(4)"
					( attribute "PN" "AE6"
						( Origin gPackager )
					)
					( objectStatus "U5D1.AE6" )
				)
				( pin "upi0_rx_dn(5)"
					( attribute "PN" "AG8"
						( Origin gPackager )
					)
					( objectStatus "U5D1.AG8" )
				)
				( pin "upi0_rx_dn(6)"
					( attribute "PN" "AJ6"
						( Origin gPackager )
					)
					( objectStatus "U5D1.AJ6" )
				)
				( pin "upi0_rx_dn(7)"
					( attribute "PN" "AL6"
						( Origin gPackager )
					)
					( objectStatus "U5D1.AL6" )
				)
				( pin "upi0_rx_dn(8)"
					( attribute "PN" "AK7"
						( Origin gPackager )
					)
					( objectStatus "U5D1.AK7" )
				)
				( pin "upi0_rx_dn(9)"
					( attribute "PN" "AM9"
						( Origin gPackager )
					)
					( objectStatus "U5D1.AM9" )
				)
				( pin "upi0_rx_dn(10)"
					( attribute "PN" "AP7"
						( Origin gPackager )
					)
					( objectStatus "U5D1.AP7" )
				)
				( pin "upi0_rx_dn(11)"
					( attribute "PN" "AR8"
						( Origin gPackager )
					)
					( objectStatus "U5D1.AR8" )
				)
				( pin "upi0_rx_dn(12)"
					( attribute "PN" "AU10"
						( Origin gPackager )
					)
					( objectStatus "U5D1.AU10" )
				)
				( pin "upi0_rx_dn(13)"
					( attribute "PN" "BA8"
						( Origin gPackager )
					)
					( objectStatus "U5D1.BA8" )
				)
				( pin "upi0_rx_dn(14)"
					( attribute "PN" "BC6"
						( Origin gPackager )
					)
					( objectStatus "U5D1.BC6" )
				)
				( pin "upi0_rx_dn(15)"
					( attribute "PN" "BD7"
						( Origin gPackager )
					)
					( objectStatus "U5D1.BD7" )
				)
				( pin "upi0_rx_dn(16)"
					( attribute "PN" "AW8"
						( Origin gPackager )
					)
					( objectStatus "U5D1.AW8" )
				)
				( pin "upi0_rx_dn(17)"
					( attribute "PN" "AY9"
						( Origin gPackager )
					)
					( objectStatus "U5D1.AY9" )
				)
				( pin "upi0_rx_dn(18)"
					( attribute "PN" "BD9"
						( Origin gPackager )
					)
					( objectStatus "U5D1.BD9" )
				)
				( pin "upi0_rx_dn(19)"
					( attribute "PN" "BB11"
						( Origin gPackager )
					)
					( objectStatus "U5D1.BB11" )
				)
				( pin "upi0_rx_dp(0)"
					( attribute "PN" "AB9"
						( Origin gPackager )
					)
					( objectStatus "U5D1.AB9" )
				)
				( pin "upi0_rx_dp(1)"
					( attribute "PN" "AC8"
						( Origin gPackager )
					)
					( objectStatus "U5D1.AC8" )
				)
				( pin "upi0_rx_dp(2)"
					( attribute "PN" "AA6"
						( Origin gPackager )
					)
					( objectStatus "U5D1.AA6" )
				)
				( pin "upi0_rx_dp(3)"
					( attribute "PN" "AC6"
						( Origin gPackager )
					)
					( objectStatus "U5D1.AC6" )
				)
				( pin "upi0_rx_dp(4)"
					( attribute "PN" "AG6"
						( Origin gPackager )
					)
					( objectStatus "U5D1.AG6" )
				)
				( pin "upi0_rx_dp(5)"
					( attribute "PN" "AF7"
						( Origin gPackager )
					)
					( objectStatus "U5D1.AF7" )
				)
				( pin "upi0_rx_dp(6)"
					( attribute "PN" "AH7"
						( Origin gPackager )
					)
					( objectStatus "U5D1.AH7" )
				)
				( pin "upi0_rx_dp(7)"
					( attribute "PN" "AK5"
						( Origin gPackager )
					)
					( objectStatus "U5D1.AK5" )
				)
				( pin "upi0_rx_dp(8)"
					( attribute "PN" "AM7"
						( Origin gPackager )
					)
					( objectStatus "U5D1.AM7" )
				)
				( pin "upi0_rx_dp(9)"
					( attribute "PN" "AL8"
						( Origin gPackager )
					)
					( objectStatus "U5D1.AL8" )
				)
				( pin "upi0_rx_dp(10)"
					( attribute "PN" "AN8"
						( Origin gPackager )
					)
					( objectStatus "U5D1.AN8" )
				)
				( pin "upi0_rx_dp(11)"
					( attribute "PN" "AU8"
						( Origin gPackager )
					)
					( objectStatus "U5D1.AU8" )
				)
				( pin "upi0_rx_dp(12)"
					( attribute "PN" "AT9"
						( Origin gPackager )
					)
					( objectStatus "U5D1.AT9" )
				)
				( pin "upi0_rx_dp(13)"
					( attribute "PN" "AY7"
						( Origin gPackager )
					)
					( objectStatus "U5D1.AY7" )
				)
				( pin "upi0_rx_dp(14)"
					( attribute "PN" "BB7"
						( Origin gPackager )
					)
					( objectStatus "U5D1.BB7" )
				)
				( pin "upi0_rx_dp(15)"
					( attribute "PN" "BF7"
						( Origin gPackager )
					)
					( objectStatus "U5D1.BF7" )
				)
				( pin "upi0_rx_dp(16)"
					( attribute "PN" "AV9"
						( Origin gPackager )
					)
					( objectStatus "U5D1.AV9" )
				)
				( pin "upi0_rx_dp(17)"
					( attribute "PN" "BB9"
						( Origin gPackager )
					)
					( objectStatus "U5D1.BB9" )
				)
				( pin "upi0_rx_dp(18)"
					( attribute "PN" "BC10"
						( Origin gPackager )
					)
					( objectStatus "U5D1.BC10" )
				)
				( pin "upi0_rx_dp(19)"
					( attribute "PN" "BA10"
						( Origin gPackager )
					)
					( objectStatus "U5D1.BA10" )
				)
				( pin "upi0_tx_dn(0)"
					( attribute "PN" "N2"
						( Origin gPackager )
					)
					( objectStatus "U5D1.N2" )
				)
				( pin "upi0_tx_dn(1)"
					( attribute "PN" "P1"
						( Origin gPackager )
					)
					( objectStatus "U5D1.P1" )
				)
				( pin "upi0_tx_dn(2)"
					( attribute "PN" "V3"
						( Origin gPackager )
					)
					( objectStatus "U5D1.V3" )
				)
				( pin "upi0_tx_dn(3)"
					( attribute "PN" "Y1"
						( Origin gPackager )
					)
					( objectStatus "U5D1.Y1" )
				)
				( pin "upi0_tx_dn(4)"
					( attribute "PN" "AB3"
						( Origin gPackager )
					)
					( objectStatus "U5D1.AB3" )
				)
				( pin "upi0_tx_dn(5)"
					( attribute "PN" "AC2"
						( Origin gPackager )
					)
					( objectStatus "U5D1.AC2" )
				)
				( pin "upi0_tx_dn(6)"
					( attribute "PN" "AG4"
						( Origin gPackager )
					)
					( objectStatus "U5D1.AG4" )
				)
				( pin "upi0_tx_dn(7)"
					( attribute "PN" "AE2"
						( Origin gPackager )
					)
					( objectStatus "U5D1.AE2" )
				)
				( pin "upi0_tx_dn(8)"
					( attribute "PN" "AH3"
						( Origin gPackager )
					)
					( objectStatus "U5D1.AH3" )
				)
				( pin "upi0_tx_dn(9)"
					( attribute "PN" "AL2"
						( Origin gPackager )
					)
					( objectStatus "U5D1.AL2" )
				)
				( pin "upi0_tx_dn(10)"
					( attribute "PN" "AM3"
						( Origin gPackager )
					)
					( objectStatus "U5D1.AM3" )
				)
				( pin "upi0_tx_dn(11)"
					( attribute "PN" "AN4"
						( Origin gPackager )
					)
					( objectStatus "U5D1.AN4" )
				)
				( pin "upi0_tx_dn(12)"
					( attribute "PN" "AT1"
						( Origin gPackager )
					)
					( objectStatus "U5D1.AT1" )
				)
				( pin "upi0_tx_dn(13)"
					( attribute "PN" "AT3"
						( Origin gPackager )
					)
					( objectStatus "U5D1.AT3" )
				)
				( pin "upi0_tx_dn(14)"
					( attribute "PN" "AU4"
						( Origin gPackager )
					)
					( objectStatus "U5D1.AU4" )
				)
				( pin "upi0_tx_dn(15)"
					( attribute "PN" "AV5"
						( Origin gPackager )
					)
					( objectStatus "U5D1.AV5" )
				)
				( pin "upi0_tx_dn(16)"
					( attribute "PN" "BA4"
						( Origin gPackager )
					)
					( objectStatus "U5D1.BA4" )
				)
				( pin "upi0_tx_dn(17)"
					( attribute "PN" "BB3"
						( Origin gPackager )
					)
					( objectStatus "U5D1.BB3" )
				)
				( pin "upi0_tx_dn(18)"
					( attribute "PN" "BF3"
						( Origin gPackager )
					)
					( objectStatus "U5D1.BF3" )
				)
				( pin "upi0_tx_dn(19)"
					( attribute "PN" "BG4"
						( Origin gPackager )
					)
					( objectStatus "U5D1.BG4" )
				)
				( pin "upi0_tx_dp(0)"
					( attribute "PN" "M1"
						( Origin gPackager )
					)
					( objectStatus "U5D1.M1" )
				)
				( pin "upi0_tx_dp(1)"
					( attribute "PN" "T1"
						( Origin gPackager )
					)
					( objectStatus "U5D1.T1" )
				)
				( pin "upi0_tx_dp(2)"
					( attribute "PN" "Y3"
						( Origin gPackager )
					)
					( objectStatus "U5D1.Y3" )
				)
				( pin "upi0_tx_dp(3)"
					( attribute "PN" "W2"
						( Origin gPackager )
					)
					( objectStatus "U5D1.W2" )
				)
				( pin "upi0_tx_dp(4)"
					( attribute "PN" "AA2"
						( Origin gPackager )
					)
					( objectStatus "U5D1.AA2" )
				)
				( pin "upi0_tx_dp(5)"
					( attribute "PN" "AD1"
						( Origin gPackager )
					)
					( objectStatus "U5D1.AD1" )
				)
				( pin "upi0_tx_dp(6)"
					( attribute "PN" "AF3"
						( Origin gPackager )
					)
					( objectStatus "U5D1.AF3" )
				)
				( pin "upi0_tx_dp(7)"
					( attribute "PN" "AG2"
						( Origin gPackager )
					)
					( objectStatus "U5D1.AG2" )
				)
				( pin "upi0_tx_dp(8)"
					( attribute "PN" "AJ2"
						( Origin gPackager )
					)
					( objectStatus "U5D1.AJ2" )
				)
				( pin "upi0_tx_dp(9)"
					( attribute "PN" "AK1"
						( Origin gPackager )
					)
					( objectStatus "U5D1.AK1" )
				)
				( pin "upi0_tx_dp(10)"
					( attribute "PN" "AK3"
						( Origin gPackager )
					)
					( objectStatus "U5D1.AK3" )
				)
				( pin "upi0_tx_dp(11)"
					( attribute "PN" "AP3"
						( Origin gPackager )
					)
					( objectStatus "U5D1.AP3" )
				)
				( pin "upi0_tx_dp(12)"
					( attribute "PN" "AP1"
						( Origin gPackager )
					)
					( objectStatus "U5D1.AP1" )
				)
				( pin "upi0_tx_dp(13)"
					( attribute "PN" "AR2"
						( Origin gPackager )
					)
					( objectStatus "U5D1.AR2" )
				)
				( pin "upi0_tx_dp(14)"
					( attribute "PN" "AR4"
						( Origin gPackager )
					)
					( objectStatus "U5D1.AR4" )
				)
				( pin "upi0_tx_dp(15)"
					( attribute "PN" "AW4"
						( Origin gPackager )
					)
					( objectStatus "U5D1.AW4" )
				)
				( pin "upi0_tx_dp(16)"
					( attribute "PN" "AY3"
						( Origin gPackager )
					)
					( objectStatus "U5D1.AY3" )
				)
				( pin "upi0_tx_dp(17)"
					( attribute "PN" "BC2"
						( Origin gPackager )
					)
					( objectStatus "U5D1.BC2" )
				)
				( pin "upi0_tx_dp(18)"
					( attribute "PN" "BD3"
						( Origin gPackager )
					)
					( objectStatus "U5D1.BD3" )
				)
				( pin "upi0_tx_dp(19)"
					( attribute "PN" "BH3"
						( Origin gPackager )
					)
					( objectStatus "U5D1.BH3" )
				)
			)
			( gate "@baseboard_fab2_lib.baseboard_fab2(sch_1):page34_i86"
				( attribute "CDS_LIB" "chpset_lib"
					( Origin gPackager )
				)
				( attribute "CDS_LOCATION" "U5D1"
					( Origin gPackager )
				)
				( attribute "CDS_SEC" "14"
					( Origin gPackager )
				)
				( attribute "LOCATION" "U5D1"
					( Origin gFrontEnd )
				)
				( attribute "MATERIAL" "IC"
					( Origin gFrontEnd )
				)
				( attribute "PACK_TYPE" "BGA1"
					( Origin gFrontEnd )
				)
				( attribute "PART_NUMBER" "TBD"
					( Origin gFrontEnd )
				)
				( attribute "PHYS_PAGE" "34"
					( Origin gFrontEnd )
				)
				( attribute "ROOM" "CPU0"
					( Origin gFrontEnd )
				)
				( attribute "ROT" "0"
					( Origin gFrontEnd )
				)
				( attribute "SEC" "14"
					( Origin gFrontEnd )
				)
				( attribute "SEC_TYPE" "BGA1"
					( Origin gFrontEnd )
				)
				( attribute "VER" "14"
					( Origin gFrontEnd )
				)
				( attribute "XY" "(-4100,2575)"
					( Origin gFrontEnd )
				)
				( attribute "CHIPS_PART_NAME" "SKX_EXT_B"
					( Origin gPackager )
				)
				( attribute "CDS_PART_NAME" "SKX_EXT_B_BGA1-IC,TBD"
					( Origin gPackager )
				)
				( objectStatus "U5D1" )
				( pin "upi1_rx_dn(0)"
					( attribute "PN" "T5"
						( Origin gPackager )
					)
					( objectStatus "U5D1.T5" )
				)
				( pin "upi1_rx_dn(1)"
					( attribute "PN" "P7"
						( Origin gPackager )
					)
					( objectStatus "U5D1.P7" )
				)
				( pin "upi1_rx_dn(2)"
					( attribute "PN" "V7"
						( Origin gPackager )
					)
					( objectStatus "U5D1.V7" )
				)
				( pin "upi1_rx_dn(3)"
					( attribute "PN" "T9"
						( Origin gPackager )
					)
					( objectStatus "U5D1.T9" )
				)
				( pin "upi1_rx_dn(4)"
					( attribute "PN" "P9"
						( Origin gPackager )
					)
					( objectStatus "U5D1.P9" )
				)
				( pin "upi1_rx_dn(5)"
					( attribute "PN" "R10"
						( Origin gPackager )
					)
					( objectStatus "U5D1.R10" )
				)
				( pin "upi1_rx_dn(6)"
					( attribute "PN" "U12"
						( Origin gPackager )
					)
					( objectStatus "U5D1.U12" )
				)
				( pin "upi1_rx_dn(7)"
					( attribute "PN" "L12"
						( Origin gPackager )
					)
					( objectStatus "U5D1.L12" )
				)
				( pin "upi1_rx_dn(8)"
					( attribute "PN" "N14"
						( Origin gPackager )
					)
					( objectStatus "U5D1.N14" )
				)
				( pin "upi1_rx_dn(9)"
					( attribute "PN" "R12"
						( Origin gPackager )
					)
					( objectStatus "U5D1.R12" )
				)
				( pin "upi1_rx_dn(10)"
					( attribute "PN" "R16"
						( Origin gPackager )
					)
					( objectStatus "U5D1.R16" )
				)
				( pin "upi1_rx_dn(11)"
					( attribute "PN" "P17"
						( Origin gPackager )
					)
					( objectStatus "U5D1.P17" )
				)
				( pin "upi1_rx_dn(12)"
					( attribute "PN" "U16"
						( Origin gPackager )
					)
					( objectStatus "U5D1.U16" )
				)
				( pin "upi1_rx_dn(13)"
					( attribute "PN" "W18"
						( Origin gPackager )
					)
					( objectStatus "U5D1.W18" )
				)
				( pin "upi1_rx_dn(14)"
					( attribute "PN" "R20"
						( Origin gPackager )
					)
					( objectStatus "U5D1.R20" )
				)
				( pin "upi1_rx_dn(15)"
					( attribute "PN" "U18"
						( Origin gPackager )
					)
					( objectStatus "U5D1.U18" )
				)
				( pin "upi1_rx_dn(16)"
					( attribute "PN" "P21"
						( Origin gPackager )
					)
					( objectStatus "U5D1.P21" )
				)
				( pin "upi1_rx_dn(17)"
					( attribute "PN" "V19"
						( Origin gPackager )
					)
					( objectStatus "U5D1.V19" )
				)
				( pin "upi1_rx_dn(18)"
					( attribute "PN" "Y21"
						( Origin gPackager )
					)
					( objectStatus "U5D1.Y21" )
				)
				( pin "upi1_rx_dn(19)"
					( attribute "PN" "AB19"
						( Origin gPackager )
					)
					( objectStatus "U5D1.AB19" )
				)
				( pin "upi1_rx_dp(0)"
					( attribute "PN" "R6"
						( Origin gPackager )
					)
					( objectStatus "U5D1.R6" )
				)
				( pin "upi1_rx_dp(1)"
					( attribute "PN" "T7"
						( Origin gPackager )
					)
					( objectStatus "U5D1.T7" )
				)
				( pin "upi1_rx_dp(2)"
					( attribute "PN" "U8"
						( Origin gPackager )
					)
					( objectStatus "U5D1.U8" )
				)
				( pin "upi1_rx_dp(3)"
					( attribute "PN" "R8"
						( Origin gPackager )
					)
					( objectStatus "U5D1.R8" )
				)
				( pin "upi1_rx_dp(4)"
					( attribute "PN" "N10"
						( Origin gPackager )
					)
					( objectStatus "U5D1.N10" )
				)
				( pin "upi1_rx_dp(5)"
					( attribute "PN" "U10"
						( Origin gPackager )
					)
					( objectStatus "U5D1.U10" )
				)
				( pin "upi1_rx_dp(6)"
					( attribute "PN" "T11"
						( Origin gPackager )
					)
					( objectStatus "U5D1.T11" )
				)
				( pin "upi1_rx_dp(7)"
					( attribute "PN" "N12"
						( Origin gPackager )
					)
					( objectStatus "U5D1.N12" )
				)
				( pin "upi1_rx_dp(8)"
					( attribute "PN" "M13"
						( Origin gPackager )
					)
					( objectStatus "U5D1.M13" )
				)
				( pin "upi1_rx_dp(9)"
					( attribute "PN" "P13"
						( Origin gPackager )
					)
					( objectStatus "U5D1.P13" )
				)
				( pin "upi1_rx_dp(10)"
					( attribute "PN" "T15"
						( Origin gPackager )
					)
					( objectStatus "U5D1.T15" )
				)
				( pin "upi1_rx_dp(11)"
					( attribute "PN" "N16"
						( Origin gPackager )
					)
					( objectStatus "U5D1.N16" )
				)
				( pin "upi1_rx_dp(12)"
					( attribute "PN" "W16"
						( Origin gPackager )
					)
					( objectStatus "U5D1.W16" )
				)
				( pin "upi1_rx_dp(13)"
					( attribute "PN" "V17"
						( Origin gPackager )
					)
					( objectStatus "U5D1.V17" )
				)
				( pin "upi1_rx_dp(14)"
					( attribute "PN" "P19"
						( Origin gPackager )
					)
					( objectStatus "U5D1.P19" )
				)
				( pin "upi1_rx_dp(15)"
					( attribute "PN" "T19"
						( Origin gPackager )
					)
					( objectStatus "U5D1.T19" )
				)
				( pin "upi1_rx_dp(16)"
					( attribute "PN" "T21"
						( Origin gPackager )
					)
					( objectStatus "U5D1.T21" )
				)
				( pin "upi1_rx_dp(17)"
					( attribute "PN" "Y19"
						( Origin gPackager )
					)
					( objectStatus "U5D1.Y19" )
				)
				( pin "upi1_rx_dp(18)"
					( attribute "PN" "W20"
						( Origin gPackager )
					)
					( objectStatus "U5D1.W20" )
				)
				( pin "upi1_rx_dp(19)"
					( attribute "PN" "AA20"
						( Origin gPackager )
					)
					( objectStatus "U5D1.AA20" )
				)
				( pin "upi1_tx_dn(0)"
					( attribute "PN" "M3"
						( Origin gPackager )
					)
					( objectStatus "U5D1.M3" )
				)
				( pin "upi1_tx_dn(1)"
					( attribute "PN" "L4"
						( Origin gPackager )
					)
					( objectStatus "U5D1.L4" )
				)
				( pin "upi1_tx_dn(2)"
					( attribute "PN" "K5"
						( Origin gPackager )
					)
					( objectStatus "U5D1.K5" )
				)
				( pin "upi1_tx_dn(3)"
					( attribute "PN" "J6"
						( Origin gPackager )
					)
					( objectStatus "U5D1.J6" )
				)
				( pin "upi1_tx_dn(4)"
					( attribute "PN" "G6"
						( Origin gPackager )
					)
					( objectStatus "U5D1.G6" )
				)
				( pin "upi1_tx_dn(5)"
					( attribute "PN" "H7"
						( Origin gPackager )
					)
					( objectStatus "U5D1.H7" )
				)
				( pin "upi1_tx_dn(6)"
					( attribute "PN" "K9"
						( Origin gPackager )
					)
					( objectStatus "U5D1.K9" )
				)
				( pin "upi1_tx_dn(7)"
					( attribute "PN" "D9"
						( Origin gPackager )
					)
					( objectStatus "U5D1.D9" )
				)
				( pin "upi1_tx_dn(8)"
					( attribute "PN" "F11"
						( Origin gPackager )
					)
					( objectStatus "U5D1.F11" )
				)
				( pin "upi1_tx_dn(9)"
					( attribute "PN" "G10"
						( Origin gPackager )
					)
					( objectStatus "U5D1.G10" )
				)
				( pin "upi1_tx_dn(10)"
					( attribute "PN" "E12"
						( Origin gPackager )
					)
					( objectStatus "U5D1.E12" )
				)
				( pin "upi1_tx_dn(11)"
					( attribute "PN" "G14"
						( Origin gPackager )
					)
					( objectStatus "U5D1.G14" )
				)
				( pin "upi1_tx_dn(12)"
					( attribute "PN" "D15"
						( Origin gPackager )
					)
					( objectStatus "U5D1.D15" )
				)
				( pin "upi1_tx_dn(13)"
					( attribute "PN" "F15"
						( Origin gPackager )
					)
					( objectStatus "U5D1.F15" )
				)
				( pin "upi1_tx_dn(14)"
					( attribute "PN" "H17"
						( Origin gPackager )
					)
					( objectStatus "U5D1.H17" )
				)
				( pin "upi1_tx_dn(15)"
					( attribute "PN" "K19"
						( Origin gPackager )
					)
					( objectStatus "U5D1.K19" )
				)
				( pin "upi1_tx_dn(16)"
					( attribute "PN" "G18"
						( Origin gPackager )
					)
					( objectStatus "U5D1.G18" )
				)
				( pin "upi1_tx_dn(17)"
					( attribute "PN" "J20"
						( Origin gPackager )
					)
					( objectStatus "U5D1.J20" )
				)
				( pin "upi1_tx_dn(18)"
					( attribute "PN" "F21"
						( Origin gPackager )
					)
					( objectStatus "U5D1.F21" )
				)
				( pin "upi1_tx_dn(19)"
					( attribute "PN" "H21"
						( Origin gPackager )
					)
					( objectStatus "U5D1.H21" )
				)
				( pin "upi1_tx_dp(0)"
					( attribute "PN" "P3"
						( Origin gPackager )
					)
					( objectStatus "U5D1.P3" )
				)
				( pin "upi1_tx_dp(1)"
					( attribute "PN" "K3"
						( Origin gPackager )
					)
					( objectStatus "U5D1.K3" )
				)
				( pin "upi1_tx_dp(2)"
					( attribute "PN" "M5"
						( Origin gPackager )
					)
					( objectStatus "U5D1.M5" )
				)
				( pin "upi1_tx_dp(3)"
					( attribute "PN" "H5"
						( Origin gPackager )
					)
					( objectStatus "U5D1.H5" )
				)
				( pin "upi1_tx_dp(4)"
					( attribute "PN" "F7"
						( Origin gPackager )
					)
					( objectStatus "U5D1.F7" )
				)
				( pin "upi1_tx_dp(5)"
					( attribute "PN" "K7"
						( Origin gPackager )
					)
					( objectStatus "U5D1.K7" )
				)
				( pin "upi1_tx_dp(6)"
					( attribute "PN" "J8"
						( Origin gPackager )
					)
					( objectStatus "U5D1.J8" )
				)
				( pin "upi1_tx_dp(7)"
					( attribute "PN" "F9"
						( Origin gPackager )
					)
					( objectStatus "U5D1.F9" )
				)
				( pin "upi1_tx_dp(8)"
					( attribute "PN" "E10"
						( Origin gPackager )
					)
					( objectStatus "U5D1.E10" )
				)
				( pin "upi1_tx_dp(9)"
					( attribute "PN" "H9"
						( Origin gPackager )
					)
					( objectStatus "U5D1.H9" )
				)
				( pin "upi1_tx_dp(10)"
					( attribute "PN" "G12"
						( Origin gPackager )
					)
					( objectStatus "U5D1.G12" )
				)
				( pin "upi1_tx_dp(11)"
					( attribute "PN" "F13"
						( Origin gPackager )
					)
					( objectStatus "U5D1.F13" )
				)
				( pin "upi1_tx_dp(12)"
					( attribute "PN" "E14"
						( Origin gPackager )
					)
					( objectStatus "U5D1.E14" )
				)
				( pin "upi1_tx_dp(13)"
					( attribute "PN" "H15"
						( Origin gPackager )
					)
					( objectStatus "U5D1.H15" )
				)
				( pin "upi1_tx_dp(14)"
					( attribute "PN" "G16"
						( Origin gPackager )
					)
					( objectStatus "U5D1.G16" )
				)
				( pin "upi1_tx_dp(15)"
					( attribute "PN" "L18"
						( Origin gPackager )
					)
					( objectStatus "U5D1.L18" )
				)
				( pin "upi1_tx_dp(16)"
					( attribute "PN" "J18"
						( Origin gPackager )
					)
					( objectStatus "U5D1.J18" )
				)
				( pin "upi1_tx_dp(17)"
					( attribute "PN" "H19"
						( Origin gPackager )
					)
					( objectStatus "U5D1.H19" )
				)
				( pin "upi1_tx_dp(18)"
					( attribute "PN" "G20"
						( Origin gPackager )
					)
					( objectStatus "U5D1.G20" )
				)
				( pin "upi1_tx_dp(19)"
					( attribute "PN" "K21"
						( Origin gPackager )
					)
					( objectStatus "U5D1.K21" )
				)
			)
			( gate "@baseboard_fab2_lib.baseboard_fab2(sch_1):page35_i3"
				( attribute "CDS_LIB" "chpset_lib"
					( Origin gPackager )
				)
				( attribute "CDS_LOCATION" "U5D1"
					( Origin gPackager )
				)
				( attribute "CDS_SEC" "15"
					( Origin gPackager )
				)
				( attribute "LOCATION" "U5D1"
					( Origin gFrontEnd )
				)
				( attribute "MATERIAL" "IC"
					( Origin gFrontEnd )
				)
				( attribute "PACK_TYPE" "BGA1"
					( Origin gFrontEnd )
				)
				( attribute "PART_NUMBER" "TBD"
					( Origin gFrontEnd )
				)
				( attribute "PHYS_PAGE" "35"
					( Origin gFrontEnd )
				)
				( attribute "ROOM" "CPU0"
					( Origin gFrontEnd )
				)
				( attribute "ROT" "0"
					( Origin gFrontEnd )
				)
				( attribute "SEC" "15"
					( Origin gFrontEnd )
				)
				( attribute "SEC_TYPE" "BGA1"
					( Origin gFrontEnd )
				)
				( attribute "VER" "15"
					( Origin gFrontEnd )
				)
				( attribute "XY" "(-4225,2625)"
					( Origin gFrontEnd )
				)
				( attribute "CHIPS_PART_NAME" "SKX_EXT_B"
					( Origin gPackager )
				)
				( attribute "CDS_PART_NAME" "SKX_EXT_B_BGA1-IC,TBD"
					( Origin gPackager )
				)
				( objectStatus "U5D1" )
				( pin "upi2_rx_dn(0)"
					( attribute "PN" "DF23"
						( Origin gPackager )
					)
					( objectStatus "U5D1.DF23" )
				)
				( pin "upi2_rx_dn(1)"
					( attribute "PN" "DE22"
						( Origin gPackager )
					)
					( objectStatus "U5D1.DE22" )
				)
				( pin "upi2_rx_dn(2)"
					( attribute "PN" "DC22"
						( Origin gPackager )
					)
					( objectStatus "U5D1.DC22" )
				)
				( pin "upi2_rx_dn(3)"
					( attribute "PN" "DB21"
						( Origin gPackager )
					)
					( objectStatus "U5D1.DB21" )
				)
				( pin "upi2_rx_dn(4)"
					( attribute "PN" "DD19"
						( Origin gPackager )
					)
					( objectStatus "U5D1.DD19" )
				)
				( pin "upi2_rx_dn(5)"
					( attribute "PN" "DA20"
						( Origin gPackager )
					)
					( objectStatus "U5D1.DA20" )
				)
				( pin "upi2_rx_dn(6)"
					( attribute "PN" "CW20"
						( Origin gPackager )
					)
					( objectStatus "U5D1.CW20" )
				)
				( pin "upi2_rx_dn(7)"
					( attribute "PN" "CV19"
						( Origin gPackager )
					)
					( objectStatus "U5D1.CV19" )
				)
				( pin "upi2_rx_dn(8)"
					( attribute "PN" "CT21"
						( Origin gPackager )
					)
					( objectStatus "U5D1.CT21" )
				)
				( pin "upi2_rx_dn(9)"
					( attribute "PN" "CR18"
						( Origin gPackager )
					)
					( objectStatus "U5D1.CR18" )
				)
				( pin "upi2_rx_dn(10)"
					( attribute "PN" "CN20"
						( Origin gPackager )
					)
					( objectStatus "U5D1.CN20" )
				)
				( pin "upi2_rx_dn(11)"
					( attribute "PN" "CP21"
						( Origin gPackager )
					)
					( objectStatus "U5D1.CP21" )
				)
				( pin "upi2_rx_dn(12)"
					( attribute "PN" "CL16"
						( Origin gPackager )
					)
					( objectStatus "U5D1.CL16" )
				)
				( pin "upi2_rx_dn(13)"
					( attribute "PN" "CJ18"
						( Origin gPackager )
					)
					( objectStatus "U5D1.CJ18" )
				)
				( pin "upi2_rx_dn(14)"
					( attribute "PN" "CH17"
						( Origin gPackager )
					)
					( objectStatus "U5D1.CH17" )
				)
				( pin "upi2_rx_dn(15)"
					( attribute "PN" "CE16"
						( Origin gPackager )
					)
					( objectStatus "U5D1.CE16" )
				)
				( pin "upi2_rx_dn(16)"
					( attribute "PN" "CD15"
						( Origin gPackager )
					)
					( objectStatus "U5D1.CD15" )
				)
				( pin "upi2_rx_dn(17)"
					( attribute "PN" "CF17"
						( Origin gPackager )
					)
					( objectStatus "U5D1.CF17" )
				)
				( pin "upi2_rx_dn(18)"
					( attribute "PN" "CB15"
						( Origin gPackager )
					)
					( objectStatus "U5D1.CB15" )
				)
				( pin "upi2_rx_dn(19)"
					( attribute "PN" "BY17"
						( Origin gPackager )
					)
					( objectStatus "U5D1.BY17" )
				)
				( pin "upi2_rx_dp(0)"
					( attribute "PN" "DG22"
						( Origin gPackager )
					)
					( objectStatus "U5D1.DG22" )
				)
				( pin "upi2_rx_dp(1)"
					( attribute "PN" "DD21"
						( Origin gPackager )
					)
					( objectStatus "U5D1.DD21" )
				)
				( pin "upi2_rx_dp(2)"
					( attribute "PN" "DA22"
						( Origin gPackager )
					)
					( objectStatus "U5D1.DA22" )
				)
				( pin "upi2_rx_dp(3)"
					( attribute "PN" "DC20"
						( Origin gPackager )
					)
					( objectStatus "U5D1.DC20" )
				)
				( pin "upi2_rx_dp(4)"
					( attribute "PN" "DB19"
						( Origin gPackager )
					)
					( objectStatus "U5D1.DB19" )
				)
				( pin "upi2_rx_dp(5)"
					( attribute "PN" "CY19"
						( Origin gPackager )
					)
					( objectStatus "U5D1.CY19" )
				)
				( pin "upi2_rx_dp(6)"
					( attribute "PN" "CU20"
						( Origin gPackager )
					)
					( objectStatus "U5D1.CU20" )
				)
				( pin "upi2_rx_dp(7)"
					( attribute "PN" "CW18"
						( Origin gPackager )
					)
					( objectStatus "U5D1.CW18" )
				)
				( pin "upi2_rx_dp(8)"
					( attribute "PN" "CR20"
						( Origin gPackager )
					)
					( objectStatus "U5D1.CR20" )
				)
				( pin "upi2_rx_dp(9)"
					( attribute "PN" "CN18"
						( Origin gPackager )
					)
					( objectStatus "U5D1.CN18" )
				)
				( pin "upi2_rx_dp(10)"
					( attribute "PN" "CP19"
						( Origin gPackager )
					)
					( objectStatus "U5D1.CP19" )
				)
				( pin "upi2_rx_dp(11)"
					( attribute "PN" "CM21"
						( Origin gPackager )
					)
					( objectStatus "U5D1.CM21" )
				)
				( pin "upi2_rx_dp(12)"
					( attribute "PN" "CJ16"
						( Origin gPackager )
					)
					( objectStatus "U5D1.CJ16" )
				)
				( pin "upi2_rx_dp(13)"
					( attribute "PN" "CK17"
						( Origin gPackager )
					)
					( objectStatus "U5D1.CK17" )
				)
				( pin "upi2_rx_dp(14)"
					( attribute "PN" "CG16"
						( Origin gPackager )
					)
					( objectStatus "U5D1.CG16" )
				)
				( pin "upi2_rx_dp(15)"
					( attribute "PN" "CF15"
						( Origin gPackager )
					)
					( objectStatus "U5D1.CF15" )
				)
				( pin "upi2_rx_dp(16)"
					( attribute "PN" "CC14"
						( Origin gPackager )
					)
					( objectStatus "U5D1.CC14" )
				)
				( pin "upi2_rx_dp(17)"
					( attribute "PN" "CD17"
						( Origin gPackager )
					)
					( objectStatus "U5D1.CD17" )
				)
				( pin "upi2_rx_dp(18)"
					( attribute "PN" "BY15"
						( Origin gPackager )
					)
					( objectStatus "U5D1.BY15" )
				)
				( pin "upi2_rx_dp(19)"
					( attribute "PN" "CA16"
						( Origin gPackager )
					)
					( objectStatus "U5D1.CA16" )
				)
				( pin "upi2_tx_dn(0)"
					( attribute "PN" "DT21"
						( Origin gPackager )
					)
					( objectStatus "U5D1.DT21" )
				)
				( pin "upi2_tx_dn(1)"
					( attribute "PN" "DM21"
						( Origin gPackager )
					)
					( objectStatus "U5D1.DM21" )
				)
				( pin "upi2_tx_dn(2)"
					( attribute "PN" "DL20"
						( Origin gPackager )
					)
					( objectStatus "U5D1.DL20" )
				)
				( pin "upi2_tx_dn(3)"
					( attribute "PN" "DG20"
						( Origin gPackager )
					)
					( objectStatus "U5D1.DG20" )
				)
				( pin "upi2_tx_dn(4)"
					( attribute "PN" "DH19"
						( Origin gPackager )
					)
					( objectStatus "U5D1.DH19" )
				)
				( pin "upi2_tx_dn(5)"
					( attribute "PN" "DK17"
						( Origin gPackager )
					)
					( objectStatus "U5D1.DK17" )
				)
				( pin "upi2_tx_dn(6)"
					( attribute "PN" "DG18"
						( Origin gPackager )
					)
					( objectStatus "U5D1.DG18" )
				)
				( pin "upi2_tx_dn(7)"
					( attribute "PN" "DD17"
						( Origin gPackager )
					)
					( objectStatus "U5D1.DD17" )
				)
				( pin "upi2_tx_dn(8)"
					( attribute "PN" "DF15"
						( Origin gPackager )
					)
					( objectStatus "U5D1.DF15" )
				)
				( pin "upi2_tx_dn(9)"
					( attribute "PN" "DC16"
						( Origin gPackager )
					)
					( objectStatus "U5D1.DC16" )
				)
				( pin "upi2_tx_dn(10)"
					( attribute "PN" "DA16"
						( Origin gPackager )
					)
					( objectStatus "U5D1.DA16" )
				)
				( pin "upi2_tx_dn(11)"
					( attribute "PN" "CW14"
						( Origin gPackager )
					)
					( objectStatus "U5D1.CW14" )
				)
				( pin "upi2_tx_dn(12)"
					( attribute "PN" "CU14"
						( Origin gPackager )
					)
					( objectStatus "U5D1.CU14" )
				)
				( pin "upi2_tx_dn(13)"
					( attribute "PN" "CM13"
						( Origin gPackager )
					)
					( objectStatus "U5D1.CM13" )
				)
				( pin "upi2_tx_dn(14)"
					( attribute "PN" "CJ14"
						( Origin gPackager )
					)
					( objectStatus "U5D1.CJ14" )
				)
				( pin "upi2_tx_dn(15)"
					( attribute "PN" "CF13"
						( Origin gPackager )
					)
					( objectStatus "U5D1.CF13" )
				)
				( pin "upi2_tx_dn(16)"
					( attribute "PN" "CH11"
						( Origin gPackager )
					)
					( objectStatus "U5D1.CH11" )
				)
				( pin "upi2_tx_dn(17)"
					( attribute "PN" "CE12"
						( Origin gPackager )
					)
					( objectStatus "U5D1.CE12" )
				)
				( pin "upi2_tx_dn(18)"
					( attribute "PN" "CC10"
						( Origin gPackager )
					)
					( objectStatus "U5D1.CC10" )
				)
				( pin "upi2_tx_dn(19)"
					( attribute "PN" "CC12"
						( Origin gPackager )
					)
					( objectStatus "U5D1.CC12" )
				)
				( pin "upi2_tx_dp(0)"
					( attribute "PN" "DP21"
						( Origin gPackager )
					)
					( objectStatus "U5D1.DP21" )
				)
				( pin "upi2_tx_dp(1)"
					( attribute "PN" "DN20"
						( Origin gPackager )
					)
					( objectStatus "U5D1.DN20" )
				)
				( pin "upi2_tx_dp(2)"
					( attribute "PN" "DK19"
						( Origin gPackager )
					)
					( objectStatus "U5D1.DK19" )
				)
				( pin "upi2_tx_dp(3)"
					( attribute "PN" "DJ20"
						( Origin gPackager )
					)
					( objectStatus "U5D1.DJ20" )
				)
				( pin "upi2_tx_dp(4)"
					( attribute "PN" "DJ18"
						( Origin gPackager )
					)
					( objectStatus "U5D1.DJ18" )
				)
				( pin "upi2_tx_dp(5)"
					( attribute "PN" "DH17"
						( Origin gPackager )
					)
					( objectStatus "U5D1.DH17" )
				)
				( pin "upi2_tx_dp(6)"
					( attribute "PN" "DF17"
						( Origin gPackager )
					)
					( objectStatus "U5D1.DF17" )
				)
				( pin "upi2_tx_dp(7)"
					( attribute "PN" "DE16"
						( Origin gPackager )
					)
					( objectStatus "U5D1.DE16" )
				)
				( pin "upi2_tx_dp(8)"
					( attribute "PN" "DD15"
						( Origin gPackager )
					)
					( objectStatus "U5D1.DD15" )
				)
				( pin "upi2_tx_dp(9)"
					( attribute "PN" "DB15"
						( Origin gPackager )
					)
					( objectStatus "U5D1.DB15" )
				)
				( pin "upi2_tx_dp(10)"
					( attribute "PN" "CW16"
						( Origin gPackager )
					)
					( objectStatus "U5D1.CW16" )
				)
				( pin "upi2_tx_dp(11)"
					( attribute "PN" "CV13"
						( Origin gPackager )
					)
					( objectStatus "U5D1.CV13" )
				)
				( pin "upi2_tx_dp(12)"
					( attribute "PN" "CR14"
						( Origin gPackager )
					)
					( objectStatus "U5D1.CR14" )
				)
				( pin "upi2_tx_dp(13)"
					( attribute "PN" "CK13"
						( Origin gPackager )
					)
					( objectStatus "U5D1.CK13" )
				)
				( pin "upi2_tx_dp(14)"
					( attribute "PN" "CH13"
						( Origin gPackager )
					)
					( objectStatus "U5D1.CH13" )
				)
				( pin "upi2_tx_dp(15)"
					( attribute "PN" "CG12"
						( Origin gPackager )
					)
					( objectStatus "U5D1.CG12" )
				)
				( pin "upi2_tx_dp(16)"
					( attribute "PN" "CF11"
						( Origin gPackager )
					)
					( objectStatus "U5D1.CF11" )
				)
				( pin "upi2_tx_dp(17)"
					( attribute "PN" "CD11"
						( Origin gPackager )
					)
					( objectStatus "U5D1.CD11" )
				)
				( pin "upi2_tx_dp(18)"
					( attribute "PN" "CB11"
						( Origin gPackager )
					)
					( objectStatus "U5D1.CB11" )
				)
				( pin "upi2_tx_dp(19)"
					( attribute "PN" "CA12"
						( Origin gPackager )
					)
					( objectStatus "U5D1.CA12" )
				)
			)
			( gate "@baseboard_fab2_lib.baseboard_fab2(sch_1):page36_i15"
				( attribute "CDS_LIB" "chpset_lib"
					( Origin gPackager )
				)
				( attribute "CDS_LOCATION" "U5D1"
					( Origin gPackager )
				)
				( attribute "CDS_SEC" "16"
					( Origin gPackager )
				)
				( attribute "LOCATION" "U5D1"
					( Origin gFrontEnd )
				)
				( attribute "MATERIAL" "IC"
					( Origin gFrontEnd )
				)
				( attribute "PACK_TYPE" "BGA1"
					( Origin gFrontEnd )
				)
				( attribute "PART_NUMBER" "TBD"
					( Origin gFrontEnd )
				)
				( attribute "PHYS_PAGE" "36"
					( Origin gFrontEnd )
				)
				( attribute "ROOM" "CPU0"
					( Origin gFrontEnd )
				)
				( attribute "ROT" "0"
					( Origin gFrontEnd )
				)
				( attribute "SEC" "16"
					( Origin gFrontEnd )
				)
				( attribute "SEC_TYPE" "BGA1"
					( Origin gFrontEnd )
				)
				( attribute "VER" "16"
					( Origin gFrontEnd )
				)
				( attribute "XY" "(-6075,2550)"
					( Origin gFrontEnd )
				)
				( attribute "CHIPS_PART_NAME" "SKX_EXT_B"
					( Origin gPackager )
				)
				( attribute "CDS_PART_NAME" "SKX_EXT_B_BGA1-IC,TBD"
					( Origin gPackager )
				)
				( objectStatus "U5D1" )
				( pin "rsvd(92)"
					( attribute "PN" "CH23"
						( Origin gPackager )
					)
					( objectStatus "U5D1.CH23" )
				)
				( pin "rsvd(93)"
					( attribute "PN" "CH21"
						( Origin gPackager )
					)
					( objectStatus "U5D1.CH21" )
				)
				( pin "rsvd(94)"
					( attribute "PN" "CG82"
						( Origin gPackager )
					)
					( objectStatus "U5D1.CG82" )
				)
				( pin "rsvd(95)"
					( attribute "PN" "CG78"
						( Origin gPackager )
					)
					( objectStatus "U5D1.CG78" )
				)
				( pin "rsvd(96)"
					( attribute "PN" "CG26"
						( Origin gPackager )
					)
					( objectStatus "U5D1.CG26" )
				)
				( pin "rsvd(97)"
					( attribute "PN" "CG24"
						( Origin gPackager )
					)
					( objectStatus "U5D1.CG24" )
				)
				( pin "rsvd(98)"
					( attribute "PN" "CG20"
						( Origin gPackager )
					)
					( objectStatus "U5D1.CG20" )
				)
				( pin "rsvd(99)"
					( attribute "PN" "CG10"
						( Origin gPackager )
					)
					( objectStatus "U5D1.CG10" )
				)
				( pin "rsvd(100)"
					( attribute "PN" "CF81"
						( Origin gPackager )
					)
					( objectStatus "U5D1.CF81" )
				)
				( pin "rsvd(101)"
					( attribute "PN" "CF79"
						( Origin gPackager )
					)
					( objectStatus "U5D1.CF79" )
				)
				( pin "rsvd(102)"
					( attribute "PN" "CF23"
						( Origin gPackager )
					)
					( objectStatus "U5D1.CF23" )
				)
				( pin "rsvd(103)"
					( attribute "PN" "CF21"
						( Origin gPackager )
					)
					( objectStatus "U5D1.CF21" )
				)
				( pin "rsvd(104)"
					( attribute "PN" "CF19"
						( Origin gPackager )
					)
					( objectStatus "U5D1.CF19" )
				)
				( pin "rsvd(105)"
					( attribute "PN" "CE80"
						( Origin gPackager )
					)
					( objectStatus "U5D1.CE80" )
				)
				( pin "rsvd(106)"
					( attribute "PN" "CE78"
						( Origin gPackager )
					)
					( objectStatus "U5D1.CE78" )
				)
				( pin "rsvd(107)"
					( attribute "PN" "CE22"
						( Origin gPackager )
					)
					( objectStatus "U5D1.CE22" )
				)
				( pin "rsvd(108)"
					( attribute "PN" "CD25"
						( Origin gPackager )
					)
					( objectStatus "U5D1.CD25" )
				)
				( pin "rsvd(109)"
					( attribute "PN" "CD21"
						( Origin gPackager )
					)
					( objectStatus "U5D1.CD21" )
				)
				( pin "rsvd(110)"
					( attribute "PN" "CD19"
						( Origin gPackager )
					)
					( objectStatus "U5D1.CD19" )
				)
				( pin "rsvd(111)"
					( attribute "PN" "CC6"
						( Origin gPackager )
					)
					( objectStatus "U5D1.CC6" )
				)
				( pin "rsvd(112)"
					( attribute "PN" "CC20"
						( Origin gPackager )
					)
					( objectStatus "U5D1.CC20" )
				)
				( pin "rsvd(113)"
					( attribute "PN" "CB5"
						( Origin gPackager )
					)
					( objectStatus "U5D1.CB5" )
				)
				( pin "rsvd(114)"
					( attribute "PN" "CB25"
						( Origin gPackager )
					)
					( objectStatus "U5D1.CB25" )
				)
				( pin "rsvd(115)"
					( attribute "PN" "CB21"
						( Origin gPackager )
					)
					( objectStatus "U5D1.CB21" )
				)
				( pin "rsvd(116)"
					( attribute "PN" "CB19"
						( Origin gPackager )
					)
					( objectStatus "U5D1.CB19" )
				)
				( pin "rsvd(117)"
					( attribute "PN" "CA24"
						( Origin gPackager )
					)
					( objectStatus "U5D1.CA24" )
				)
				( pin "rsvd(118)"
					( attribute "PN" "CA22"
						( Origin gPackager )
					)
					( objectStatus "U5D1.CA22" )
				)
				( pin "rsvd(119)"
					( attribute "PN" "BY25"
						( Origin gPackager )
					)
					( objectStatus "U5D1.BY25" )
				)
				( pin "rsvd(120)"
					( attribute "PN" "BY19"
						( Origin gPackager )
					)
					( objectStatus "U5D1.BY19" )
				)
				( pin "rsvd(121)"
					( attribute "PN" "BW22"
						( Origin gPackager )
					)
					( objectStatus "U5D1.BW22" )
				)
				( pin "rsvd(122)"
					( attribute "PN" "BW20"
						( Origin gPackager )
					)
					( objectStatus "U5D1.BW20" )
				)
				( pin "rsvd(123)"
					( attribute "PN" "BW10"
						( Origin gPackager )
					)
					( objectStatus "U5D1.BW10" )
				)
				( pin "rsvd(124)"
					( attribute "PN" "BV23"
						( Origin gPackager )
					)
					( objectStatus "U5D1.BV23" )
				)
				( pin "rsvd(125)"
					( attribute "PN" "BV21"
						( Origin gPackager )
					)
					( objectStatus "U5D1.BV21" )
				)
				( pin "rsvd(126)"
					( attribute "PN" "BV19"
						( Origin gPackager )
					)
					( objectStatus "U5D1.BV19" )
				)
				( pin "rsvd(127)"
					( attribute "PN" "BU22"
						( Origin gPackager )
					)
					( objectStatus "U5D1.BU22" )
				)
				( pin "rsvd(128)"
					( attribute "PN" "BU20"
						( Origin gPackager )
					)
					( objectStatus "U5D1.BU20" )
				)
				( pin "rsvd(129)"
					( attribute "PN" "BU18"
						( Origin gPackager )
					)
					( objectStatus "U5D1.BU18" )
				)
				( pin "rsvd(130)"
					( attribute "PN" "BR24"
						( Origin gPackager )
					)
					( objectStatus "U5D1.BR24" )
				)
				( pin "rsvd(131)"
					( attribute "PN" "BR22"
						( Origin gPackager )
					)
					( objectStatus "U5D1.BR22" )
				)
				( pin "rsvd(132)"
					( attribute "PN" "BP21"
						( Origin gPackager )
					)
					( objectStatus "U5D1.BP21" )
				)
				( pin "rsvd(133)"
					( attribute "PN" "BP17"
						( Origin gPackager )
					)
					( objectStatus "U5D1.BP17" )
				)
				( pin "rsvd(134)"
					( attribute "PN" "BN18"
						( Origin gPackager )
					)
					( objectStatus "U5D1.BN18" )
				)
				( pin "rsvd(135)"
					( attribute "PN" "BM19"
						( Origin gPackager )
					)
					( objectStatus "U5D1.BM19" )
				)
				( pin "rsvd(136)"
					( attribute "PN" "BM17"
						( Origin gPackager )
					)
					( objectStatus "U5D1.BM17" )
				)
				( pin "rsvd(137)"
					( attribute "PN" "BL20"
						( Origin gPackager )
					)
					( objectStatus "U5D1.BL20" )
				)
				( pin "rsvd(138)"
					( attribute "PN" "BL18"
						( Origin gPackager )
					)
					( objectStatus "U5D1.BL18" )
				)
				( pin "rsvd(139)"
					( attribute "PN" "BK17"
						( Origin gPackager )
					)
					( objectStatus "U5D1.BK17" )
				)
				( pin "rsvd(140)"
					( attribute "PN" "BJ20"
						( Origin gPackager )
					)
					( objectStatus "U5D1.BJ20" )
				)
				( pin "rsvd(141)"
					( attribute "PN" "BJ18"
						( Origin gPackager )
					)
					( objectStatus "U5D1.BJ18" )
				)
				( pin "rsvd(142)"
					( attribute "PN" "BJ16"
						( Origin gPackager )
					)
					( objectStatus "U5D1.BJ16" )
				)
				( pin "rsvd(143)"
					( attribute "PN" "BH19"
						( Origin gPackager )
					)
					( objectStatus "U5D1.BH19" )
				)
				( pin "rsvd(144)"
					( attribute "PN" "BG20"
						( Origin gPackager )
					)
					( objectStatus "U5D1.BG20" )
				)
				( pin "rsvd(145)"
					( attribute "PN" "BG18"
						( Origin gPackager )
					)
					( objectStatus "U5D1.BG18" )
				)
				( pin "rsvd(146)"
					( attribute "PN" "BF21"
						( Origin gPackager )
					)
					( objectStatus "U5D1.BF21" )
				)
				( pin "rsvd(147)"
					( attribute "PN" "BE22"
						( Origin gPackager )
					)
					( objectStatus "U5D1.BE22" )
				)
				( pin "rsvd(148)"
					( attribute "PN" "BE20"
						( Origin gPackager )
					)
					( objectStatus "U5D1.BE20" )
				)
				( pin "rsvd(149)"
					( attribute "PN" "BE18"
						( Origin gPackager )
					)
					( objectStatus "U5D1.BE18" )
				)
				( pin "rsvd(150)"
					( attribute "PN" "BD69"
						( Origin gPackager )
					)
					( objectStatus "U5D1.BD69" )
				)
				( pin "rsvd(151)"
					( attribute "PN" "BD67"
						( Origin gPackager )
					)
					( objectStatus "U5D1.BD67" )
				)
				( pin "rsvd(152)"
					( attribute "PN" "BD65"
						( Origin gPackager )
					)
					( objectStatus "U5D1.BD65" )
				)
				( pin "rsvd(153)"
					( attribute "PN" "BD25"
						( Origin gPackager )
					)
					( objectStatus "U5D1.BD25" )
				)
				( pin "rsvd(154)"
					( attribute "PN" "BD19"
						( Origin gPackager )
					)
					( objectStatus "U5D1.BD19" )
				)
				( pin "rsvd(155)"
					( attribute "PN" "BD17"
						( Origin gPackager )
					)
					( objectStatus "U5D1.BD17" )
				)
				( pin "rsvd(156)"
					( attribute "PN" "BC68"
						( Origin gPackager )
					)
					( objectStatus "U5D1.BC68" )
				)
				( pin "rsvd(157)"
					( attribute "PN" "BC66"
						( Origin gPackager )
					)
					( objectStatus "U5D1.BC66" )
				)
				( pin "rsvd(158)"
					( attribute "PN" "BC64"
						( Origin gPackager )
					)
					( objectStatus "U5D1.BC64" )
				)
				( pin "rsvd(159)"
					( attribute "PN" "BC22"
						( Origin gPackager )
					)
					( objectStatus "U5D1.BC22" )
				)
				( pin "rsvd(160)"
					( attribute "PN" "BC20"
						( Origin gPackager )
					)
					( objectStatus "U5D1.BC20" )
				)
				( pin "rsvd(161)"
					( attribute "PN" "BC18"
						( Origin gPackager )
					)
					( objectStatus "U5D1.BC18" )
				)
				( pin "rsvd(162)"
					( attribute "PN" "BC14"
						( Origin gPackager )
					)
					( objectStatus "U5D1.BC14" )
				)
				( pin "rsvd(163)"
					( attribute "PN" "BB67"
						( Origin gPackager )
					)
					( objectStatus "U5D1.BB67" )
				)
				( pin "rsvd(164)"
					( attribute "PN" "BB65"
						( Origin gPackager )
					)
					( objectStatus "U5D1.BB65" )
				)
				( pin "rsvd(165)"
					( attribute "PN" "BB25"
						( Origin gPackager )
					)
					( objectStatus "U5D1.BB25" )
				)
				( pin "rsvd(166)"
					( attribute "PN" "BB21"
						( Origin gPackager )
					)
					( objectStatus "U5D1.BB21" )
				)
				( pin "rsvd(167)"
					( attribute "PN" "BB17"
						( Origin gPackager )
					)
					( objectStatus "U5D1.BB17" )
				)
				( pin "rsvd(168)"
					( attribute "PN" "BB15"
						( Origin gPackager )
					)
					( objectStatus "U5D1.BB15" )
				)
				( pin "rsvd(169)"
					( attribute "PN" "BB13"
						( Origin gPackager )
					)
					( objectStatus "U5D1.BB13" )
				)
				( pin "rsvd(170)"
					( attribute "PN" "BA82"
						( Origin gPackager )
					)
					( objectStatus "U5D1.BA82" )
				)
				( pin "rsvd(171)"
					( attribute "PN" "BA78"
						( Origin gPackager )
					)
					( objectStatus "U5D1.BA78" )
				)
				( pin "rsvd(172)"
					( attribute "CDS_NOT_ON_SYM" "TRUE"
						( Origin gFrontEnd )
					)
				)
				( pin "rsvd(173)"
					( attribute "CDS_NOT_ON_SYM" "TRUE"
						( Origin gFrontEnd )
					)
				)
				( pin "rsvd(174)"
					( attribute "CDS_NOT_ON_SYM" "TRUE"
						( Origin gFrontEnd )
					)
				)
				( pin "rsvd(175)"
					( attribute "CDS_NOT_ON_SYM" "TRUE"
						( Origin gFrontEnd )
					)
				)
				( pin "rsvd(176)"
					( attribute "CDS_NOT_ON_SYM" "TRUE"
						( Origin gFrontEnd )
					)
				)
				( pin "rsvd(177)"
					( attribute "CDS_NOT_ON_SYM" "TRUE"
						( Origin gFrontEnd )
					)
				)
				( pin "rsvd(178)"
					( attribute "CDS_NOT_ON_SYM" "TRUE"
						( Origin gFrontEnd )
					)
				)
				( pin "rsvd(179)"
					( attribute "CDS_NOT_ON_SYM" "TRUE"
						( Origin gFrontEnd )
					)
				)
				( pin "rsvd(180)"
					( attribute "CDS_NOT_ON_SYM" "TRUE"
						( Origin gFrontEnd )
					)
				)
				( pin "rsvd(181)"
					( attribute "CDS_NOT_ON_SYM" "TRUE"
						( Origin gFrontEnd )
					)
				)
				( pin "rsvd(182)"
					( attribute "CDS_NOT_ON_SYM" "TRUE"
						( Origin gFrontEnd )
					)
				)
				( pin "rsvd(183)"
					( attribute "CDS_NOT_ON_SYM" "TRUE"
						( Origin gFrontEnd )
					)
				)
				( pin "rsvd(184)"
					( attribute "CDS_NOT_ON_SYM" "TRUE"
						( Origin gFrontEnd )
					)
				)
				( pin "rsvd(185)"
					( attribute "CDS_NOT_ON_SYM" "TRUE"
						( Origin gFrontEnd )
					)
				)
				( pin "rsvd(186)"
					( attribute "CDS_NOT_ON_SYM" "TRUE"
						( Origin gFrontEnd )
					)
				)
				( pin "rsvd(187)"
					( attribute "CDS_NOT_ON_SYM" "TRUE"
						( Origin gFrontEnd )
					)
				)
				( pin "rsvd(188)"
					( attribute "CDS_NOT_ON_SYM" "TRUE"
						( Origin gFrontEnd )
					)
				)
				( pin "rsvd(189)"
					( attribute "CDS_NOT_ON_SYM" "TRUE"
						( Origin gFrontEnd )
					)
				)
				( pin "rsvd(190)"
					( attribute "CDS_NOT_ON_SYM" "TRUE"
						( Origin gFrontEnd )
					)
				)
				( pin "rsvd(191)"
					( attribute "CDS_NOT_ON_SYM" "TRUE"
						( Origin gFrontEnd )
					)
				)
				( pin "rsvd(192)"
					( attribute "CDS_NOT_ON_SYM" "TRUE"
						( Origin gFrontEnd )
					)
				)
				( pin "rsvd(193)"
					( attribute "CDS_NOT_ON_SYM" "TRUE"
						( Origin gFrontEnd )
					)
				)
				( pin "rsvd(194)"
					( attribute "CDS_NOT_ON_SYM" "TRUE"
						( Origin gFrontEnd )
					)
				)
				( pin "rsvd(195)"
					( attribute "CDS_NOT_ON_SYM" "TRUE"
						( Origin gFrontEnd )
					)
				)
				( pin "rsvd(196)"
					( attribute "CDS_NOT_ON_SYM" "TRUE"
						( Origin gFrontEnd )
					)
				)
				( pin "rsvd(197)"
					( attribute "CDS_NOT_ON_SYM" "TRUE"
						( Origin gFrontEnd )
					)
				)
				( pin "rsvd(198)"
					( attribute "CDS_NOT_ON_SYM" "TRUE"
						( Origin gFrontEnd )
					)
				)
				( pin "rsvd(199)"
					( attribute "CDS_NOT_ON_SYM" "TRUE"
						( Origin gFrontEnd )
					)
				)
				( pin "rsvd(200)"
					( attribute "CDS_NOT_ON_SYM" "TRUE"
						( Origin gFrontEnd )
					)
				)
				( pin "rsvd(201)"
					( attribute "CDS_NOT_ON_SYM" "TRUE"
						( Origin gFrontEnd )
					)
				)
				( pin "rsvd(202)"
					( attribute "CDS_NOT_ON_SYM" "TRUE"
						( Origin gFrontEnd )
					)
				)
				( pin "rsvd(203)"
					( attribute "CDS_NOT_ON_SYM" "TRUE"
						( Origin gFrontEnd )
					)
				)
				( pin "rsvd(204)"
					( attribute "CDS_NOT_ON_SYM" "TRUE"
						( Origin gFrontEnd )
					)
				)
				( pin "rsvd(205)"
					( attribute "CDS_NOT_ON_SYM" "TRUE"
						( Origin gFrontEnd )
					)
				)
				( pin "rsvd(206)"
					( attribute "CDS_NOT_ON_SYM" "TRUE"
						( Origin gFrontEnd )
					)
				)
				( pin "rsvd(207)"
					( attribute "CDS_NOT_ON_SYM" "TRUE"
						( Origin gFrontEnd )
					)
				)
				( pin "rsvd(208)"
					( attribute "CDS_NOT_ON_SYM" "TRUE"
						( Origin gFrontEnd )
					)
				)
				( pin "rsvd(209)"
					( attribute "CDS_NOT_ON_SYM" "TRUE"
						( Origin gFrontEnd )
					)
				)
				( pin "rsvd(210)"
					( attribute "CDS_NOT_ON_SYM" "TRUE"
						( Origin gFrontEnd )
					)
				)
				( pin "rsvd(211)"
					( attribute "CDS_NOT_ON_SYM" "TRUE"
						( Origin gFrontEnd )
					)
				)
				( pin "rsvd(212)"
					( attribute "CDS_NOT_ON_SYM" "TRUE"
						( Origin gFrontEnd )
					)
				)
				( pin "rsvd(213)"
					( attribute "CDS_NOT_ON_SYM" "TRUE"
						( Origin gFrontEnd )
					)
				)
				( pin "rsvd(214)"
					( attribute "CDS_NOT_ON_SYM" "TRUE"
						( Origin gFrontEnd )
					)
				)
				( pin "rsvd(215)"
					( attribute "CDS_NOT_ON_SYM" "TRUE"
						( Origin gFrontEnd )
					)
				)
				( pin "rsvd(216)"
					( attribute "CDS_NOT_ON_SYM" "TRUE"
						( Origin gFrontEnd )
					)
				)
				( pin "rsvd(217)"
					( attribute "CDS_NOT_ON_SYM" "TRUE"
						( Origin gFrontEnd )
					)
				)
				( pin "rsvd(218)"
					( attribute "CDS_NOT_ON_SYM" "TRUE"
						( Origin gFrontEnd )
					)
				)
				( pin "rsvd(219)"
					( attribute "CDS_NOT_ON_SYM" "TRUE"
						( Origin gFrontEnd )
					)
				)
				( pin "rsvd(220)"
					( attribute "CDS_NOT_ON_SYM" "TRUE"
						( Origin gFrontEnd )
					)
				)
				( pin "rsvd(221)"
					( attribute "CDS_NOT_ON_SYM" "TRUE"
						( Origin gFrontEnd )
					)
				)
				( pin "rsvd(222)"
					( attribute "CDS_NOT_ON_SYM" "TRUE"
						( Origin gFrontEnd )
					)
				)
				( pin "rsvd(223)"
					( attribute "CDS_NOT_ON_SYM" "TRUE"
						( Origin gFrontEnd )
					)
				)
				( pin "rsvd(224)"
					( attribute "CDS_NOT_ON_SYM" "TRUE"
						( Origin gFrontEnd )
					)
				)
				( pin "rsvd(225)"
					( attribute "CDS_NOT_ON_SYM" "TRUE"
						( Origin gFrontEnd )
					)
				)
				( pin "rsvd(226)"
					( attribute "CDS_NOT_ON_SYM" "TRUE"
						( Origin gFrontEnd )
					)
				)
				( pin "rsvd(227)"
					( attribute "CDS_NOT_ON_SYM" "TRUE"
						( Origin gFrontEnd )
					)
				)
				( pin "rsvd(228)"
					( attribute "CDS_NOT_ON_SYM" "TRUE"
						( Origin gFrontEnd )
					)
				)
				( pin "rsvd(229)"
					( attribute "CDS_NOT_ON_SYM" "TRUE"
						( Origin gFrontEnd )
					)
				)
				( pin "rsvd(230)"
					( attribute "CDS_NOT_ON_SYM" "TRUE"
						( Origin gFrontEnd )
					)
				)
				( pin "rsvd(231)"
					( attribute "CDS_NOT_ON_SYM" "TRUE"
						( Origin gFrontEnd )
					)
				)
				( pin "rsvd(232)"
					( attribute "CDS_NOT_ON_SYM" "TRUE"
						( Origin gFrontEnd )
					)
				)
				( pin "rsvd(233)"
					( attribute "CDS_NOT_ON_SYM" "TRUE"
						( Origin gFrontEnd )
					)
				)
				( pin "rsvd(234)"
					( attribute "CDS_NOT_ON_SYM" "TRUE"
						( Origin gFrontEnd )
					)
				)
				( pin "rsvd(235)"
					( attribute "CDS_NOT_ON_SYM" "TRUE"
						( Origin gFrontEnd )
					)
				)
				( pin "rsvd(236)"
					( attribute "CDS_NOT_ON_SYM" "TRUE"
						( Origin gFrontEnd )
					)
				)
				( pin "rsvd(237)"
					( attribute "CDS_NOT_ON_SYM" "TRUE"
						( Origin gFrontEnd )
					)
				)
				( pin "rsvd(238)"
					( attribute "CDS_NOT_ON_SYM" "TRUE"
						( Origin gFrontEnd )
					)
				)
				( pin "rsvd(239)"
					( attribute "CDS_NOT_ON_SYM" "TRUE"
						( Origin gFrontEnd )
					)
				)
				( pin "rsvd(240)"
					( attribute "CDS_NOT_ON_SYM" "TRUE"
						( Origin gFrontEnd )
					)
				)
				( pin "rsvd(241)"
					( attribute "CDS_NOT_ON_SYM" "TRUE"
						( Origin gFrontEnd )
					)
				)
				( pin "rsvd(242)"
					( attribute "CDS_NOT_ON_SYM" "TRUE"
						( Origin gFrontEnd )
					)
				)
				( pin "rsvd(243)"
					( attribute "CDS_NOT_ON_SYM" "TRUE"
						( Origin gFrontEnd )
					)
				)
				( pin "rsvd(244)"
					( attribute "CDS_NOT_ON_SYM" "TRUE"
						( Origin gFrontEnd )
					)
				)
				( pin "rsvd(245)"
					( attribute "CDS_NOT_ON_SYM" "TRUE"
						( Origin gFrontEnd )
					)
				)
				( pin "rsvd(246)"
					( attribute "CDS_NOT_ON_SYM" "TRUE"
						( Origin gFrontEnd )
					)
				)
				( pin "rsvd(247)"
					( attribute "CDS_NOT_ON_SYM" "TRUE"
						( Origin gFrontEnd )
					)
				)
				( pin "rsvd(248)"
					( attribute "CDS_NOT_ON_SYM" "TRUE"
						( Origin gFrontEnd )
					)
				)
				( pin "rsvd(249)"
					( attribute "CDS_NOT_ON_SYM" "TRUE"
						( Origin gFrontEnd )
					)
				)
				( pin "rsvd(250)"
					( attribute "CDS_NOT_ON_SYM" "TRUE"
						( Origin gFrontEnd )
					)
				)
				( pin "rsvd(251)"
					( attribute "CDS_NOT_ON_SYM" "TRUE"
						( Origin gFrontEnd )
					)
				)
				( pin "rsvd(252)"
					( attribute "CDS_NOT_ON_SYM" "TRUE"
						( Origin gFrontEnd )
					)
				)
				( pin "rsvd(253)"
					( attribute "CDS_NOT_ON_SYM" "TRUE"
						( Origin gFrontEnd )
					)
				)
				( pin "rsvd(254)"
					( attribute "CDS_NOT_ON_SYM" "TRUE"
						( Origin gFrontEnd )
					)
				)
				( pin "rsvd(255)"
					( attribute "PN" "AY83"
						( Origin gPackager )
					)
					( objectStatus "U5D1.AY83" )
				)
			)
			( gate "@baseboard_fab2_lib.baseboard_fab2(sch_1):page36_i16"
				( attribute "CDS_LIB" "chpset_lib"
					( Origin gPackager )
				)
				( attribute "CDS_LOCATION" "U5D1"
					( Origin gPackager )
				)
				( attribute "CDS_SEC" "17"
					( Origin gPackager )
				)
				( attribute "LOCATION" "U5D1"
					( Origin gFrontEnd )
				)
				( attribute "MATERIAL" "IC"
					( Origin gFrontEnd )
				)
				( attribute "PACK_TYPE" "BGA1"
					( Origin gFrontEnd )
				)
				( attribute "PART_NUMBER" "TBD"
					( Origin gFrontEnd )
				)
				( attribute "PHYS_PAGE" "36"
					( Origin gFrontEnd )
				)
				( attribute "ROOM" "CPU0"
					( Origin gFrontEnd )
				)
				( attribute "ROT" "0"
					( Origin gFrontEnd )
				)
				( attribute "SEC" "17"
					( Origin gFrontEnd )
				)
				( attribute "SEC_TYPE" "BGA1"
					( Origin gFrontEnd )
				)
				( attribute "VER" "17"
					( Origin gFrontEnd )
				)
				( attribute "XY" "(-2550,2525)"
					( Origin gFrontEnd )
				)
				( attribute "CHIPS_PART_NAME" "SKX_EXT_B"
					( Origin gPackager )
				)
				( attribute "CDS_PART_NAME" "SKX_EXT_B_BGA1-IC,TBD"
					( Origin gPackager )
				)
				( objectStatus "U5D1" )
				( pin "rsvd(81)"
					( attribute "PN" "CL24"
						( Origin gPackager )
					)
					( objectStatus "U5D1.CL24" )
				)
				( pin "rsvd(82)"
					( attribute "PN" "CK77"
						( Origin gPackager )
					)
					( objectStatus "U5D1.CK77" )
				)
				( pin "rsvd(83)"
					( attribute "PN" "CK25"
						( Origin gPackager )
					)
					( objectStatus "U5D1.CK25" )
				)
				( pin "rsvd(84)"
					( attribute "PN" "CK23"
						( Origin gPackager )
					)
					( objectStatus "U5D1.CK23" )
				)
				( pin "rsvd(85)"
					( attribute "PN" "CK19"
						( Origin gPackager )
					)
					( objectStatus "U5D1.CK19" )
				)
				( pin "rsvd(86)"
					( attribute "PN" "CJ26"
						( Origin gPackager )
					)
					( objectStatus "U5D1.CJ26" )
				)
				( pin "rsvd(87)"
					( attribute "PN" "CJ24"
						( Origin gPackager )
					)
					( objectStatus "U5D1.CJ24" )
				)
				( pin "rsvd(88)"
					( attribute "PN" "CJ22"
						( Origin gPackager )
					)
					( objectStatus "U5D1.CJ22" )
				)
				( pin "rsvd(89)"
					( attribute "PN" "CJ20"
						( Origin gPackager )
					)
					( objectStatus "U5D1.CJ20" )
				)
				( pin "rsvd(90)"
					( attribute "PN" "CH77"
						( Origin gPackager )
					)
					( objectStatus "U5D1.CH77" )
				)
				( pin "rsvd(91)"
					( attribute "PN" "CH25"
						( Origin gPackager )
					)
					( objectStatus "U5D1.CH25" )
				)
				( pin "test_6"
					( attribute "PN" "AR16"
						( Origin gPackager )
					)
					( objectStatus "U5D1.AR16" )
				)
				( pin "test_7"
					( attribute "PN" "AU18"
						( Origin gPackager )
					)
					( objectStatus "U5D1.AU18" )
				)
				( pin "test_8"
					( attribute "PN" "AW16"
						( Origin gPackager )
					)
					( objectStatus "U5D1.AW16" )
				)
				( pin "test_9"
					( attribute "PN" "AW20"
						( Origin gPackager )
					)
					( objectStatus "U5D1.AW20" )
				)
				( pin "test_10"
					( attribute "PN" "AW22"
						( Origin gPackager )
					)
					( objectStatus "U5D1.AW22" )
				)
			)
			( gate "@baseboard_fab2_lib.baseboard_fab2(sch_1):page37_i303"
				( attribute "BOM_COST" "PROC_SOCKET"
					( Origin gFrontEnd )
				)
				( attribute "CDS_LIB" "mstr_discrete"
					( Origin gPackager )
				)
				( attribute "CDS_LOCATION" "R5D5"
					( Origin gPackager )
				)
				( attribute "CDS_SEC" "1"
					( Origin gPackager )
				)
				( attribute "LOCATION" "R5D5"
					( Origin gFrontEnd )
				)
				( attribute "MATERIAL" "CHIP"
					( Origin gFrontEnd )
				)
				( attribute "PACK_TYPE" "0402"
					( Origin gFrontEnd )
				)
				( attribute "PART_NUMBER" "G85996-031"
					( Origin gFrontEnd )
				)
				( attribute "PHYS_PAGE" "37"
					( Origin gFrontEnd )
				)
				( attribute "ROOM" "CPU0"
					( Origin gFrontEnd )
				)
				( attribute "ROT" "0"
					( Origin gFrontEnd )
				)
				( attribute "SEC" "1"
					( Origin gFrontEnd )
				)
				( attribute "SEC_TYPE" "0402"
					( Origin gFrontEnd )
				)
				( attribute "TOLERANCE" "0.1%"
					( Origin gFrontEnd )
				)
				( attribute "VALUE" "249"
					( Origin gFrontEnd )
				)
				( attribute "VER" "2"
					( Origin gFrontEnd )
				)
				( attribute "WATTAGE" "1/16W"
					( Origin gFrontEnd )
				)
				( attribute "XY" "(-375,750)"
					( Origin gFrontEnd )
				)
				( attribute "CHIPS_PART_NAME" "RES"
					( Origin gPackager )
				)
				( attribute "CDS_PART_NAME" "RES_0402-249,0.1%,1/16W,CHIP,GA"
					( Origin gPackager )
				)
				( objectStatus "R5D5" )
				( pin "a"
					( attribute "PN" "1"
						( Origin gPackager )
					)
					( objectStatus "R5D5.1" )
				)
				( pin "b"
					( attribute "PN" "2"
						( Origin gPackager )
					)
					( objectStatus "R5D5.2" )
				)
			)
			( gate "@baseboard_fab2_lib.baseboard_fab2(sch_1):page37_i309"
				( attribute "BOM_COST" "PROC_SOCKET"
					( Origin gFrontEnd )
				)
				( attribute "CDS_LIB" "mstr_discrete"
					( Origin gPackager )
				)
				( attribute "CDS_LOCATION" "R5P1"
					( Origin gPackager )
				)
				( attribute "CDS_SEC" "1"
					( Origin gPackager )
				)
				( attribute "LOCATION" "R5P1"
					( Origin gFrontEnd )
				)
				( attribute "MATERIAL" "CHIP"
					( Origin gFrontEnd )
				)
				( attribute "PACK_TYPE" "0603"
					( Origin gFrontEnd )
				)
				( attribute "PART_NUMBER" "G22026-050"
					( Origin gFrontEnd )
				)
				( attribute "PHYS_PAGE" "37"
					( Origin gFrontEnd )
				)
				( attribute "ROOM" "CPU0"
					( Origin gFrontEnd )
				)
				( attribute "ROT" "0"
					( Origin gFrontEnd )
				)
				( attribute "SEC" "1"
					( Origin gFrontEnd )
				)
				( attribute "SEC_TYPE" "0603"
					( Origin gFrontEnd )
				)
				( attribute "TOLERANCE" "1%"
					( Origin gFrontEnd )
				)
				( attribute "VALUE" "100.0K"
					( Origin gFrontEnd )
				)
				( attribute "VER" "2"
					( Origin gFrontEnd )
				)
				( attribute "WATTAGE" "1/10W"
					( Origin gFrontEnd )
				)
				( attribute "XY" "(-775,1350)"
					( Origin gFrontEnd )
				)
				( attribute "CHIPS_PART_NAME" "RES"
					( Origin gPackager )
				)
				( attribute "CDS_PART_NAME" "RES_0603-100.0K,1%,1/10W,CHIP,A"
					( Origin gPackager )
				)
				( objectStatus "R5P1" )
				( pin "a"
					( attribute "PN" "1"
						( Origin gPackager )
					)
					( objectStatus "R5P1.1" )
				)
				( pin "b"
					( attribute "PN" "2"
						( Origin gPackager )
					)
					( objectStatus "R5P1.2" )
				)
			)
			( gate "@baseboard_fab2_lib.baseboard_fab2(sch_1):page37_i310"
				( attribute "CDS_LIB" "chpset_lib"
					( Origin gPackager )
				)
				( attribute "CDS_LOCATION" "U5D1"
					( Origin gPackager )
				)
				( attribute "CDS_SEC" "18"
					( Origin gPackager )
				)
				( attribute "LOCATION" "U5D1"
					( Origin gFrontEnd )
				)
				( attribute "MATERIAL" "IC"
					( Origin gFrontEnd )
				)
				( attribute "PACK_TYPE" "BGA1"
					( Origin gFrontEnd )
				)
				( attribute "PART_NUMBER" "TBD"
					( Origin gFrontEnd )
				)
				( attribute "PHYS_PAGE" "37"
					( Origin gFrontEnd )
				)
				( attribute "ROOM" "CPU0"
					( Origin gFrontEnd )
				)
				( attribute "ROT" "0"
					( Origin gFrontEnd )
				)
				( attribute "SEC" "18"
					( Origin gFrontEnd )
				)
				( attribute "SEC_TYPE" "BGA1"
					( Origin gFrontEnd )
				)
				( attribute "VER" "18"
					( Origin gFrontEnd )
				)
				( attribute "XY" "(-6200,2475)"
					( Origin gFrontEnd )
				)
				( attribute "CHIPS_PART_NAME" "SKX_EXT_B"
					( Origin gPackager )
				)
				( attribute "CDS_PART_NAME" "SKX_EXT_B_BGA1-IC,TBD"
					( Origin gPackager )
				)
				( objectStatus "U5D1" )
				( pin "vccin(130)"
					( attribute "PN" "BN78"
						( Origin gPackager )
					)
					( objectStatus "U5D1.BN78" )
				)
				( pin "vccin(131)"
					( attribute "PN" "BN76"
						( Origin gPackager )
					)
					( objectStatus "U5D1.BN76" )
				)
				( pin "vccin(132)"
					( attribute "PN" "BN74"
						( Origin gPackager )
					)
					( objectStatus "U5D1.BN74" )
				)
				( pin "vccin(133)"
					( attribute "PN" "BN72"
						( Origin gPackager )
					)
					( objectStatus "U5D1.BN72" )
				)
				( pin "vccin(134)"
					( attribute "PN" "BN70"
						( Origin gPackager )
					)
					( objectStatus "U5D1.BN70" )
				)
				( pin "vccin(135)"
					( attribute "PN" "BN68"
						( Origin gPackager )
					)
					( objectStatus "U5D1.BN68" )
				)
				( pin "vccin(136)"
					( attribute "PN" "BN66"
						( Origin gPackager )
					)
					( objectStatus "U5D1.BN66" )
				)
				( pin "vccin(137)"
					( attribute "PN" "BN64"
						( Origin gPackager )
					)
					( objectStatus "U5D1.BN64" )
				)
				( pin "vccin(138)"
					( attribute "PN" "BN62"
						( Origin gPackager )
					)
					( objectStatus "U5D1.BN62" )
				)
				( pin "vccin(139)"
					( attribute "PN" "BN60"
						( Origin gPackager )
					)
					( objectStatus "U5D1.BN60" )
				)
				( pin "vccin(140)"
					( attribute "PN" "BM83"
						( Origin gPackager )
					)
					( objectStatus "U5D1.BM83" )
				)
				( pin "vccin(141)"
					( attribute "PN" "BM81"
						( Origin gPackager )
					)
					( objectStatus "U5D1.BM81" )
				)
				( pin "vccin(142)"
					( attribute "PN" "BM79"
						( Origin gPackager )
					)
					( objectStatus "U5D1.BM79" )
				)
				( pin "vccin(143)"
					( attribute "PN" "BM77"
						( Origin gPackager )
					)
					( objectStatus "U5D1.BM77" )
				)
				( pin "vccin(144)"
					( attribute "PN" "BM75"
						( Origin gPackager )
					)
					( objectStatus "U5D1.BM75" )
				)
				( pin "vccin(145)"
					( attribute "PN" "BM73"
						( Origin gPackager )
					)
					( objectStatus "U5D1.BM73" )
				)
				( pin "vccin(146)"
					( attribute "PN" "BM71"
						( Origin gPackager )
					)
					( objectStatus "U5D1.BM71" )
				)
				( pin "vccin(147)"
					( attribute "PN" "BM69"
						( Origin gPackager )
					)
					( objectStatus "U5D1.BM69" )
				)
				( pin "vccin(148)"
					( attribute "PN" "BM67"
						( Origin gPackager )
					)
					( objectStatus "U5D1.BM67" )
				)
				( pin "vccin(149)"
					( attribute "PN" "BM65"
						( Origin gPackager )
					)
					( objectStatus "U5D1.BM65" )
				)
				( pin "vccin(150)"
					( attribute "PN" "BM63"
						( Origin gPackager )
					)
					( objectStatus "U5D1.BM63" )
				)
				( pin "vccin(151)"
					( attribute "PN" "BM61"
						( Origin gPackager )
					)
					( objectStatus "U5D1.BM61" )
				)
				( pin "vccin(152)"
					( attribute "PN" "BL84"
						( Origin gPackager )
					)
					( objectStatus "U5D1.BL84" )
				)
				( pin "vccin(153)"
					( attribute "PN" "BL62"
						( Origin gPackager )
					)
					( objectStatus "U5D1.BL62" )
				)
				( pin "vccin(154)"
					( attribute "PN" "BL60"
						( Origin gPackager )
					)
					( objectStatus "U5D1.BL60" )
				)
				( pin "vccin(155)"
					( attribute "PN" "BK83"
						( Origin gPackager )
					)
					( objectStatus "U5D1.BK83" )
				)
				( pin "vccin(156)"
					( attribute "PN" "BK81"
						( Origin gPackager )
					)
					( objectStatus "U5D1.BK81" )
				)
				( pin "vccin(157)"
					( attribute "PN" "BK79"
						( Origin gPackager )
					)
					( objectStatus "U5D1.BK79" )
				)
				( pin "vccin(158)"
					( attribute "PN" "BK77"
						( Origin gPackager )
					)
					( objectStatus "U5D1.BK77" )
				)
				( pin "vccin(159)"
					( attribute "PN" "BK75"
						( Origin gPackager )
					)
					( objectStatus "U5D1.BK75" )
				)
				( pin "vccin(160)"
					( attribute "PN" "BK73"
						( Origin gPackager )
					)
					( objectStatus "U5D1.BK73" )
				)
				( pin "vccin(161)"
					( attribute "PN" "BK71"
						( Origin gPackager )
					)
					( objectStatus "U5D1.BK71" )
				)
				( pin "vccin(162)"
					( attribute "PN" "BK69"
						( Origin gPackager )
					)
					( objectStatus "U5D1.BK69" )
				)
				( pin "vccin(163)"
					( attribute "PN" "BK67"
						( Origin gPackager )
					)
					( objectStatus "U5D1.BK67" )
				)
				( pin "vccin(164)"
					( attribute "PN" "BK65"
						( Origin gPackager )
					)
					( objectStatus "U5D1.BK65" )
				)
				( pin "vccin(165)"
					( attribute "PN" "BK63"
						( Origin gPackager )
					)
					( objectStatus "U5D1.BK63" )
				)
				( pin "vccin(166)"
					( attribute "PN" "BK61"
						( Origin gPackager )
					)
					( objectStatus "U5D1.BK61" )
				)
				( pin "vccin(167)"
					( attribute "PN" "BJ84"
						( Origin gPackager )
					)
					( objectStatus "U5D1.BJ84" )
				)
				( pin "vccin(168)"
					( attribute "PN" "BJ82"
						( Origin gPackager )
					)
					( objectStatus "U5D1.BJ82" )
				)
				( pin "vccin(169)"
					( attribute "PN" "BJ80"
						( Origin gPackager )
					)
					( objectStatus "U5D1.BJ80" )
				)
				( pin "vccin(170)"
					( attribute "PN" "BJ78"
						( Origin gPackager )
					)
					( objectStatus "U5D1.BJ78" )
				)
				( pin "vccin(171)"
					( attribute "PN" "BJ76"
						( Origin gPackager )
					)
					( objectStatus "U5D1.BJ76" )
				)
				( pin "vccin(172)"
					( attribute "PN" "BJ74"
						( Origin gPackager )
					)
					( objectStatus "U5D1.BJ74" )
				)
				( pin "vccin(173)"
					( attribute "PN" "BJ72"
						( Origin gPackager )
					)
					( objectStatus "U5D1.BJ72" )
				)
				( pin "vccin(174)"
					( attribute "PN" "BJ70"
						( Origin gPackager )
					)
					( objectStatus "U5D1.BJ70" )
				)
				( pin "vccin(175)"
					( attribute "PN" "BJ68"
						( Origin gPackager )
					)
					( objectStatus "U5D1.BJ68" )
				)
				( pin "vccin(176)"
					( attribute "PN" "BJ66"
						( Origin gPackager )
					)
					( objectStatus "U5D1.BJ66" )
				)
				( pin "vccin(177)"
					( attribute "PN" "BJ64"
						( Origin gPackager )
					)
					( objectStatus "U5D1.BJ64" )
				)
				( pin "vccin(178)"
					( attribute "PN" "BJ62"
						( Origin gPackager )
					)
					( objectStatus "U5D1.BJ62" )
				)
				( pin "vccin(179)"
					( attribute "PN" "BJ60"
						( Origin gPackager )
					)
					( objectStatus "U5D1.BJ60" )
				)
				( pin "vccin(180)"
					( attribute "PN" "BH83"
						( Origin gPackager )
					)
					( objectStatus "U5D1.BH83" )
				)
				( pin "vccin(181)"
					( attribute "PN" "BH81"
						( Origin gPackager )
					)
					( objectStatus "U5D1.BH81" )
				)
				( pin "vccin(182)"
					( attribute "PN" "BH79"
						( Origin gPackager )
					)
					( objectStatus "U5D1.BH79" )
				)
				( pin "vccin(183)"
					( attribute "PN" "BH77"
						( Origin gPackager )
					)
					( objectStatus "U5D1.BH77" )
				)
				( pin "vccin(184)"
					( attribute "PN" "BH75"
						( Origin gPackager )
					)
					( objectStatus "U5D1.BH75" )
				)
				( pin "vccin(185)"
					( attribute "PN" "BH73"
						( Origin gPackager )
					)
					( objectStatus "U5D1.BH73" )
				)
				( pin "vccin(186)"
					( attribute "PN" "BH71"
						( Origin gPackager )
					)
					( objectStatus "U5D1.BH71" )
				)
				( pin "vccin(187)"
					( attribute "PN" "BH69"
						( Origin gPackager )
					)
					( objectStatus "U5D1.BH69" )
				)
				( pin "vccin(188)"
					( attribute "PN" "BH67"
						( Origin gPackager )
					)
					( objectStatus "U5D1.BH67" )
				)
				( pin "vccin(189)"
					( attribute "PN" "BH65"
						( Origin gPackager )
					)
					( objectStatus "U5D1.BH65" )
				)
				( pin "vccin(190)"
					( attribute "PN" "BH63"
						( Origin gPackager )
					)
					( objectStatus "U5D1.BH63" )
				)
				( pin "vccin(191)"
					( attribute "PN" "BH61"
						( Origin gPackager )
					)
					( objectStatus "U5D1.BH61" )
				)
				( pin "vccin(192)"
					( attribute "PN" "BG84"
						( Origin gPackager )
					)
					( objectStatus "U5D1.BG84" )
				)
				( pin "vccin(193)"
					( attribute "PN" "BG70"
						( Origin gPackager )
					)
					( objectStatus "U5D1.BG70" )
				)
				( pin "vccin(194)"
					( attribute "PN" "BG68"
						( Origin gPackager )
					)
					( objectStatus "U5D1.BG68" )
				)
				( pin "vccin(195)"
					( attribute "PN" "BG66"
						( Origin gPackager )
					)
					( objectStatus "U5D1.BG66" )
				)
				( pin "vccin(196)"
					( attribute "PN" "BG64"
						( Origin gPackager )
					)
					( objectStatus "U5D1.BG64" )
				)
				( pin "vccin(197)"
					( attribute "PN" "BG62"
						( Origin gPackager )
					)
					( objectStatus "U5D1.BG62" )
				)
				( pin "vccin(198)"
					( attribute "PN" "BG60"
						( Origin gPackager )
					)
					( objectStatus "U5D1.BG60" )
				)
				( pin "vccin(199)"
					( attribute "PN" "BF85"
						( Origin gPackager )
					)
					( objectStatus "U5D1.BF85" )
				)
				( pin "vccin(200)"
					( attribute "PN" "BF83"
						( Origin gPackager )
					)
					( objectStatus "U5D1.BF83" )
				)
				( pin "vccin(201)"
					( attribute "PN" "BF81"
						( Origin gPackager )
					)
					( objectStatus "U5D1.BF81" )
				)
				( pin "vccin(202)"
					( attribute "PN" "BF79"
						( Origin gPackager )
					)
					( objectStatus "U5D1.BF79" )
				)
				( pin "vccin(203)"
					( attribute "PN" "BF77"
						( Origin gPackager )
					)
					( objectStatus "U5D1.BF77" )
				)
				( pin "vccin(204)"
					( attribute "PN" "BF75"
						( Origin gPackager )
					)
					( objectStatus "U5D1.BF75" )
				)
				( pin "vccin(205)"
					( attribute "PN" "BF73"
						( Origin gPackager )
					)
					( objectStatus "U5D1.BF73" )
				)
				( pin "vccin(206)"
					( attribute "PN" "BF61"
						( Origin gPackager )
					)
					( objectStatus "U5D1.BF61" )
				)
				( pin "vccin(207)"
					( attribute "PN" "BE84"
						( Origin gPackager )
					)
					( objectStatus "U5D1.BE84" )
				)
				( pin "vccin(208)"
					( attribute "PN" "BE82"
						( Origin gPackager )
					)
					( objectStatus "U5D1.BE82" )
				)
				( pin "vccin(209)"
					( attribute "PN" "BE80"
						( Origin gPackager )
					)
					( objectStatus "U5D1.BE80" )
				)
				( pin "vccin(210)"
					( attribute "PN" "BE78"
						( Origin gPackager )
					)
					( objectStatus "U5D1.BE78" )
				)
				( pin "vccin(211)"
					( attribute "PN" "BE76"
						( Origin gPackager )
					)
					( objectStatus "U5D1.BE76" )
				)
				( pin "vccin(212)"
					( attribute "PN" "BE74"
						( Origin gPackager )
					)
					( objectStatus "U5D1.BE74" )
				)
				( pin "vccin(213)"
					( attribute "PN" "BE72"
						( Origin gPackager )
					)
					( objectStatus "U5D1.BE72" )
				)
				( pin "vccin(214)"
					( attribute "PN" "BE62"
						( Origin gPackager )
					)
					( objectStatus "U5D1.BE62" )
				)
				( pin "vccin(215)"
					( attribute "PN" "BE60"
						( Origin gPackager )
					)
					( objectStatus "U5D1.BE60" )
				)
				( pin "vccin(216)"
					( attribute "PN" "BD85"
						( Origin gPackager )
					)
					( objectStatus "U5D1.BD85" )
				)
				( pin "vccin(217)"
					( attribute "PN" "BD83"
						( Origin gPackager )
					)
					( objectStatus "U5D1.BD83" )
				)
				( pin "vccin(218)"
					( attribute "PN" "BD81"
						( Origin gPackager )
					)
					( objectStatus "U5D1.BD81" )
				)
				( pin "vccin(219)"
					( attribute "PN" "BD79"
						( Origin gPackager )
					)
					( objectStatus "U5D1.BD79" )
				)
				( pin "vccin(220)"
					( attribute "PN" "BD77"
						( Origin gPackager )
					)
					( objectStatus "U5D1.BD77" )
				)
				( pin "vccin(221)"
					( attribute "PN" "BD75"
						( Origin gPackager )
					)
					( objectStatus "U5D1.BD75" )
				)
				( pin "vccin(222)"
					( attribute "PN" "BD73"
						( Origin gPackager )
					)
					( objectStatus "U5D1.BD73" )
				)
				( pin "vccin(223)"
					( attribute "PN" "BD61"
						( Origin gPackager )
					)
					( objectStatus "U5D1.BD61" )
				)
				( pin "vccin(224)"
					( attribute "PN" "BC84"
						( Origin gPackager )
					)
					( objectStatus "U5D1.BC84" )
				)
				( pin "vccin(225)"
					( attribute "PN" "BC62"
						( Origin gPackager )
					)
					( objectStatus "U5D1.BC62" )
				)
				( pin "vccin(226)"
					( attribute "PN" "BC60"
						( Origin gPackager )
					)
					( objectStatus "U5D1.BC60" )
				)
				( pin "vccin(227)"
					( attribute "PN" "BB85"
						( Origin gPackager )
					)
					( objectStatus "U5D1.BB85" )
				)
				( pin "vccin(228)"
					( attribute "PN" "BB61"
						( Origin gPackager )
					)
					( objectStatus "U5D1.BB61" )
				)
				( pin "vccin(229)"
					( attribute "PN" "BA60"
						( Origin gPackager )
					)
					( objectStatus "U5D1.BA60" )
				)
				( pin "vccin(230)"
					( attribute "PN" "AY61"
						( Origin gPackager )
					)
					( objectStatus "U5D1.AY61" )
				)
				( pin "vccin(231)"
					( attribute "PN" "AW60"
						( Origin gPackager )
					)
					( objectStatus "U5D1.AW60" )
				)
				( pin "vccin(232)"
					( attribute "PN" "AV61"
						( Origin gPackager )
					)
					( objectStatus "U5D1.AV61" )
				)
				( pin "vccin(233)"
					( attribute "PN" "AV59"
						( Origin gPackager )
					)
					( objectStatus "U5D1.AV59" )
				)
				( pin "vccin(234)"
					( attribute "PN" "AU60"
						( Origin gPackager )
					)
					( objectStatus "U5D1.AU60" )
				)
				( pin "vccin(235)"
					( attribute "PN" "AU58"
						( Origin gPackager )
					)
					( objectStatus "U5D1.AU58" )
				)
				( pin "vccin(236)"
					( attribute "PN" "AT59"
						( Origin gPackager )
					)
					( objectStatus "U5D1.AT59" )
				)
				( pin "vccin(237)"
					( attribute "PN" "AT57"
						( Origin gPackager )
					)
					( objectStatus "U5D1.AT57" )
				)
				( pin "vccin(238)"
					( attribute "PN" "AR58"
						( Origin gPackager )
					)
					( objectStatus "U5D1.AR58" )
				)
				( pin "vccin(239)"
					( attribute "PN" "AR56"
						( Origin gPackager )
					)
					( objectStatus "U5D1.AR56" )
				)
				( pin "vccin(240)"
					( attribute "PN" "AP57"
						( Origin gPackager )
					)
					( objectStatus "U5D1.AP57" )
				)
				( pin "vccin(241)"
					( attribute "PN" "AP55"
						( Origin gPackager )
					)
					( objectStatus "U5D1.AP55" )
				)
				( pin "vccin(242)"
					( attribute "PN" "AN56"
						( Origin gPackager )
					)
					( objectStatus "U5D1.AN56" )
				)
				( pin "vccin(243)"
					( attribute "PN" "AN54"
						( Origin gPackager )
					)
					( objectStatus "U5D1.AN54" )
				)
				( pin "vccin(244)"
					( attribute "PN" "AN32"
						( Origin gPackager )
					)
					( objectStatus "U5D1.AN32" )
				)
				( pin "vccin(245)"
					( attribute "PN" "AM55"
						( Origin gPackager )
					)
					( objectStatus "U5D1.AM55" )
				)
				( pin "vccin(246)"
					( attribute "PN" "AM53"
						( Origin gPackager )
					)
					( objectStatus "U5D1.AM53" )
				)
				( pin "vccin(247)"
					( attribute "PN" "AM33"
						( Origin gPackager )
					)
					( objectStatus "U5D1.AM33" )
				)
				( pin "vccin(248)"
					( attribute "PN" "AL54"
						( Origin gPackager )
					)
					( objectStatus "U5D1.AL54" )
				)
				( pin "vccin(249)"
					( attribute "PN" "AL52"
						( Origin gPackager )
					)
					( objectStatus "U5D1.AL52" )
				)
				( pin "vccin(250)"
					( attribute "PN" "AL50"
						( Origin gPackager )
					)
					( objectStatus "U5D1.AL50" )
				)
				( pin "vccin(251)"
					( attribute "PN" "AL48"
						( Origin gPackager )
					)
					( objectStatus "U5D1.AL48" )
				)
				( pin "vccin(252)"
					( attribute "PN" "AL46"
						( Origin gPackager )
					)
					( objectStatus "U5D1.AL46" )
				)
				( pin "vccin(253)"
					( attribute "PN" "AL34"
						( Origin gPackager )
					)
					( objectStatus "U5D1.AL34" )
				)
				( pin "vccin(254)"
					( attribute "PN" "AK53"
						( Origin gPackager )
					)
					( objectStatus "U5D1.AK53" )
				)
				( pin "vccin(255)"
					( attribute "PN" "AK51"
						( Origin gPackager )
					)
					( objectStatus "U5D1.AK51" )
				)
				( pin "vccin(256)"
					( attribute "PN" "AK49"
						( Origin gPackager )
					)
					( objectStatus "U5D1.AK49" )
				)
				( pin "vccin(257)"
					( attribute "PN" "AK47"
						( Origin gPackager )
					)
					( objectStatus "U5D1.AK47" )
				)
				( pin "vccin(258)"
					( attribute "PN" "AK45"
						( Origin gPackager )
					)
					( objectStatus "U5D1.AK45" )
				)
				( pin "vccin(259)"
					( attribute "PN" "AK35"
						( Origin gPackager )
					)
					( objectStatus "U5D1.AK35" )
				)
				( pin "vccin(260)"
					( attribute "PN" "AJ36"
						( Origin gPackager )
					)
					( objectStatus "U5D1.AJ36" )
				)
				( pin "vccin(261)"
					( attribute "PN" "AH41"
						( Origin gPackager )
					)
					( objectStatus "U5D1.AH41" )
				)
				( pin "vccin(262)"
					( attribute "PN" "AH39"
						( Origin gPackager )
					)
					( objectStatus "U5D1.AH39" )
				)
				( pin "vccin(263)"
					( attribute "PN" "AH37"
						( Origin gPackager )
					)
					( objectStatus "U5D1.AH37" )
				)
				( pin "vccin(264)"
					( attribute "PN" "AG42"
						( Origin gPackager )
					)
					( objectStatus "U5D1.AG42" )
				)
				( pin "vccin(265)"
					( attribute "PN" "AG40"
						( Origin gPackager )
					)
					( objectStatus "U5D1.AG40" )
				)
				( pin "vccin(266)"
					( attribute "PN" "AG38"
						( Origin gPackager )
					)
					( objectStatus "U5D1.AG38" )
				)
				( pin "vccin(267)"
					( attribute "PN" "AF43"
						( Origin gPackager )
					)
					( objectStatus "U5D1.AF43" )
				)
			)
			( gate "@baseboard_fab2_lib.baseboard_fab2(sch_1):page37_i311"
				( attribute "CDS_LIB" "chpset_lib"
					( Origin gPackager )
				)
				( attribute "CDS_LOCATION" "U5D1"
					( Origin gPackager )
				)
				( attribute "CDS_SEC" "19"
					( Origin gPackager )
				)
				( attribute "LOCATION" "U5D1"
					( Origin gFrontEnd )
				)
				( attribute "MATERIAL" "IC"
					( Origin gFrontEnd )
				)
				( attribute "PACK_TYPE" "BGA1"
					( Origin gFrontEnd )
				)
				( attribute "PART_NUMBER" "TBD"
					( Origin gFrontEnd )
				)
				( attribute "PHYS_PAGE" "37"
					( Origin gFrontEnd )
				)
				( attribute "ROOM" "CPU0"
					( Origin gFrontEnd )
				)
				( attribute "ROT" "0"
					( Origin gFrontEnd )
				)
				( attribute "SEC" "19"
					( Origin gFrontEnd )
				)
				( attribute "SEC_TYPE" "BGA1"
					( Origin gFrontEnd )
				)
				( attribute "VER" "19"
					( Origin gFrontEnd )
				)
				( attribute "XY" "(-2425,2475)"
					( Origin gFrontEnd )
				)
				( attribute "CHIPS_PART_NAME" "SKX_EXT_B"
					( Origin gPackager )
				)
				( attribute "CDS_PART_NAME" "SKX_EXT_B_BGA1-IC,TBD"
					( Origin gPackager )
				)
				( objectStatus "U5D1" )
				( pin "vccin(0)"
					( attribute "PN" "CY49"
						( Origin gPackager )
					)
					( objectStatus "U5D1.CY49" )
				)
				( pin "vccin(1)"
					( attribute "PN" "CY47"
						( Origin gPackager )
					)
					( objectStatus "U5D1.CY47" )
				)
				( pin "vccin(2)"
					( attribute "PN" "CW50"
						( Origin gPackager )
					)
					( objectStatus "U5D1.CW50" )
				)
				( pin "vccin(3)"
					( attribute "PN" "CW48"
						( Origin gPackager )
					)
					( objectStatus "U5D1.CW48" )
				)
				( pin "vccin(4)"
					( attribute "PN" "CW46"
						( Origin gPackager )
					)
					( objectStatus "U5D1.CW46" )
				)
				( pin "vccin(5)"
					( attribute "PN" "CV51"
						( Origin gPackager )
					)
					( objectStatus "U5D1.CV51" )
				)
				( pin "vccin(6)"
					( attribute "PN" "CU54"
						( Origin gPackager )
					)
					( objectStatus "U5D1.CU54" )
				)
				( pin "vccin(7)"
					( attribute "PN" "CU52"
						( Origin gPackager )
					)
					( objectStatus "U5D1.CU52" )
				)
				( pin "vccin(8)"
					( attribute "PN" "CU42"
						( Origin gPackager )
					)
					( objectStatus "U5D1.CU42" )
				)
				( pin "vccin(9)"
					( attribute "PN" "CU40"
						( Origin gPackager )
					)
					( objectStatus "U5D1.CU40" )
				)
				( pin "vccin(10)"
					( attribute "PN" "CU38"
						( Origin gPackager )
					)
					( objectStatus "U5D1.CU38" )
				)
				( pin "vccin(11)"
					( attribute "PN" "CT55"
						( Origin gPackager )
					)
					( objectStatus "U5D1.CT55" )
				)
				( pin "vccin(12)"
					( attribute "PN" "CT53"
						( Origin gPackager )
					)
					( objectStatus "U5D1.CT53" )
				)
				( pin "vccin(13)"
					( attribute "PN" "CT41"
						( Origin gPackager )
					)
					( objectStatus "U5D1.CT41" )
				)
				( pin "vccin(14)"
					( attribute "PN" "CT39"
						( Origin gPackager )
					)
					( objectStatus "U5D1.CT39" )
				)
				( pin "vccin(15)"
					( attribute "PN" "CT37"
						( Origin gPackager )
					)
					( objectStatus "U5D1.CT37" )
				)
				( pin "vccin(16)"
					( attribute "PN" "CR56"
						( Origin gPackager )
					)
					( objectStatus "U5D1.CR56" )
				)
				( pin "vccin(17)"
					( attribute "PN" "CR54"
						( Origin gPackager )
					)
					( objectStatus "U5D1.CR54" )
				)
				( pin "vccin(18)"
					( attribute "PN" "CR34"
						( Origin gPackager )
					)
					( objectStatus "U5D1.CR34" )
				)
				( pin "vccin(19)"
					( attribute "PN" "CP57"
						( Origin gPackager )
					)
					( objectStatus "U5D1.CP57" )
				)
				( pin "vccin(20)"
					( attribute "PN" "CP55"
						( Origin gPackager )
					)
					( objectStatus "U5D1.CP55" )
				)
				( pin "vccin(21)"
					( attribute "PN" "CP33"
						( Origin gPackager )
					)
					( objectStatus "U5D1.CP33" )
				)
				( pin "vccin(22)"
					( attribute "PN" "CN58"
						( Origin gPackager )
					)
					( objectStatus "U5D1.CN58" )
				)
				( pin "vccin(23)"
					( attribute "PN" "CN56"
						( Origin gPackager )
					)
					( objectStatus "U5D1.CN56" )
				)
				( pin "vccin(24)"
					( attribute "PN" "CM59"
						( Origin gPackager )
					)
					( objectStatus "U5D1.CM59" )
				)
				( pin "vccin(25)"
					( attribute "PN" "CM57"
						( Origin gPackager )
					)
					( objectStatus "U5D1.CM57" )
				)
				( pin "vccin(26)"
					( attribute "PN" "CL60"
						( Origin gPackager )
					)
					( objectStatus "U5D1.CL60" )
				)
				( pin "vccin(27)"
					( attribute "PN" "CL58"
						( Origin gPackager )
					)
					( objectStatus "U5D1.CL58" )
				)
				( pin "vccin(28)"
					( attribute "PN" "CK61"
						( Origin gPackager )
					)
					( objectStatus "U5D1.CK61" )
				)
				( pin "vccin(29)"
					( attribute "PN" "CK59"
						( Origin gPackager )
					)
					( objectStatus "U5D1.CK59" )
				)
				( pin "vccin(30)"
					( attribute "PN" "CJ60"
						( Origin gPackager )
					)
					( objectStatus "U5D1.CJ60" )
				)
				( pin "vccin(31)"
					( attribute "PN" "CH85"
						( Origin gPackager )
					)
					( objectStatus "U5D1.CH85" )
				)
				( pin "vccin(32)"
					( attribute "PN" "CH61"
						( Origin gPackager )
					)
					( objectStatus "U5D1.CH61" )
				)
				( pin "vccin(33)"
					( attribute "PN" "CG84"
						( Origin gPackager )
					)
					( objectStatus "U5D1.CG84" )
				)
				( pin "vccin(34)"
					( attribute "PN" "CG60"
						( Origin gPackager )
					)
					( objectStatus "U5D1.CG60" )
				)
				( pin "vccin(35)"
					( attribute "PN" "CF85"
						( Origin gPackager )
					)
					( objectStatus "U5D1.CF85" )
				)
				( pin "vccin(36)"
					( attribute "PN" "CF61"
						( Origin gPackager )
					)
					( objectStatus "U5D1.CF61" )
				)
				( pin "vccin(37)"
					( attribute "PN" "CE84"
						( Origin gPackager )
					)
					( objectStatus "U5D1.CE84" )
				)
				( pin "vccin(38)"
					( attribute "PN" "CE60"
						( Origin gPackager )
					)
					( objectStatus "U5D1.CE60" )
				)
				( pin "vccin(39)"
					( attribute "PN" "CD85"
						( Origin gPackager )
					)
					( objectStatus "U5D1.CD85" )
				)
				( pin "vccin(40)"
					( attribute "PN" "CD83"
						( Origin gPackager )
					)
					( objectStatus "U5D1.CD83" )
				)
				( pin "vccin(41)"
					( attribute "PN" "CD61"
						( Origin gPackager )
					)
					( objectStatus "U5D1.CD61" )
				)
				( pin "vccin(42)"
					( attribute "PN" "CC84"
						( Origin gPackager )
					)
					( objectStatus "U5D1.CC84" )
				)
				( pin "vccin(43)"
					( attribute "PN" "CC62"
						( Origin gPackager )
					)
					( objectStatus "U5D1.CC62" )
				)
				( pin "vccin(44)"
					( attribute "PN" "CC60"
						( Origin gPackager )
					)
					( objectStatus "U5D1.CC60" )
				)
				( pin "vccin(45)"
					( attribute "PN" "CB83"
						( Origin gPackager )
					)
					( objectStatus "U5D1.CB83" )
				)
				( pin "vccin(46)"
					( attribute "PN" "CB81"
						( Origin gPackager )
					)
					( objectStatus "U5D1.CB81" )
				)
				( pin "vccin(47)"
					( attribute "PN" "CB79"
						( Origin gPackager )
					)
					( objectStatus "U5D1.CB79" )
				)
				( pin "vccin(48)"
					( attribute "PN" "CB77"
						( Origin gPackager )
					)
					( objectStatus "U5D1.CB77" )
				)
				( pin "vccin(49)"
					( attribute "PN" "CB75"
						( Origin gPackager )
					)
					( objectStatus "U5D1.CB75" )
				)
				( pin "vccin(50)"
					( attribute "PN" "CB73"
						( Origin gPackager )
					)
					( objectStatus "U5D1.CB73" )
				)
				( pin "vccin(51)"
					( attribute "PN" "CB61"
						( Origin gPackager )
					)
					( objectStatus "U5D1.CB61" )
				)
				( pin "vccin(52)"
					( attribute "PN" "CA84"
						( Origin gPackager )
					)
					( objectStatus "U5D1.CA84" )
				)
				( pin "vccin(53)"
					( attribute "PN" "CA82"
						( Origin gPackager )
					)
					( objectStatus "U5D1.CA82" )
				)
				( pin "vccin(54)"
					( attribute "PN" "CA80"
						( Origin gPackager )
					)
					( objectStatus "U5D1.CA80" )
				)
				( pin "vccin(55)"
					( attribute "PN" "CA78"
						( Origin gPackager )
					)
					( objectStatus "U5D1.CA78" )
				)
				( pin "vccin(56)"
					( attribute "PN" "CA76"
						( Origin gPackager )
					)
					( objectStatus "U5D1.CA76" )
				)
				( pin "vccin(57)"
					( attribute "PN" "CA74"
						( Origin gPackager )
					)
					( objectStatus "U5D1.CA74" )
				)
				( pin "vccin(58)"
					( attribute "PN" "CA72"
						( Origin gPackager )
					)
					( objectStatus "U5D1.CA72" )
				)
				( pin "vccin(59)"
					( attribute "PN" "CA62"
						( Origin gPackager )
					)
					( objectStatus "U5D1.CA62" )
				)
				( pin "vccin(60)"
					( attribute "PN" "CA60"
						( Origin gPackager )
					)
					( objectStatus "U5D1.CA60" )
				)
				( pin "vccin(61)"
					( attribute "PN" "BY83"
						( Origin gPackager )
					)
					( objectStatus "U5D1.BY83" )
				)
				( pin "vccin(62)"
					( attribute "PN" "BY81"
						( Origin gPackager )
					)
					( objectStatus "U5D1.BY81" )
				)
				( pin "vccin(63)"
					( attribute "PN" "BY79"
						( Origin gPackager )
					)
					( objectStatus "U5D1.BY79" )
				)
				( pin "vccin(64)"
					( attribute "PN" "BY77"
						( Origin gPackager )
					)
					( objectStatus "U5D1.BY77" )
				)
				( pin "vccin(65)"
					( attribute "PN" "BY75"
						( Origin gPackager )
					)
					( objectStatus "U5D1.BY75" )
				)
				( pin "vccin(66)"
					( attribute "PN" "BY73"
						( Origin gPackager )
					)
					( objectStatus "U5D1.BY73" )
				)
				( pin "vccin(67)"
					( attribute "PN" "BY61"
						( Origin gPackager )
					)
					( objectStatus "U5D1.BY61" )
				)
				( pin "vccin(68)"
					( attribute "PN" "BW84"
						( Origin gPackager )
					)
					( objectStatus "U5D1.BW84" )
				)
				( pin "vccin(69)"
					( attribute "PN" "BW70"
						( Origin gPackager )
					)
					( objectStatus "U5D1.BW70" )
				)
				( pin "vccin(70)"
					( attribute "PN" "BW68"
						( Origin gPackager )
					)
					( objectStatus "U5D1.BW68" )
				)
				( pin "vccin(71)"
					( attribute "PN" "BW66"
						( Origin gPackager )
					)
					( objectStatus "U5D1.BW66" )
				)
				( pin "vccin(72)"
					( attribute "PN" "BW64"
						( Origin gPackager )
					)
					( objectStatus "U5D1.BW64" )
				)
				( pin "vccin(73)"
					( attribute "PN" "BW62"
						( Origin gPackager )
					)
					( objectStatus "U5D1.BW62" )
				)
				( pin "vccin(74)"
					( attribute "PN" "BW60"
						( Origin gPackager )
					)
					( objectStatus "U5D1.BW60" )
				)
				( pin "vccin(75)"
					( attribute "PN" "BV83"
						( Origin gPackager )
					)
					( objectStatus "U5D1.BV83" )
				)
				( pin "vccin(76)"
					( attribute "PN" "BV81"
						( Origin gPackager )
					)
					( objectStatus "U5D1.BV81" )
				)
				( pin "vccin(77)"
					( attribute "PN" "BV79"
						( Origin gPackager )
					)
					( objectStatus "U5D1.BV79" )
				)
				( pin "vccin(78)"
					( attribute "PN" "BV77"
						( Origin gPackager )
					)
					( objectStatus "U5D1.BV77" )
				)
				( pin "vccin(79)"
					( attribute "PN" "BV75"
						( Origin gPackager )
					)
					( objectStatus "U5D1.BV75" )
				)
				( pin "vccin(80)"
					( attribute "PN" "BV73"
						( Origin gPackager )
					)
					( objectStatus "U5D1.BV73" )
				)
				( pin "vccin(81)"
					( attribute "PN" "BV71"
						( Origin gPackager )
					)
					( objectStatus "U5D1.BV71" )
				)
				( pin "vccin(82)"
					( attribute "PN" "BV69"
						( Origin gPackager )
					)
					( objectStatus "U5D1.BV69" )
				)
				( pin "vccin(83)"
					( attribute "PN" "BV67"
						( Origin gPackager )
					)
					( objectStatus "U5D1.BV67" )
				)
				( pin "vccin(84)"
					( attribute "PN" "BV65"
						( Origin gPackager )
					)
					( objectStatus "U5D1.BV65" )
				)
				( pin "vccin(85)"
					( attribute "PN" "BV63"
						( Origin gPackager )
					)
					( objectStatus "U5D1.BV63" )
				)
				( pin "vccin(86)"
					( attribute "PN" "BV61"
						( Origin gPackager )
					)
					( objectStatus "U5D1.BV61" )
				)
				( pin "vccin(87)"
					( attribute "PN" "BU84"
						( Origin gPackager )
					)
					( objectStatus "U5D1.BU84" )
				)
				( pin "vccin(88)"
					( attribute "PN" "BU82"
						( Origin gPackager )
					)
					( objectStatus "U5D1.BU82" )
				)
				( pin "vccin(89)"
					( attribute "PN" "BU80"
						( Origin gPackager )
					)
					( objectStatus "U5D1.BU80" )
				)
				( pin "vccin(90)"
					( attribute "PN" "BU78"
						( Origin gPackager )
					)
					( objectStatus "U5D1.BU78" )
				)
				( pin "vccin(91)"
					( attribute "PN" "BU76"
						( Origin gPackager )
					)
					( objectStatus "U5D1.BU76" )
				)
				( pin "vccin(92)"
					( attribute "PN" "BU74"
						( Origin gPackager )
					)
					( objectStatus "U5D1.BU74" )
				)
				( pin "vccin(93)"
					( attribute "PN" "BU72"
						( Origin gPackager )
					)
					( objectStatus "U5D1.BU72" )
				)
				( pin "vccin(94)"
					( attribute "PN" "BU70"
						( Origin gPackager )
					)
					( objectStatus "U5D1.BU70" )
				)
				( pin "vccin(95)"
					( attribute "PN" "BU68"
						( Origin gPackager )
					)
					( objectStatus "U5D1.BU68" )
				)
				( pin "vccin(96)"
					( attribute "PN" "BU66"
						( Origin gPackager )
					)
					( objectStatus "U5D1.BU66" )
				)
				( pin "vccin(97)"
					( attribute "PN" "BU64"
						( Origin gPackager )
					)
					( objectStatus "U5D1.BU64" )
				)
				( pin "vccin(98)"
					( attribute "PN" "BU62"
						( Origin gPackager )
					)
					( objectStatus "U5D1.BU62" )
				)
				( pin "vccin(99)"
					( attribute "PN" "BU60"
						( Origin gPackager )
					)
					( objectStatus "U5D1.BU60" )
				)
				( pin "vccin(100)"
					( attribute "PN" "BT83"
						( Origin gPackager )
					)
					( objectStatus "U5D1.BT83" )
				)
				( pin "vccin(101)"
					( attribute "PN" "BT81"
						( Origin gPackager )
					)
					( objectStatus "U5D1.BT81" )
				)
				( pin "vccin(102)"
					( attribute "PN" "BT79"
						( Origin gPackager )
					)
					( objectStatus "U5D1.BT79" )
				)
				( pin "vccin(103)"
					( attribute "PN" "BT77"
						( Origin gPackager )
					)
					( objectStatus "U5D1.BT77" )
				)
				( pin "vccin(104)"
					( attribute "PN" "BT75"
						( Origin gPackager )
					)
					( objectStatus "U5D1.BT75" )
				)
				( pin "vccin(105)"
					( attribute "PN" "BT73"
						( Origin gPackager )
					)
					( objectStatus "U5D1.BT73" )
				)
				( pin "vccin(106)"
					( attribute "PN" "BT71"
						( Origin gPackager )
					)
					( objectStatus "U5D1.BT71" )
				)
				( pin "vccin(107)"
					( attribute "PN" "BT69"
						( Origin gPackager )
					)
					( objectStatus "U5D1.BT69" )
				)
				( pin "vccin(108)"
					( attribute "PN" "BT67"
						( Origin gPackager )
					)
					( objectStatus "U5D1.BT67" )
				)
				( pin "vccin(109)"
					( attribute "PN" "BT65"
						( Origin gPackager )
					)
					( objectStatus "U5D1.BT65" )
				)
				( pin "vccin(110)"
					( attribute "PN" "BT63"
						( Origin gPackager )
					)
					( objectStatus "U5D1.BT63" )
				)
				( pin "vccin(111)"
					( attribute "PN" "BT61"
						( Origin gPackager )
					)
					( objectStatus "U5D1.BT61" )
				)
				( pin "vccin(112)"
					( attribute "PN" "BR84"
						( Origin gPackager )
					)
					( objectStatus "U5D1.BR84" )
				)
				( pin "vccin(113)"
					( attribute "PN" "BR62"
						( Origin gPackager )
					)
					( objectStatus "U5D1.BR62" )
				)
				( pin "vccin(114)"
					( attribute "PN" "BR60"
						( Origin gPackager )
					)
					( objectStatus "U5D1.BR60" )
				)
				( pin "vccin(115)"
					( attribute "PN" "BP83"
						( Origin gPackager )
					)
					( objectStatus "U5D1.BP83" )
				)
				( pin "vccin(116)"
					( attribute "PN" "BP81"
						( Origin gPackager )
					)
					( objectStatus "U5D1.BP81" )
				)
				( pin "vccin(117)"
					( attribute "PN" "BP79"
						( Origin gPackager )
					)
					( objectStatus "U5D1.BP79" )
				)
				( pin "vccin(118)"
					( attribute "PN" "BP77"
						( Origin gPackager )
					)
					( objectStatus "U5D1.BP77" )
				)
				( pin "vccin(119)"
					( attribute "PN" "BP75"
						( Origin gPackager )
					)
					( objectStatus "U5D1.BP75" )
				)
				( pin "vccin(120)"
					( attribute "PN" "BP73"
						( Origin gPackager )
					)
					( objectStatus "U5D1.BP73" )
				)
				( pin "vccin(121)"
					( attribute "PN" "BP71"
						( Origin gPackager )
					)
					( objectStatus "U5D1.BP71" )
				)
				( pin "vccin(122)"
					( attribute "PN" "BP69"
						( Origin gPackager )
					)
					( objectStatus "U5D1.BP69" )
				)
				( pin "vccin(123)"
					( attribute "PN" "BP67"
						( Origin gPackager )
					)
					( objectStatus "U5D1.BP67" )
				)
				( pin "vccin(124)"
					( attribute "PN" "BP65"
						( Origin gPackager )
					)
					( objectStatus "U5D1.BP65" )
				)
				( pin "vccin(125)"
					( attribute "PN" "BP63"
						( Origin gPackager )
					)
					( objectStatus "U5D1.BP63" )
				)
				( pin "vccin(126)"
					( attribute "PN" "BP61"
						( Origin gPackager )
					)
					( objectStatus "U5D1.BP61" )
				)
				( pin "vccin(127)"
					( attribute "PN" "BN84"
						( Origin gPackager )
					)
					( objectStatus "U5D1.BN84" )
				)
				( pin "vccin(128)"
					( attribute "PN" "BN82"
						( Origin gPackager )
					)
					( objectStatus "U5D1.BN82" )
				)
				( pin "vccin(129)"
					( attribute "PN" "BN80"
						( Origin gPackager )
					)
					( objectStatus "U5D1.BN80" )
				)
				( pin "vccin_sense"
					( attribute "PN" "BA86"
						( Origin gPackager )
					)
					( objectStatus "U5D1.BA86" )
				)
				( pin "vccinpmax(0)"
					( attribute "PN" "AW86"
						( Origin gPackager )
					)
					( objectStatus "U5D1.AW86" )
				)
				( pin "vccinpmax(1)"
					( attribute "PN" "AV85"
						( Origin gPackager )
					)
					( objectStatus "U5D1.AV85" )
				)
				( pin "vsensepmax"
					( attribute "PN" "AD41"
						( Origin gPackager )
					)
					( objectStatus "U5D1.AD41" )
				)
				( pin "vss_vccin_sense"
					( attribute "PN" "AY85"
						( Origin gPackager )
					)
					( objectStatus "U5D1.AY85" )
				)
			)
			( gate "@baseboard_fab2_lib.baseboard_fab2(sch_1):page37_i312"
				( attribute "CDS_LIB" "mstr_discrete"
					( Origin gPackager )
				)
				( attribute "CDS_LOCATION" "R5D6"
					( Origin gPackager )
				)
				( attribute "CDS_SEC" "1"
					( Origin gPackager )
				)
				( attribute "LOCATION" "R5D6"
					( Origin gFrontEnd )
				)
				( attribute "MATERIAL" "EMPTY"
					( Origin gFrontEnd )
				)
				( attribute "PACK_TYPE" "0402"
					( Origin gFrontEnd )
				)
				( attribute "PART_NUMBER" "G21796-066"
					( Origin gFrontEnd )
				)
				( attribute "PHYS_PAGE" "37"
					( Origin gFrontEnd )
				)
				( attribute "ROOM" "CPU0"
					( Origin gFrontEnd )
				)
				( attribute "ROT" "0"
					( Origin gFrontEnd )
				)
				( attribute "SEC" "1"
					( Origin gFrontEnd )
				)
				( attribute "SEC_TYPE" "0402"
					( Origin gFrontEnd )
				)
				( attribute "TOLERANCE" "1%"
					( Origin gFrontEnd )
				)
				( attribute "VALUE" "10.0"
					( Origin gFrontEnd )
				)
				( attribute "VER" "2"
					( Origin gFrontEnd )
				)
				( attribute "WATTAGE" "1/16W"
					( Origin gFrontEnd )
				)
				( attribute "XY" "(-375,1125)"
					( Origin gFrontEnd )
				)
				( attribute "CHIPS_PART_NAME" "RES"
					( Origin gPackager )
				)
				( attribute "CDS_PART_NAME" "RES_0402-10.0,1%,1/16W,EMPTY,GA"
					( Origin gPackager )
				)
				( objectStatus "R5D6" )
				( pin "a"
					( attribute "PN" "1"
						( Origin gPackager )
					)
					( objectStatus "R5D6.1" )
				)
				( pin "b"
					( attribute "PN" "2"
						( Origin gPackager )
					)
					( objectStatus "R5D6.2" )
				)
			)
			( gate "@baseboard_fab2_lib.baseboard_fab2(sch_1):page38_i19"
				( attribute "BOM_COST" "PROC_SOCKET"
					( Origin gFrontEnd )
				)
				( attribute "CDS_LIB" "mstr_discrete"
					( Origin gPackager )
				)
				( attribute "CDS_LOCATION" "C6D1"
					( Origin gPackager )
				)
				( attribute "CDS_SEC" "1"
					( Origin gPackager )
				)
				( attribute "LOCATION" "C6D1"
					( Origin gFrontEnd )
				)
				( attribute "MATERIAL" "X6S"
					( Origin gFrontEnd )
				)
				( attribute "PACK_TYPE" "0603LF"
					( Origin gFrontEnd )
				)
				( attribute "PART_NUMBER" "E15431-001"
					( Origin gFrontEnd )
				)
				( attribute "PHYS_PAGE" "38"
					( Origin gFrontEnd )
				)
				( attribute "ROOM" "CPU0"
					( Origin gFrontEnd )
				)
				( attribute "ROT" "0"
					( Origin gFrontEnd )
				)
				( attribute "SEC" "1"
					( Origin gFrontEnd )
				)
				( attribute "SEC_TYPE" "0603LF"
					( Origin gFrontEnd )
				)
				( attribute "TOLERANCE" "20%"
					( Origin gFrontEnd )
				)
				( attribute "VALUE" "10UF"
					( Origin gFrontEnd )
				)
				( attribute "VER" "1"
					( Origin gFrontEnd )
				)
				( attribute "VOLTAGE" "4V"
					( Units "uVoltage" "V" 1.000000)
					( Origin gFrontEnd )
				)
				( attribute "XY" "(3400,1125)"
					( Origin gFrontEnd )
				)
				( attribute "CHIPS_PART_NAME" "CAP"
					( Origin gPackager )
				)
				( attribute "CDS_PART_NAME" "CAP_0603LF-10UF,4V,20%,X6S,E15A"
					( Origin gPackager )
				)
				( objectStatus "C6D1" )
				( pin "a"
					( attribute "PN" "1"
						( Origin gPackager )
					)
					( objectStatus "C6D1.1" )
				)
				( pin "b"
					( attribute "PN" "2"
						( Origin gPackager )
					)
					( objectStatus "C6D1.2" )
				)
			)
			( gate "@baseboard_fab2_lib.baseboard_fab2(sch_1):page38_i33"
				( attribute "CDS_LIB" "chpset_lib"
					( Origin gPackager )
				)
				( attribute "CDS_LOCATION" "U5D1"
					( Origin gPackager )
				)
				( attribute "CDS_SEC" "20"
					( Origin gPackager )
				)
				( attribute "LOCATION" "U5D1"
					( Origin gFrontEnd )
				)
				( attribute "MATERIAL" "IC"
					( Origin gFrontEnd )
				)
				( attribute "PACK_TYPE" "BGA1"
					( Origin gFrontEnd )
				)
				( attribute "PART_NUMBER" "TBD"
					( Origin gFrontEnd )
				)
				( attribute "PHYS_PAGE" "38"
					( Origin gFrontEnd )
				)
				( attribute "ROOM" "CPU0"
					( Origin gFrontEnd )
				)
				( attribute "ROT" "0"
					( Origin gFrontEnd )
				)
				( attribute "SEC" "20"
					( Origin gFrontEnd )
				)
				( attribute "SEC_TYPE" "BGA1"
					( Origin gFrontEnd )
				)
				( attribute "VER" "20"
					( Origin gFrontEnd )
				)
				( attribute "XY" "(-1950,2650)"
					( Origin gFrontEnd )
				)
				( attribute "CHIPS_PART_NAME" "SKX_EXT_B"
					( Origin gPackager )
				)
				( attribute "CDS_PART_NAME" "SKX_EXT_B_BGA1-IC,TBD"
					( Origin gPackager )
				)
				( objectStatus "U5D1" )
				( pin "vccd012(0)"
					( attribute "PN" "B49"
						( Origin gPackager )
					)
					( objectStatus "U5D1.B49" )
				)
				( pin "vccd012(1)"
					( attribute "PN" "B53"
						( Origin gPackager )
					)
					( objectStatus "U5D1.B53" )
				)
				( pin "vccd012(2)"
					( attribute "PN" "B59"
						( Origin gPackager )
					)
					( objectStatus "U5D1.B59" )
				)
				( pin "vccd012(3)"
					( attribute "PN" "E46"
						( Origin gPackager )
					)
					( objectStatus "U5D1.E46" )
				)
				( pin "vccd012(4)"
					( attribute "PN" "E48"
						( Origin gPackager )
					)
					( objectStatus "U5D1.E48" )
				)
				( pin "vccd012(5)"
					( attribute "PN" "E50"
						( Origin gPackager )
					)
					( objectStatus "U5D1.E50" )
				)
				( pin "vccd012(6)"
					( attribute "PN" "E52"
						( Origin gPackager )
					)
					( objectStatus "U5D1.E52" )
				)
				( pin "vccd012(7)"
					( attribute "PN" "E54"
						( Origin gPackager )
					)
					( objectStatus "U5D1.E54" )
				)
				( pin "vccd012(8)"
					( attribute "PN" "E56"
						( Origin gPackager )
					)
					( objectStatus "U5D1.E56" )
				)
				( pin "vccd012(9)"
					( attribute "PN" "E58"
						( Origin gPackager )
					)
					( objectStatus "U5D1.E58" )
				)
				( pin "vccd012(10)"
					( attribute "PN" "E60"
						( Origin gPackager )
					)
					( objectStatus "U5D1.E60" )
				)
				( pin "vccd012(11)"
					( attribute "PN" "E62"
						( Origin gPackager )
					)
					( objectStatus "U5D1.E62" )
				)
				( pin "vccd012(12)"
					( attribute "PN" "E64"
						( Origin gPackager )
					)
					( objectStatus "U5D1.E64" )
				)
				( pin "vccd012(13)"
					( attribute "PN" "L46"
						( Origin gPackager )
					)
					( objectStatus "U5D1.L46" )
				)
				( pin "vccd012(14)"
					( attribute "PN" "L48"
						( Origin gPackager )
					)
					( objectStatus "U5D1.L48" )
				)
				( pin "vccd012(15)"
					( attribute "PN" "L50"
						( Origin gPackager )
					)
					( objectStatus "U5D1.L50" )
				)
				( pin "vccd012(16)"
					( attribute "PN" "L52"
						( Origin gPackager )
					)
					( objectStatus "U5D1.L52" )
				)
				( pin "vccd012(17)"
					( attribute "PN" "L54"
						( Origin gPackager )
					)
					( objectStatus "U5D1.L54" )
				)
				( pin "vccd012(18)"
					( attribute "PN" "L56"
						( Origin gPackager )
					)
					( objectStatus "U5D1.L56" )
				)
				( pin "vccd012(19)"
					( attribute "PN" "L58"
						( Origin gPackager )
					)
					( objectStatus "U5D1.L58" )
				)
				( pin "vccd012(20)"
					( attribute "PN" "L60"
						( Origin gPackager )
					)
					( objectStatus "U5D1.L60" )
				)
				( pin "vccd012(21)"
					( attribute "PN" "L62"
						( Origin gPackager )
					)
					( objectStatus "U5D1.L62" )
				)
				( pin "vccd012(22)"
					( attribute "PN" "N64"
						( Origin gPackager )
					)
					( objectStatus "U5D1.N64" )
				)
				( pin "vccd012(23)"
					( attribute "PN" "U46"
						( Origin gPackager )
					)
					( objectStatus "U5D1.U46" )
				)
				( pin "vccd012(24)"
					( attribute "PN" "U48"
						( Origin gPackager )
					)
					( objectStatus "U5D1.U48" )
				)
				( pin "vccd012(25)"
					( attribute "PN" "U50"
						( Origin gPackager )
					)
					( objectStatus "U5D1.U50" )
				)
				( pin "vccd012(26)"
					( attribute "PN" "U52"
						( Origin gPackager )
					)
					( objectStatus "U5D1.U52" )
				)
				( pin "vccd012(27)"
					( attribute "PN" "U54"
						( Origin gPackager )
					)
					( objectStatus "U5D1.U54" )
				)
				( pin "vccd012(28)"
					( attribute "PN" "U56"
						( Origin gPackager )
					)
					( objectStatus "U5D1.U56" )
				)
				( pin "vccd012(29)"
					( attribute "PN" "U58"
						( Origin gPackager )
					)
					( objectStatus "U5D1.U58" )
				)
				( pin "vccd012(30)"
					( attribute "PN" "U60"
						( Origin gPackager )
					)
					( objectStatus "U5D1.U60" )
				)
				( pin "vccd012(31)"
					( attribute "PN" "U62"
						( Origin gPackager )
					)
					( objectStatus "U5D1.U62" )
				)
				( pin "vccd012(32)"
					( attribute "PN" "W64"
						( Origin gPackager )
					)
					( objectStatus "U5D1.W64" )
				)
				( pin "vccd012(33)"
					( attribute "PN" "Y45"
						( Origin gPackager )
					)
					( objectStatus "U5D1.Y45" )
				)
				( pin "vccd012(34)"
					( attribute "PN" "Y47"
						( Origin gPackager )
					)
					( objectStatus "U5D1.Y47" )
				)
				( pin "vccd012(35)"
					( attribute "PN" "Y49"
						( Origin gPackager )
					)
					( objectStatus "U5D1.Y49" )
				)
				( pin "vccd012(36)"
					( attribute "PN" "Y51"
						( Origin gPackager )
					)
					( objectStatus "U5D1.Y51" )
				)
				( pin "vccd012(37)"
					( attribute "PN" "Y53"
						( Origin gPackager )
					)
					( objectStatus "U5D1.Y53" )
				)
				( pin "vccd012(38)"
					( attribute "PN" "Y55"
						( Origin gPackager )
					)
					( objectStatus "U5D1.Y55" )
				)
				( pin "vccd012(39)"
					( attribute "PN" "Y57"
						( Origin gPackager )
					)
					( objectStatus "U5D1.Y57" )
				)
				( pin "vccd012(40)"
					( attribute "PN" "Y59"
						( Origin gPackager )
					)
					( objectStatus "U5D1.Y59" )
				)
				( pin "vccd012(41)"
					( attribute "PN" "Y61"
						( Origin gPackager )
					)
					( objectStatus "U5D1.Y61" )
				)
				( pin "vccd012(42)"
					( attribute "PN" "Y63"
						( Origin gPackager )
					)
					( objectStatus "U5D1.Y63" )
				)
				( pin "vccd012(43)"
					( attribute "PN" "AD45"
						( Origin gPackager )
					)
					( objectStatus "U5D1.AD45" )
				)
				( pin "vccd012(44)"
					( attribute "PN" "AF55"
						( Origin gPackager )
					)
					( objectStatus "U5D1.AF55" )
				)
				( pin "vccd012(45)"
					( attribute "PN" "AF57"
						( Origin gPackager )
					)
					( objectStatus "U5D1.AF57" )
				)
				( pin "vccd012(46)"
					( attribute "PN" "AF59"
						( Origin gPackager )
					)
					( objectStatus "U5D1.AF59" )
				)
				( pin "vccd012(47)"
					( attribute "PN" "AF61"
						( Origin gPackager )
					)
					( objectStatus "U5D1.AF61" )
				)
				( pin "vccd012(48)"
					( attribute "PN" "AF63"
						( Origin gPackager )
					)
					( objectStatus "U5D1.AF63" )
				)
				( pin "vccd012(49)"
					( attribute "PN" "D45"
						( Origin gPackager )
					)
					( objectStatus "U5D1.D45" )
				)
				( pin "vccd012(50)"
					( attribute "PN" "C46"
						( Origin gPackager )
					)
					( objectStatus "U5D1.C46" )
				)
				( pin "vccd012(51)"
					( attribute "PN" "B47"
						( Origin gPackager )
					)
					( objectStatus "U5D1.B47" )
				)
				( pin "vccd345(0)"
					( attribute "PN" "EF59"
						( Origin gPackager )
					)
					( objectStatus "U5D1.EF59" )
				)
				( pin "vccd345(1)"
					( attribute "PN" "EF53"
						( Origin gPackager )
					)
					( objectStatus "U5D1.EF53" )
				)
				( pin "vccd345(2)"
					( attribute "PN" "EF49"
						( Origin gPackager )
					)
					( objectStatus "U5D1.EF49" )
				)
				( pin "vccd345(3)"
					( attribute "PN" "EC62"
						( Origin gPackager )
					)
					( objectStatus "U5D1.EC62" )
				)
				( pin "vccd345(4)"
					( attribute "PN" "EC60"
						( Origin gPackager )
					)
					( objectStatus "U5D1.EC60" )
				)
				( pin "vccd345(5)"
					( attribute "PN" "EC58"
						( Origin gPackager )
					)
					( objectStatus "U5D1.EC58" )
				)
				( pin "vccd345(6)"
					( attribute "PN" "EC56"
						( Origin gPackager )
					)
					( objectStatus "U5D1.EC56" )
				)
				( pin "vccd345(7)"
					( attribute "PN" "EC54"
						( Origin gPackager )
					)
					( objectStatus "U5D1.EC54" )
				)
				( pin "vccd345(8)"
					( attribute "PN" "EC52"
						( Origin gPackager )
					)
					( objectStatus "U5D1.EC52" )
				)
				( pin "vccd345(9)"
					( attribute "PN" "EC50"
						( Origin gPackager )
					)
					( objectStatus "U5D1.EC50" )
				)
				( pin "vccd345(10)"
					( attribute "PN" "EC48"
						( Origin gPackager )
					)
					( objectStatus "U5D1.EC48" )
				)
				( pin "vccd345(11)"
					( attribute "PN" "EC46"
						( Origin gPackager )
					)
					( objectStatus "U5D1.EC46" )
				)
				( pin "vccd345(12)"
					( attribute "PN" "DU64"
						( Origin gPackager )
					)
					( objectStatus "U5D1.DU64" )
				)
				( pin "vccd345(13)"
					( attribute "PN" "DU62"
						( Origin gPackager )
					)
					( objectStatus "U5D1.DU62" )
				)
				( pin "vccd345(14)"
					( attribute "PN" "DU60"
						( Origin gPackager )
					)
					( objectStatus "U5D1.DU60" )
				)
				( pin "vccd345(15)"
					( attribute "PN" "DU58"
						( Origin gPackager )
					)
					( objectStatus "U5D1.DU58" )
				)
				( pin "vccd345(16)"
					( attribute "PN" "DU56"
						( Origin gPackager )
					)
					( objectStatus "U5D1.DU56" )
				)
				( pin "vccd345(17)"
					( attribute "PN" "DU54"
						( Origin gPackager )
					)
					( objectStatus "U5D1.DU54" )
				)
				( pin "vccd345(18)"
					( attribute "PN" "DU52"
						( Origin gPackager )
					)
					( objectStatus "U5D1.DU52" )
				)
				( pin "vccd345(19)"
					( attribute "PN" "DU50"
						( Origin gPackager )
					)
					( objectStatus "U5D1.DU50" )
				)
				( pin "vccd345(20)"
					( attribute "PN" "DU48"
						( Origin gPackager )
					)
					( objectStatus "U5D1.DU48" )
				)
				( pin "vccd345(21)"
					( attribute "PN" "DU46"
						( Origin gPackager )
					)
					( objectStatus "U5D1.DU46" )
				)
				( pin "vccd345(22)"
					( attribute "PN" "DL62"
						( Origin gPackager )
					)
					( objectStatus "U5D1.DL62" )
				)
				( pin "vccd345(23)"
					( attribute "PN" "DL60"
						( Origin gPackager )
					)
					( objectStatus "U5D1.DL60" )
				)
				( pin "vccd345(24)"
					( attribute "PN" "DL58"
						( Origin gPackager )
					)
					( objectStatus "U5D1.DL58" )
				)
				( pin "vccd345(25)"
					( attribute "PN" "DL56"
						( Origin gPackager )
					)
					( objectStatus "U5D1.DL56" )
				)
				( pin "vccd345(26)"
					( attribute "PN" "DL54"
						( Origin gPackager )
					)
					( objectStatus "U5D1.DL54" )
				)
				( pin "vccd345(27)"
					( attribute "PN" "DL52"
						( Origin gPackager )
					)
					( objectStatus "U5D1.DL52" )
				)
				( pin "vccd345(28)"
					( attribute "PN" "DL50"
						( Origin gPackager )
					)
					( objectStatus "U5D1.DL50" )
				)
				( pin "vccd345(29)"
					( attribute "PN" "DL48"
						( Origin gPackager )
					)
					( objectStatus "U5D1.DL48" )
				)
				( pin "vccd345(30)"
					( attribute "PN" "DL46"
						( Origin gPackager )
					)
					( objectStatus "U5D1.DL46" )
				)
				( pin "vccd345(31)"
					( attribute "PN" "DJ64"
						( Origin gPackager )
					)
					( objectStatus "U5D1.DJ64" )
				)
				( pin "vccd345(32)"
					( attribute "PN" "DH63"
						( Origin gPackager )
					)
					( objectStatus "U5D1.DH63" )
				)
				( pin "vccd345(33)"
					( attribute "PN" "DH61"
						( Origin gPackager )
					)
					( objectStatus "U5D1.DH61" )
				)
				( pin "vccd345(34)"
					( attribute "PN" "DH59"
						( Origin gPackager )
					)
					( objectStatus "U5D1.DH59" )
				)
				( pin "vccd345(35)"
					( attribute "PN" "DH57"
						( Origin gPackager )
					)
					( objectStatus "U5D1.DH57" )
				)
				( pin "vccd345(36)"
					( attribute "PN" "DH55"
						( Origin gPackager )
					)
					( objectStatus "U5D1.DH55" )
				)
				( pin "vccd345(37)"
					( attribute "PN" "DH53"
						( Origin gPackager )
					)
					( objectStatus "U5D1.DH53" )
				)
				( pin "vccd345(38)"
					( attribute "PN" "DH51"
						( Origin gPackager )
					)
					( objectStatus "U5D1.DH51" )
				)
				( pin "vccd345(39)"
					( attribute "PN" "DH49"
						( Origin gPackager )
					)
					( objectStatus "U5D1.DH49" )
				)
				( pin "vccd345(40)"
					( attribute "PN" "DH47"
						( Origin gPackager )
					)
					( objectStatus "U5D1.DH47" )
				)
				( pin "vccd345(41)"
					( attribute "PN" "DH45"
						( Origin gPackager )
					)
					( objectStatus "U5D1.DH45" )
				)
				( pin "vccd345(42)"
					( attribute "PN" "DD45"
						( Origin gPackager )
					)
					( objectStatus "U5D1.DD45" )
				)
				( pin "vccd345(43)"
					( attribute "PN" "DB63"
						( Origin gPackager )
					)
					( objectStatus "U5D1.DB63" )
				)
				( pin "vccd345(44)"
					( attribute "PN" "DB61"
						( Origin gPackager )
					)
					( objectStatus "U5D1.DB61" )
				)
				( pin "vccd345(45)"
					( attribute "PN" "DB59"
						( Origin gPackager )
					)
					( objectStatus "U5D1.DB59" )
				)
				( pin "vccd345(46)"
					( attribute "PN" "DB57"
						( Origin gPackager )
					)
					( objectStatus "U5D1.DB57" )
				)
				( pin "vccd345(47)"
					( attribute "PN" "DB55"
						( Origin gPackager )
					)
					( objectStatus "U5D1.DB55" )
				)
				( pin "vccd345(48)"
					( attribute "PN" "DB53"
						( Origin gPackager )
					)
					( objectStatus "U5D1.DB53" )
				)
				( pin "vccd345(49)"
					( attribute "PN" "EF45"
						( Origin gPackager )
					)
					( objectStatus "U5D1.EF45" )
				)
				( pin "vccd345(50)"
					( attribute "PN" "EE44"
						( Origin gPackager )
					)
					( objectStatus "U5D1.EE44" )
				)
			)
			( gate "@baseboard_fab2_lib.baseboard_fab2(sch_1):page38_i34"
				( attribute "CDS_LIB" "chpset_lib"
					( Origin gPackager )
				)
				( attribute "CDS_LOCATION" "U5D1"
					( Origin gPackager )
				)
				( attribute "CDS_SEC" "21"
					( Origin gPackager )
				)
				( attribute "LOCATION" "U5D1"
					( Origin gFrontEnd )
				)
				( attribute "MATERIAL" "IC"
					( Origin gFrontEnd )
				)
				( attribute "PACK_TYPE" "BGA1"
					( Origin gFrontEnd )
				)
				( attribute "PART_NUMBER" "TBD"
					( Origin gFrontEnd )
				)
				( attribute "PHYS_PAGE" "38"
					( Origin gFrontEnd )
				)
				( attribute "ROOM" "CPU0"
					( Origin gFrontEnd )
				)
				( attribute "ROT" "0"
					( Origin gFrontEnd )
				)
				( attribute "SEC" "21"
					( Origin gFrontEnd )
				)
				( attribute "SEC_TYPE" "BGA1"
					( Origin gFrontEnd )
				)
				( attribute "VER" "21"
					( Origin gFrontEnd )
				)
				( attribute "XY" "(1050,2725)"
					( Origin gFrontEnd )
				)
				( attribute "CHIPS_PART_NAME" "SKX_EXT_B"
					( Origin gPackager )
				)
				( attribute "CDS_PART_NAME" "SKX_EXT_B_BGA1-IC,TBD"
					( Origin gPackager )
				)
				( objectStatus "U5D1" )
				( pin "cd_vcc_core(0)"
					( attribute "PN" "BL14"
						( Origin gPackager )
					)
					( objectStatus "U5D1.BL14" )
				)
				( pin "cd_vcc_core(1)"
					( attribute "PN" "BK15"
						( Origin gPackager )
					)
					( objectStatus "U5D1.BK15" )
				)
				( pin "cd_vcc_core(2)"
					( attribute "PN" "BK13"
						( Origin gPackager )
					)
					( objectStatus "U5D1.BK13" )
				)
				( pin "cd_vcc_core(3)"
					( attribute "PN" "BJ14"
						( Origin gPackager )
					)
					( objectStatus "U5D1.BJ14" )
				)
				( pin "cd_vcc_core(4)"
					( attribute "PN" "BJ12"
						( Origin gPackager )
					)
					( objectStatus "U5D1.BJ12" )
				)
				( pin "cd_vcc_core(5)"
					( attribute "PN" "BH13"
						( Origin gPackager )
					)
					( objectStatus "U5D1.BH13" )
				)
				( pin "cd_vcc_core(6)"
					( attribute "PN" "BG14"
						( Origin gPackager )
					)
					( objectStatus "U5D1.BG14" )
				)
				( pin "cd_vcc_core(7)"
					( attribute "PN" "BG12"
						( Origin gPackager )
					)
					( objectStatus "U5D1.BG12" )
				)
				( pin "cd_vcc_core(8)"
					( attribute "PN" "BF13"
						( Origin gPackager )
					)
					( objectStatus "U5D1.BF13" )
				)
				( pin "cd_vcc_core(9)"
					( attribute "PN" "BF11"
						( Origin gPackager )
					)
					( objectStatus "U5D1.BF11" )
				)
				( pin "cd_vcc_core(10)"
					( attribute "PN" "BE14"
						( Origin gPackager )
					)
					( objectStatus "U5D1.BE14" )
				)
				( pin "cd_vcc_core(11)"
					( attribute "PN" "BE12"
						( Origin gPackager )
					)
					( objectStatus "U5D1.BE12" )
				)
				( pin "cd_vcc_core(12)"
					( attribute "PN" "BD13"
						( Origin gPackager )
					)
					( objectStatus "U5D1.BD13" )
				)
				( pin "cd_vccin(0)"
					( attribute "PN" "BT27"
						( Origin gPackager )
					)
					( objectStatus "U5D1.BT27" )
				)
				( pin "cd_vccin(1)"
					( attribute "PN" "BU26"
						( Origin gPackager )
					)
					( objectStatus "U5D1.BU26" )
				)
				( pin "cd_vccin(2)"
					( attribute "PN" "BV27"
						( Origin gPackager )
					)
					( objectStatus "U5D1.BV27" )
				)
				( pin "cd_vccin(3)"
					( attribute "PN" "BY27"
						( Origin gPackager )
					)
					( objectStatus "U5D1.BY27" )
				)
				( pin "cd_vccp(0)"
					( attribute "PN" "BV15"
						( Origin gPackager )
					)
					( objectStatus "U5D1.BV15" )
				)
				( pin "cd_vccp(1)"
					( attribute "PN" "BV13"
						( Origin gPackager )
					)
					( objectStatus "U5D1.BV13" )
				)
				( pin "cd_vccp(2)"
					( attribute "PN" "BV11"
						( Origin gPackager )
					)
					( objectStatus "U5D1.BV11" )
				)
				( pin "cd_vccp(3)"
					( attribute "PN" "BU14"
						( Origin gPackager )
					)
					( objectStatus "U5D1.BU14" )
				)
				( pin "cd_vccp(4)"
					( attribute "PN" "BU12"
						( Origin gPackager )
					)
					( objectStatus "U5D1.BU12" )
				)
				( pin "cd_vccp(5)"
					( attribute "PN" "BT15"
						( Origin gPackager )
					)
					( objectStatus "U5D1.BT15" )
				)
				( pin "cd_vccp(6)"
					( attribute "PN" "BT13"
						( Origin gPackager )
					)
					( objectStatus "U5D1.BT13" )
				)
				( pin "cd_vccp(7)"
					( attribute "PN" "BT11"
						( Origin gPackager )
					)
					( objectStatus "U5D1.BT11" )
				)
				( pin "cd_vccp(8)"
					( attribute "PN" "BR14"
						( Origin gPackager )
					)
					( objectStatus "U5D1.BR14" )
				)
				( pin "cd_vccp(9)"
					( attribute "PN" "BR12"
						( Origin gPackager )
					)
					( objectStatus "U5D1.BR12" )
				)
				( pin "cd_vccp(10)"
					( attribute "PN" "BP15"
						( Origin gPackager )
					)
					( objectStatus "U5D1.BP15" )
				)
				( pin "cd_vccp(11)"
					( attribute "PN" "BP13"
						( Origin gPackager )
					)
					( objectStatus "U5D1.BP13" )
				)
				( pin "cd_vccp(12)"
					( attribute "PN" "BP11"
						( Origin gPackager )
					)
					( objectStatus "U5D1.BP11" )
				)
				( pin "cd_vccp(13)"
					( attribute "PN" "BN14"
						( Origin gPackager )
					)
					( objectStatus "U5D1.BN14" )
				)
				( pin "cd_vccp(14)"
					( attribute "PN" "BN12"
						( Origin gPackager )
					)
					( objectStatus "U5D1.BN12" )
				)
				( pin "cd_vccp(15)"
					( attribute "PN" "BM11"
						( Origin gPackager )
					)
					( objectStatus "U5D1.BM11" )
				)
				( pin "cd_vpp(0)"
					( attribute "PN" "B11"
						( Origin gPackager )
					)
					( objectStatus "U5D1.B11" )
				)
				( pin "cd_vpp(1)"
					( attribute "PN" "A12"
						( Origin gPackager )
					)
					( objectStatus "U5D1.A12" )
				)
				( pin "cd_vpp(2)"
					( attribute "PN" "A10"
						( Origin gPackager )
					)
					( objectStatus "U5D1.A10" )
				)
				( pin "cd_vpp(3)"
					( attribute "PN" "A8"
						( Origin gPackager )
					)
					( objectStatus "U5D1.A8" )
				)
				( pin "vcc33"
					( attribute "PN" "CY55"
						( Origin gPackager )
					)
					( objectStatus "U5D1.CY55" )
				)
				( pin "vccio(20)"
					( attribute "PN" "CM15"
						( Origin gPackager )
					)
					( objectStatus "U5D1.CM15" )
				)
				( pin "vccio(21)"
					( attribute "PN" "CL12"
						( Origin gPackager )
					)
					( objectStatus "U5D1.CL12" )
				)
				( pin "vccio(22)"
					( attribute "PN" "CK5"
						( Origin gPackager )
					)
					( objectStatus "U5D1.CK5" )
				)
				( pin "vccio(23)"
					( attribute "PN" "CV7"
						( Origin gPackager )
					)
					( objectStatus "U5D1.CV7" )
				)
				( pin "vccio(24)"
					( attribute "PN" "CH9"
						( Origin gPackager )
					)
					( objectStatus "U5D1.CH9" )
				)
				( pin "vccio(25)"
					( attribute "PN" "D7"
						( Origin gPackager )
					)
					( objectStatus "U5D1.D7" )
				)
				( pin "vccio(26)"
					( attribute "PN" "CE18"
						( Origin gPackager )
					)
					( objectStatus "U5D1.CE18" )
				)
				( pin "vccio(27)"
					( attribute "PN" "CD9"
						( Origin gPackager )
					)
					( objectStatus "U5D1.CD9" )
				)
				( pin "vccio(28)"
					( attribute "PN" "CB17"
						( Origin gPackager )
					)
					( objectStatus "U5D1.CB17" )
				)
				( pin "vccio(29)"
					( attribute "PN" "CB13"
						( Origin gPackager )
					)
					( objectStatus "U5D1.CB13" )
				)
				( pin "vccio(30)"
					( attribute "PN" "BP25"
						( Origin gPackager )
					)
					( objectStatus "U5D1.BP25" )
				)
				( pin "vccio(31)"
					( attribute "PN" "BJ24"
						( Origin gPackager )
					)
					( objectStatus "U5D1.BJ24" )
				)
				( pin "vccio(32)"
					( attribute "PN" "BF23"
						( Origin gPackager )
					)
					( objectStatus "U5D1.BF23" )
				)
				( pin "vccio(33)"
					( attribute "PN" "DA14"
						( Origin gPackager )
					)
					( objectStatus "U5D1.DA14" )
				)
				( pin "vccio(34)"
					( attribute "PN" "BB5"
						( Origin gPackager )
					)
					( objectStatus "U5D1.BB5" )
				)
				( pin "vccio(35)"
					( attribute "PN" "BA24"
						( Origin gPackager )
					)
					( objectStatus "U5D1.BA24" )
				)
				( pin "vccio(36)"
					( attribute "PN" "AY11"
						( Origin gPackager )
					)
					( objectStatus "U5D1.AY11" )
				)
				( pin "vccio(37)"
					( attribute "PN" "AW6"
						( Origin gPackager )
					)
					( objectStatus "U5D1.AW6" )
				)
				( pin "vccio(38)"
					( attribute "PN" "AT11"
						( Origin gPackager )
					)
					( objectStatus "U5D1.AT11" )
				)
				( pin "vccio(39)"
					( attribute "PN" "DD7"
						( Origin gPackager )
					)
					( objectStatus "U5D1.DD7" )
				)
				( pin "vccio(40)"
					( attribute "PN" "AN10"
						( Origin gPackager )
					)
					( objectStatus "U5D1.AN10" )
				)
				( pin "vccio(41)"
					( attribute "PN" "DF13"
						( Origin gPackager )
					)
					( objectStatus "U5D1.DF13" )
				)
				( pin "vccio(42)"
					( attribute "PN" "AH9"
						( Origin gPackager )
					)
					( objectStatus "U5D1.AH9" )
				)
				( pin "vccio(43)"
					( attribute "PN" "AC4"
						( Origin gPackager )
					)
					( objectStatus "U5D1.AC4" )
				)
				( pin "vccio(44)"
					( attribute "PN" "AC20"
						( Origin gPackager )
					)
					( objectStatus "U5D1.AC20" )
				)
				( pin "vccio(45)"
					( attribute "PN" "AA10"
						( Origin gPackager )
					)
					( objectStatus "U5D1.AA10" )
				)
				( pin "vccio(46)"
					( attribute "PN" "W6"
						( Origin gPackager )
					)
					( objectStatus "U5D1.W6" )
				)
				( pin "vccio(47)"
					( attribute "PN" "W4"
						( Origin gPackager )
					)
					( objectStatus "U5D1.W4" )
				)
				( pin "vccio(48)"
					( attribute "PN" "DF21"
						( Origin gPackager )
					)
					( objectStatus "U5D1.DF21" )
				)
				( pin "vccio(49)"
					( attribute "PN" "U14"
						( Origin gPackager )
					)
					( objectStatus "U5D1.U14" )
				)
				( pin "vccio(50)"
					( attribute "PN" "T3"
						( Origin gPackager )
					)
					( objectStatus "U5D1.T3" )
				)
				( pin "vccio(51)"
					( attribute "PN" "P5"
						( Origin gPackager )
					)
					( objectStatus "U5D1.P5" )
				)
				( pin "vccio(52)"
					( attribute "PN" "M21"
						( Origin gPackager )
					)
					( objectStatus "U5D1.M21" )
				)
				( pin "vccio(53)"
					( attribute "PN" "M11"
						( Origin gPackager )
					)
					( objectStatus "U5D1.M11" )
				)
				( pin "vccio(54)"
					( attribute "PN" "DG8"
						( Origin gPackager )
					)
					( objectStatus "U5D1.DG8" )
				)
				( pin "vccio(55)"
					( attribute "PN" "DH7"
						( Origin gPackager )
					)
					( objectStatus "U5D1.DH7" )
				)
				( pin "vccio(56)"
					( attribute "PN" "L16"
						( Origin gPackager )
					)
					( objectStatus "U5D1.L16" )
				)
				( pin "vccio(57)"
					( attribute "PN" "L14"
						( Origin gPackager )
					)
					( objectStatus "U5D1.L14" )
				)
				( pin "vccio(58)"
					( attribute "PN" "J10"
						( Origin gPackager )
					)
					( objectStatus "U5D1.J10" )
				)
				( pin "vccio(59)"
					( attribute "PN" "H13"
						( Origin gPackager )
					)
					( objectStatus "U5D1.H13" )
				)
				( pin "vccio(60)"
					( attribute "PN" "DJ16"
						( Origin gPackager )
					)
					( objectStatus "U5D1.DJ16" )
				)
				( pin "vccio(61)"
					( attribute "PN" "DM17"
						( Origin gPackager )
					)
					( objectStatus "U5D1.DM17" )
				)
				( pin "vccio(62)"
					( attribute "PN" "DN8"
						( Origin gPackager )
					)
					( objectStatus "U5D1.DN8" )
				)
				( pin "vccio(63)"
					( attribute "PN" "DP19"
						( Origin gPackager )
					)
					( objectStatus "U5D1.DP19" )
				)
				( pin "vccio(64)"
					( attribute "PN" "DR10"
						( Origin gPackager )
					)
					( objectStatus "U5D1.DR10" )
				)
				( pin "vccio(65)"
					( attribute "PN" "DR2"
						( Origin gPackager )
					)
					( objectStatus "U5D1.DR2" )
				)
				( pin "vccio(66)"
					( attribute "PN" "DU20"
						( Origin gPackager )
					)
					( objectStatus "U5D1.DU20" )
				)
				( pin "vccio(67)"
					( attribute "PN" "EA12"
						( Origin gPackager )
					)
					( objectStatus "U5D1.EA12" )
				)
				( pin "vccio(68)"
					( attribute "PN" "EB15"
						( Origin gPackager )
					)
					( objectStatus "U5D1.EB15" )
				)
				( pin "vccio(69)"
					( attribute "PN" "J2"
						( Origin gPackager )
					)
					( objectStatus "U5D1.J2" )
				)
				( pin "vccio(70)"
					( attribute "PN" "K15"
						( Origin gPackager )
					)
					( objectStatus "U5D1.K15" )
				)
				( pin "vccio(71)"
					( attribute "PN" "M7"
						( Origin gPackager )
					)
					( objectStatus "U5D1.M7" )
				)
				( pin "vccio(72)"
					( attribute "PN" "M9"
						( Origin gPackager )
					)
					( objectStatus "U5D1.M9" )
				)
				( pin "vccio(73)"
					( attribute "PN" "N18"
						( Origin gPackager )
					)
					( objectStatus "U5D1.N18" )
				)
				( pin "vccio(74)"
					( attribute "PN" "W10"
						( Origin gPackager )
					)
					( objectStatus "U5D1.W10" )
				)
				( pin "vccio(75)"
					( attribute "PN" "BC26"
						( Origin gPackager )
					)
					( objectStatus "U5D1.BC26" )
				)
				( pin "vccio(76)"
					( attribute "PN" "BB27"
						( Origin gPackager )
					)
					( objectStatus "U5D1.BB27" )
				)
				( pin "vccio(77)"
					( attribute "PN" "BA26"
						( Origin gPackager )
					)
					( objectStatus "U5D1.BA26" )
				)
				( pin "vccio(78)"
					( attribute "PN" "AY27"
						( Origin gPackager )
					)
					( objectStatus "U5D1.AY27" )
				)
				( pin "vccio(79)"
					( attribute "PN" "AW26"
						( Origin gPackager )
					)
					( objectStatus "U5D1.AW26" )
				)
				( pin "vccio(80)"
					( attribute "PN" "AV27"
						( Origin gPackager )
					)
					( objectStatus "U5D1.AV27" )
				)
				( pin "vccio(81)"
					( attribute "PN" "CF27"
						( Origin gPackager )
					)
					( objectStatus "U5D1.CF27" )
				)
				( pin "vccio(82)"
					( attribute "PN" "CD27"
						( Origin gPackager )
					)
					( objectStatus "U5D1.CD27" )
				)
				( pin "vccio(83)"
					( attribute "PN" "CC26"
						( Origin gPackager )
					)
					( objectStatus "U5D1.CC26" )
				)
				( pin "vccio(84)"
					( attribute "PN" "CJ28"
						( Origin gPackager )
					)
					( objectStatus "U5D1.CJ28" )
				)
				( pin "vccio(85)"
					( attribute "PN" "CH27"
						( Origin gPackager )
					)
					( objectStatus "U5D1.CH27" )
				)
				( pin "vccio(86)"
					( attribute "PN" "BM27"
						( Origin gPackager )
					)
					( objectStatus "U5D1.BM27" )
				)
				( pin "vccio(87)"
					( attribute "PN" "BL26"
						( Origin gPackager )
					)
					( objectStatus "U5D1.BL26" )
				)
				( pin "vccio(88)"
					( attribute "PN" "BK27"
						( Origin gPackager )
					)
					( objectStatus "U5D1.BK27" )
				)
				( pin "vccio(89)"
					( attribute "PN" "BK25"
						( Origin gPackager )
					)
					( objectStatus "U5D1.BK25" )
				)
				( pin "vccio(90)"
					( attribute "PN" "BJ26"
						( Origin gPackager )
					)
					( objectStatus "U5D1.BJ26" )
				)
				( pin "vccio(91)"
					( attribute "PN" "BH27"
						( Origin gPackager )
					)
					( objectStatus "U5D1.BH27" )
				)
				( pin "vccio(92)"
					( attribute "PN" "BH25"
						( Origin gPackager )
					)
					( objectStatus "U5D1.BH25" )
				)
				( pin "vccio(93)"
					( attribute "PN" "BG26"
						( Origin gPackager )
					)
					( objectStatus "U5D1.BG26" )
				)
				( pin "vccio(94)"
					( attribute "PN" "BF27"
						( Origin gPackager )
					)
					( objectStatus "U5D1.BF27" )
				)
				( pin "vccio(95)"
					( attribute "PN" "AE36"
						( Origin gPackager )
					)
					( objectStatus "U5D1.AE36" )
				)
				( pin "vccio(96)"
					( attribute "PN" "AD37"
						( Origin gPackager )
					)
					( objectStatus "U5D1.AD37" )
				)
				( pin "vccio(97)"
					( attribute "PN" "AC36"
						( Origin gPackager )
					)
					( objectStatus "U5D1.AC36" )
				)
				( pin "vccio(98)"
					( attribute "PN" "AF35"
						( Origin gPackager )
					)
					( objectStatus "U5D1.AF35" )
				)
				( pin "vccio(99)"
					( attribute "PN" "AD35"
						( Origin gPackager )
					)
					( objectStatus "U5D1.AD35" )
				)
				( pin "vccio(100)"
					( attribute "PN" "AE34"
						( Origin gPackager )
					)
					( objectStatus "U5D1.AE34" )
				)
				( pin "vccio(101)"
					( attribute "PN" "AG34"
						( Origin gPackager )
					)
					( objectStatus "U5D1.AG34" )
				)
				( pin "vccio(102)"
					( attribute "PN" "AM29"
						( Origin gPackager )
					)
					( objectStatus "U5D1.AM29" )
				)
				( pin "vccio(103)"
					( attribute "PN" "AL28"
						( Origin gPackager )
					)
					( objectStatus "U5D1.AL28" )
				)
				( pin "vccio(104)"
					( attribute "PN" "AR28"
						( Origin gPackager )
					)
					( objectStatus "U5D1.AR28" )
				)
				( pin "vccsa(0)"
					( attribute "PN" "CJ66"
						( Origin gPackager )
					)
					( objectStatus "U5D1.CJ66" )
				)
				( pin "vccsa(1)"
					( attribute "PN" "CJ64"
						( Origin gPackager )
					)
					( objectStatus "U5D1.CJ64" )
				)
				( pin "vccsa(2)"
					( attribute "PN" "CH75"
						( Origin gPackager )
					)
					( objectStatus "U5D1.CH75" )
				)
				( pin "vccsa(3)"
					( attribute "PN" "CH65"
						( Origin gPackager )
					)
					( objectStatus "U5D1.CH65" )
				)
				( pin "vccsa(4)"
					( attribute "PN" "CG74"
						( Origin gPackager )
					)
					( objectStatus "U5D1.CG74" )
				)
				( pin "vccsa(5)"
					( attribute "PN" "CG66"
						( Origin gPackager )
					)
					( objectStatus "U5D1.CG66" )
				)
				( pin "vccsa(6)"
					( attribute "PN" "CG64"
						( Origin gPackager )
					)
					( objectStatus "U5D1.CG64" )
				)
				( pin "vccsa(7)"
					( attribute "PN" "CF75"
						( Origin gPackager )
					)
					( objectStatus "U5D1.CF75" )
				)
				( pin "vccsa(8)"
					( attribute "PN" "CF73"
						( Origin gPackager )
					)
					( objectStatus "U5D1.CF73" )
				)
				( pin "vccsa(9)"
					( attribute "PN" "CF67"
						( Origin gPackager )
					)
					( objectStatus "U5D1.CF67" )
				)
				( pin "vccsa(10)"
					( attribute "PN" "CF65"
						( Origin gPackager )
					)
					( objectStatus "U5D1.CF65" )
				)
				( pin "vccsa(11)"
					( attribute "PN" "CE74"
						( Origin gPackager )
					)
					( objectStatus "U5D1.CE74" )
				)
				( pin "vccsa(12)"
					( attribute "PN" "CE72"
						( Origin gPackager )
					)
					( objectStatus "U5D1.CE72" )
				)
				( pin "vccsa(13)"
					( attribute "PN" "CE68"
						( Origin gPackager )
					)
					( objectStatus "U5D1.CE68" )
				)
				( pin "vccsa(14)"
					( attribute "PN" "CE66"
						( Origin gPackager )
					)
					( objectStatus "U5D1.CE66" )
				)
				( pin "vccsa(15)"
					( attribute "PN" "CE64"
						( Origin gPackager )
					)
					( objectStatus "U5D1.CE64" )
				)
				( pin "vccsa(16)"
					( attribute "PN" "CD71"
						( Origin gPackager )
					)
					( objectStatus "U5D1.CD71" )
				)
				( pin "vccsa(17)"
					( attribute "PN" "CD69"
						( Origin gPackager )
					)
					( objectStatus "U5D1.CD69" )
				)
				( pin "vccsa(18)"
					( attribute "PN" "CD67"
						( Origin gPackager )
					)
					( objectStatus "U5D1.CD67" )
				)
				( pin "vccsa(19)"
					( attribute "PN" "CD65"
						( Origin gPackager )
					)
					( objectStatus "U5D1.CD65" )
				)
				( pin "vccsa(20)"
					( attribute "PN" "CC70"
						( Origin gPackager )
					)
					( objectStatus "U5D1.CC70" )
				)
				( pin "vccsa(21)"
					( attribute "PN" "CC68"
						( Origin gPackager )
					)
					( objectStatus "U5D1.CC68" )
				)
				( pin "vccsa(22)"
					( attribute "PN" "CC66"
						( Origin gPackager )
					)
					( objectStatus "U5D1.CC66" )
				)
				( pin "vccsa(23)"
					( attribute "PN" "CB69"
						( Origin gPackager )
					)
					( objectStatus "U5D1.CB69" )
				)
				( pin "vccsa(24)"
					( attribute "PN" "CB67"
						( Origin gPackager )
					)
					( objectStatus "U5D1.CB67" )
				)
				( pin "vccsa(25)"
					( attribute "PN" "CB65"
						( Origin gPackager )
					)
					( objectStatus "U5D1.CB65" )
				)
			)
			( gate "@baseboard_fab2_lib.baseboard_fab2(sch_1):page39_i127"
				( attribute "CDS_LIB" "chpset_lib"
					( Origin gPackager )
				)
				( attribute "CDS_LOCATION" "U5D1"
					( Origin gPackager )
				)
				( attribute "CDS_SEC" "22"
					( Origin gPackager )
				)
				( attribute "LOCATION" "U5D1"
					( Origin gFrontEnd )
				)
				( attribute "MATERIAL" "IC"
					( Origin gFrontEnd )
				)
				( attribute "PACK_TYPE" "BGA1"
					( Origin gFrontEnd )
				)
				( attribute "PART_NUMBER" "TBD"
					( Origin gFrontEnd )
				)
				( attribute "PHYS_PAGE" "39"
					( Origin gFrontEnd )
				)
				( attribute "ROOM" "CPU0"
					( Origin gFrontEnd )
				)
				( attribute "ROT" "0"
					( Origin gFrontEnd )
				)
				( attribute "SEC" "22"
					( Origin gFrontEnd )
				)
				( attribute "SEC_TYPE" "BGA1"
					( Origin gFrontEnd )
				)
				( attribute "VER" "22"
					( Origin gFrontEnd )
				)
				( attribute "XY" "(-4250,2550)"
					( Origin gFrontEnd )
				)
				( attribute "CHIPS_PART_NAME" "SKX_EXT_B"
					( Origin gPackager )
				)
				( attribute "CDS_PART_NAME" "SKX_EXT_B_BGA1-IC,TBD"
					( Origin gPackager )
				)
				( objectStatus "U5D1" )
				( pin "cd_vcc_core_sense"
					( attribute "PN" "BN16"
						( Origin gPackager )
					)
					( objectStatus "U5D1.BN16" )
				)
				( pin "cd_vccp_sense(0)"
					( attribute "PN" "BU16"
						( Origin gPackager )
					)
					( objectStatus "U5D1.BU16" )
				)
				( pin "cd_vccp_sense(1)"
					( attribute "PN" "BT17"
						( Origin gPackager )
					)
					( objectStatus "U5D1.BT17" )
				)
				( pin "cd_vss_vcc_core_sense"
					( attribute "PN" "BL16"
						( Origin gPackager )
					)
					( objectStatus "U5D1.BL16" )
				)
				( pin "rsvd(0)"
					( attribute "PN" "EF83"
						( Origin gPackager )
					)
					( objectStatus "U5D1.EF83" )
				)
				( pin "rsvd(1)"
					( attribute "PN" "EF81"
						( Origin gPackager )
					)
					( objectStatus "U5D1.EF81" )
				)
				( pin "rsvd(2)"
					( attribute "PN" "EF77"
						( Origin gPackager )
					)
					( objectStatus "U5D1.EF77" )
				)
				( pin "rsvd(3)"
					( attribute "PN" "EF47"
						( Origin gPackager )
					)
					( objectStatus "U5D1.EF47" )
				)
				( pin "rsvd(4)"
					( attribute "PN" "EE84"
						( Origin gPackager )
					)
					( objectStatus "U5D1.EE84" )
				)
				( pin "rsvd(5)"
					( attribute "PN" "EE82"
						( Origin gPackager )
					)
					( objectStatus "U5D1.EE82" )
				)
				( pin "rsvd(6)"
					( attribute "PN" "EE6"
						( Origin gPackager )
					)
					( objectStatus "U5D1.EE6" )
				)
				( pin "rsvd(7)"
					( attribute "PN" "EE46"
						( Origin gPackager )
					)
					( objectStatus "U5D1.EE46" )
				)
				( pin "rsvd(8)"
					( attribute "PN" "EE16"
						( Origin gPackager )
					)
					( objectStatus "U5D1.EE16" )
				)
				( pin "rsvd(9)"
					( attribute "PN" "ED83"
						( Origin gPackager )
					)
					( objectStatus "U5D1.ED83" )
				)
				( pin "rsvd(10)"
					( attribute "PN" "ED5"
						( Origin gPackager )
					)
					( objectStatus "U5D1.ED5" )
				)
				( pin "rsvd(11)"
					( attribute "PN" "ED45"
						( Origin gPackager )
					)
					( objectStatus "U5D1.ED45" )
				)
				( pin "rsvd(12)"
					( attribute "PN" "EC84"
						( Origin gPackager )
					)
					( objectStatus "U5D1.EC84" )
				)
				( pin "rsvd(13)"
					( attribute "PN" "EC44"
						( Origin gPackager )
					)
					( objectStatus "U5D1.EC44" )
				)
				( pin "rsvd(14)"
					( attribute "PN" "EC4"
						( Origin gPackager )
					)
					( objectStatus "U5D1.EC4" )
				)
				( pin "rsvd(15)"
					( attribute "PN" "EC16"
						( Origin gPackager )
					)
					( objectStatus "U5D1.EC16" )
				)
				( pin "rsvd(16)"
					( attribute "PN" "EB85"
						( Origin gPackager )
					)
					( objectStatus "U5D1.EB85" )
				)
				( pin "rsvd(17)"
					( attribute "PN" "EB5"
						( Origin gPackager )
					)
					( objectStatus "U5D1.EB5" )
				)
				( pin "rsvd(18)"
					( attribute "PN" "EB3"
						( Origin gPackager )
					)
					( objectStatus "U5D1.EB3" )
				)
				( pin "rsvd(19)"
					( attribute "PN" "EA44"
						( Origin gPackager )
					)
					( objectStatus "U5D1.EA44" )
				)
				( pin "rsvd(20)"
					( attribute "PN" "EA4"
						( Origin gPackager )
					)
					( objectStatus "U5D1.EA4" )
				)
				( pin "rsvd(21)"
					( attribute "PN" "DY3"
						( Origin gPackager )
					)
					( objectStatus "U5D1.DY3" )
				)
				( pin "rsvd(22)"
					( attribute "PN" "DW46"
						( Origin gPackager )
					)
					( objectStatus "U5D1.DW46" )
				)
				( pin "rsvd(23)"
					( attribute "PN" "DW44"
						( Origin gPackager )
					)
					( objectStatus "U5D1.DW44" )
				)
				( pin "rsvd(24)"
					( attribute "PN" "DV71"
						( Origin gPackager )
					)
					( objectStatus "U5D1.DV71" )
				)
				( pin "rsvd(25)"
					( attribute "PN" "DV61"
						( Origin gPackager )
					)
					( objectStatus "U5D1.DV61" )
				)
				( pin "rsvd(26)"
					( attribute "PN" "DU44"
						( Origin gPackager )
					)
					( objectStatus "U5D1.DU44" )
				)
				( pin "rsvd(27)"
					( attribute "PN" "DT71"
						( Origin gPackager )
					)
					( objectStatus "U5D1.DT71" )
				)
				( pin "rsvd(28)"
					( attribute "PN" "DR44"
						( Origin gPackager )
					)
					( objectStatus "U5D1.DR44" )
				)
				( pin "rsvd(29)"
					( attribute "PN" "DP65"
						( Origin gPackager )
					)
					( objectStatus "U5D1.DP65" )
				)
				( pin "rsvd(30)"
					( attribute "PN" "DP17"
						( Origin gPackager )
					)
					( objectStatus "U5D1.DP17" )
				)
				( pin "rsvd(31)"
					( attribute "PN" "DN66"
						( Origin gPackager )
					)
					( objectStatus "U5D1.DN66" )
				)
				( pin "rsvd(32)"
					( attribute "PN" "DN62"
						( Origin gPackager )
					)
					( objectStatus "U5D1.DN62" )
				)
				( pin "rsvd(33)"
					( attribute "PN" "DM67"
						( Origin gPackager )
					)
					( objectStatus "U5D1.DM67" )
				)
				( pin "rsvd(34)"
					( attribute "PN" "DL66"
						( Origin gPackager )
					)
					( objectStatus "U5D1.DL66" )
				)
				( pin "rsvd(35)"
					( attribute "PN" "DL38"
						( Origin gPackager )
					)
					( objectStatus "U5D1.DL38" )
				)
				( pin "rsvd(36)"
					( attribute "PN" "DK67"
						( Origin gPackager )
					)
					( objectStatus "U5D1.DK67" )
				)
				( pin "rsvd(37)"
					( attribute "PN" "DK65"
						( Origin gPackager )
					)
					( objectStatus "U5D1.DK65" )
				)
				( pin "rsvd(38)"
					( attribute "PN" "DK37"
						( Origin gPackager )
					)
					( objectStatus "U5D1.DK37" )
				)
				( pin "rsvd(39)"
					( attribute "PN" "DK15"
						( Origin gPackager )
					)
					( objectStatus "U5D1.DK15" )
				)
				( pin "rsvd(40)"
					( attribute "PN" "DJ66"
						( Origin gPackager )
					)
					( objectStatus "U5D1.DJ66" )
				)
				( pin "rsvd(41)"
					( attribute "PN" "DJ36"
						( Origin gPackager )
					)
					( objectStatus "U5D1.DJ36" )
				)
				( pin "rsvd(42)"
					( attribute "PN" "DH65"
						( Origin gPackager )
					)
					( objectStatus "U5D1.DH65" )
				)
				( pin "rsvd(43)"
					( attribute "PN" "DG64"
						( Origin gPackager )
					)
					( objectStatus "U5D1.DG64" )
				)
				( pin "rsvd(44)"
					( attribute "PN" "DG36"
						( Origin gPackager )
					)
					( objectStatus "U5D1.DG36" )
				)
				( pin "rsvd(45)"
					( attribute "PN" "DD51"
						( Origin gPackager )
					)
					( objectStatus "U5D1.DD51" )
				)
				( pin "rsvd(46)"
					( attribute "PN" "DC52"
						( Origin gPackager )
					)
					( objectStatus "U5D1.DC52" )
				)
				( pin "rsvd(47)"
					( attribute "PN" "DC46"
						( Origin gPackager )
					)
					( objectStatus "U5D1.DC46" )
				)
				( pin "rsvd(48)"
					( attribute "PN" "DA56"
						( Origin gPackager )
					)
					( objectStatus "U5D1.DA56" )
				)
				( pin "rsvd(49)"
					( attribute "PN" "DA54"
						( Origin gPackager )
					)
					( objectStatus "U5D1.DA54" )
				)
				( pin "rsvd(50)"
					( attribute "PN" "DA52"
						( Origin gPackager )
					)
					( objectStatus "U5D1.DA52" )
				)
				( pin "rsvd(51)"
					( attribute "PN" "DA40"
						( Origin gPackager )
					)
					( objectStatus "U5D1.DA40" )
				)
				( pin "rsvd(52)"
					( attribute "PN" "DA24"
						( Origin gPackager )
					)
					( objectStatus "U5D1.DA24" )
				)
				( pin "rsvd(53)"
					( attribute "PN" "CY73"
						( Origin gPackager )
					)
					( objectStatus "U5D1.CY73" )
				)
				( pin "rsvd(54)"
					( attribute "PN" "CY63"
						( Origin gPackager )
					)
					( objectStatus "U5D1.CY63" )
				)
				( pin "rsvd(55)"
					( attribute "PN" "CY57"
						( Origin gPackager )
					)
					( objectStatus "U5D1.CY57" )
				)
				( pin "rsvd(56)"
					( attribute "PN" "CY53"
						( Origin gPackager )
					)
					( objectStatus "U5D1.CY53" )
				)
				( pin "rsvd(57)"
					( attribute "PN" "CY39"
						( Origin gPackager )
					)
					( objectStatus "U5D1.CY39" )
				)
				( pin "rsvd(58)"
					( attribute "PN" "CY25"
						( Origin gPackager )
					)
					( objectStatus "U5D1.CY25" )
				)
				( pin "rsvd(59)"
					( attribute "PN" "CY23"
						( Origin gPackager )
					)
					( objectStatus "U5D1.CY23" )
				)
				( pin "rsvd(60)"
					( attribute "PN" "CW62"
						( Origin gPackager )
					)
					( objectStatus "U5D1.CW62" )
				)
				( pin "rsvd(61)"
					( attribute "PN" "CW60"
						( Origin gPackager )
					)
					( objectStatus "U5D1.CW60" )
				)
				( pin "rsvd(62)"
					( attribute "PN" "CW24"
						( Origin gPackager )
					)
					( objectStatus "U5D1.CW24" )
				)
				( pin "rsvd(63)"
					( attribute "PN" "CW22"
						( Origin gPackager )
					)
					( objectStatus "U5D1.CW22" )
				)
				( pin "rsvd(64)"
					( attribute "PN" "CV69"
						( Origin gPackager )
					)
					( objectStatus "U5D1.CV69" )
				)
				( pin "rsvd(65)"
					( attribute "PN" "CV23"
						( Origin gPackager )
					)
					( objectStatus "U5D1.CV23" )
				)
				( pin "rsvd(66)"
					( attribute "PN" "CU60"
						( Origin gPackager )
					)
					( objectStatus "U5D1.CU60" )
				)
				( pin "rsvd(67)"
					( attribute "PN" "CU6"
						( Origin gPackager )
					)
					( objectStatus "U5D1.CU6" )
				)
				( pin "rsvd(68)"
					( attribute "PN" "CU24"
						( Origin gPackager )
					)
					( objectStatus "U5D1.CU24" )
				)
				( pin "rsvd(69)"
					( attribute "PN" "CT69"
						( Origin gPackager )
					)
					( objectStatus "U5D1.CT69" )
				)
				( pin "rsvd(70)"
					( attribute "PN" "CT5"
						( Origin gPackager )
					)
					( objectStatus "U5D1.CT5" )
				)
				( pin "rsvd(71)"
					( attribute "PN" "CT23"
						( Origin gPackager )
					)
					( objectStatus "U5D1.CT23" )
				)
				( pin "rsvd(72)"
					( attribute "PN" "CR60"
						( Origin gPackager )
					)
					( objectStatus "U5D1.CR60" )
				)
				( pin "rsvd(73)"
					( attribute "PN" "CP31"
						( Origin gPackager )
					)
					( objectStatus "U5D1.CP31" )
				)
				( pin "rsvd(74)"
					( attribute "PN" "CP23"
						( Origin gPackager )
					)
					( objectStatus "U5D1.CP23" )
				)
				( pin "rsvd(75)"
					( attribute "PN" "CN28"
						( Origin gPackager )
					)
					( objectStatus "U5D1.CN28" )
				)
				( pin "rsvd(76)"
					( attribute "PN" "CN24"
						( Origin gPackager )
					)
					( objectStatus "U5D1.CN24" )
				)
				( pin "rsvd(77)"
					( attribute "PN" "CN22"
						( Origin gPackager )
					)
					( objectStatus "U5D1.CN22" )
				)
				( pin "rsvd(78)"
					( attribute "PN" "CM25"
						( Origin gPackager )
					)
					( objectStatus "U5D1.CM25" )
				)
				( pin "rsvd(79)"
					( attribute "PN" "CM23"
						( Origin gPackager )
					)
					( objectStatus "U5D1.CM23" )
				)
				( pin "rsvd(80)"
					( attribute "PN" "CL26"
						( Origin gPackager )
					)
					( objectStatus "U5D1.CL26" )
				)
				( pin "vccio(0)"
					( attribute "PN" "EE10"
						( Origin gPackager )
					)
					( objectStatus "U5D1.EE10" )
				)
				( pin "vccio(1)"
					( attribute "PN" "AE10"
						( Origin gPackager )
					)
					( objectStatus "U5D1.AE10" )
				)
				( pin "vccio(2)"
					( attribute "PN" "AF5"
						( Origin gPackager )
					)
					( objectStatus "U5D1.AF5" )
				)
				( pin "vccio(3)"
					( attribute "PN" "DV11"
						( Origin gPackager )
					)
					( objectStatus "U5D1.DV11" )
				)
				( pin "vccio(4)"
					( attribute "PN" "AM5"
						( Origin gPackager )
					)
					( objectStatus "U5D1.AM5" )
				)
				( pin "vccio(5)"
					( attribute "PN" "AT5"
						( Origin gPackager )
					)
					( objectStatus "U5D1.AT5" )
				)
				( pin "vccio(6)"
					( attribute "PN" "AT7"
						( Origin gPackager )
					)
					( objectStatus "U5D1.AT7" )
				)
				( pin "vccio(7)"
					( attribute "PN" "BE24"
						( Origin gPackager )
					)
					( objectStatus "U5D1.BE24" )
				)
				( pin "vccio(8)"
					( attribute "PN" "DK21"
						( Origin gPackager )
					)
					( objectStatus "U5D1.DK21" )
				)
				( pin "vccio(9)"
					( attribute "PN" "CF5"
						( Origin gPackager )
					)
					( objectStatus "U5D1.CF5" )
				)
				( pin "vccio(10)"
					( attribute "PN" "CG14"
						( Origin gPackager )
					)
					( objectStatus "U5D1.CG14" )
				)
				( pin "vccio(11)"
					( attribute "PN" "CL20"
						( Origin gPackager )
					)
					( objectStatus "U5D1.CL20" )
				)
				( pin "vccio(12)"
					( attribute "PN" "CP13"
						( Origin gPackager )
					)
					( objectStatus "U5D1.CP13" )
				)
				( pin "vccio(13)"
					( attribute "PN" "DE14"
						( Origin gPackager )
					)
					( objectStatus "U5D1.DE14" )
				)
				( pin "vccio(14)"
					( attribute "PN" "DC18"
						( Origin gPackager )
					)
					( objectStatus "U5D1.DC18" )
				)
				( pin "vccio(15)"
					( attribute "PN" "CY17"
						( Origin gPackager )
					)
					( objectStatus "U5D1.CY17" )
				)
				( pin "vccio(16)"
					( attribute "PN" "CU18"
						( Origin gPackager )
					)
					( objectStatus "U5D1.CU18" )
				)
				( pin "vccio(17)"
					( attribute "PN" "CV21"
						( Origin gPackager )
					)
					( objectStatus "U5D1.CV21" )
				)
				( pin "vccio(18)"
					( attribute "PN" "CU12"
						( Origin gPackager )
					)
					( objectStatus "U5D1.CU12" )
				)
				( pin "vccio(19)"
					( attribute "PN" "CN6"
						( Origin gPackager )
					)
					( objectStatus "U5D1.CN6" )
				)
				( pin "vccio_sense"
					( attribute "PN" "BH5"
						( Origin gPackager )
					)
					( objectStatus "U5D1.BH5" )
				)
				( pin "vccsa_sense"
					( attribute "PN" "CE76"
						( Origin gPackager )
					)
					( objectStatus "U5D1.CE76" )
				)
				( pin "vss_vccio_sense"
					( attribute "PN" "BF5"
						( Origin gPackager )
					)
					( objectStatus "U5D1.BF5" )
				)
				( pin "vss_vccsa_sense"
					( attribute "PN" "CG76"
						( Origin gPackager )
					)
					( objectStatus "U5D1.CG76" )
				)
			)
			( gate "@baseboard_fab2_lib.baseboard_fab2(sch_1):page40_i20"
				( attribute "CDS_LIB" "chpset_lib"
					( Origin gPackager )
				)
				( attribute "CDS_LOCATION" "U5D1"
					( Origin gPackager )
				)
				( attribute "CDS_SEC" "23"
					( Origin gPackager )
				)
				( attribute "LOCATION" "U5D1"
					( Origin gFrontEnd )
				)
				( attribute "MATERIAL" "IC"
					( Origin gFrontEnd )
				)
				( attribute "PACK_TYPE" "BGA1"
					( Origin gFrontEnd )
				)
				( attribute "PART_NUMBER" "TBD"
					( Origin gFrontEnd )
				)
				( attribute "PHYS_PAGE" "40"
					( Origin gFrontEnd )
				)
				( attribute "ROOM" "CPU0"
					( Origin gFrontEnd )
				)
				( attribute "ROT" "0"
					( Origin gFrontEnd )
				)
				( attribute "SEC" "23"
					( Origin gFrontEnd )
				)
				( attribute "SEC_TYPE" "BGA1"
					( Origin gFrontEnd )
				)
				( attribute "VER" "23"
					( Origin gFrontEnd )
				)
				( attribute "XY" "(-7050,2575)"
					( Origin gFrontEnd )
				)
				( attribute "CHIPS_PART_NAME" "SKX_EXT_B"
					( Origin gPackager )
				)
				( attribute "CDS_PART_NAME" "SKX_EXT_B_BGA1-IC,TBD"
					( Origin gPackager )
				)
				( objectStatus "U5D1" )
				( pin "vss(1094)"
					( attribute "PN" "J74"
						( Origin gPackager )
					)
					( objectStatus "U5D1.J74" )
				)
				( pin "vss(1095)"
					( attribute "PN" "J72"
						( Origin gPackager )
					)
					( objectStatus "U5D1.J72" )
				)
				( pin "vss(1096)"
					( attribute "PN" "J40"
						( Origin gPackager )
					)
					( objectStatus "U5D1.J40" )
				)
				( pin "vss(1097)"
					( attribute "PN" "J38"
						( Origin gPackager )
					)
					( objectStatus "U5D1.J38" )
				)
				( pin "vss(1098)"
					( attribute "PN" "J34"
						( Origin gPackager )
					)
					( objectStatus "U5D1.J34" )
				)
				( pin "vss(1099)"
					( attribute "PN" "J32"
						( Origin gPackager )
					)
					( objectStatus "U5D1.J32" )
				)
				( pin "vss(1100)"
					( attribute "PN" "J28"
						( Origin gPackager )
					)
					( objectStatus "U5D1.J28" )
				)
				( pin "vss(1101)"
					( attribute "PN" "J26"
						( Origin gPackager )
					)
					( objectStatus "U5D1.J26" )
				)
				( pin "vss(1102)"
					( attribute "PN" "J22"
						( Origin gPackager )
					)
					( objectStatus "U5D1.J22" )
				)
				( pin "vss(1103)"
					( attribute "PN" "J14"
						( Origin gPackager )
					)
					( objectStatus "U5D1.J14" )
				)
				( pin "vss(1104)"
					( attribute "PN" "J12"
						( Origin gPackager )
					)
					( objectStatus "U5D1.J12" )
				)
				( pin "vss(1105)"
					( attribute "PN" "J4"
						( Origin gPackager )
					)
					( objectStatus "U5D1.J4" )
				)
				( pin "vss(1106)"
					( attribute "PN" "DN44"
						( Origin gPackager )
					)
					( objectStatus "U5D1.DN44" )
				)
				( pin "vss(1107)"
					( attribute "PN" "H75"
						( Origin gPackager )
					)
					( objectStatus "U5D1.H75" )
				)
				( pin "vss(1108)"
					( attribute "PN" "H71"
						( Origin gPackager )
					)
					( objectStatus "U5D1.H71" )
				)
				( pin "vss(1109)"
					( attribute "PN" "H65"
						( Origin gPackager )
					)
					( objectStatus "U5D1.H65" )
				)
				( pin "vss(1110)"
					( attribute "PN" "H41"
						( Origin gPackager )
					)
					( objectStatus "U5D1.H41" )
				)
				( pin "vss(1111)"
					( attribute "PN" "H39"
						( Origin gPackager )
					)
					( objectStatus "U5D1.H39" )
				)
				( pin "vss(1112)"
					( attribute "PN" "H37"
						( Origin gPackager )
					)
					( objectStatus "U5D1.H37" )
				)
				( pin "vss(1113)"
					( attribute "PN" "H35"
						( Origin gPackager )
					)
					( objectStatus "U5D1.H35" )
				)
				( pin "vss(1114)"
					( attribute "PN" "H33"
						( Origin gPackager )
					)
					( objectStatus "U5D1.H33" )
				)
				( pin "vss(1115)"
					( attribute "PN" "H31"
						( Origin gPackager )
					)
					( objectStatus "U5D1.H31" )
				)
				( pin "vss(1116)"
					( attribute "PN" "H29"
						( Origin gPackager )
					)
					( objectStatus "U5D1.H29" )
				)
				( pin "vss(1117)"
					( attribute "PN" "H27"
						( Origin gPackager )
					)
					( objectStatus "U5D1.H27" )
				)
				( pin "vss(1118)"
					( attribute "PN" "H25"
						( Origin gPackager )
					)
					( objectStatus "U5D1.H25" )
				)
				( pin "vss(1119)"
					( attribute "PN" "H11"
						( Origin gPackager )
					)
					( objectStatus "U5D1.H11" )
				)
				( pin "vss(1120)"
					( attribute "PN" "H3"
						( Origin gPackager )
					)
					( objectStatus "U5D1.H3" )
				)
				( pin "vss(1121)"
					( attribute "PN" "G82"
						( Origin gPackager )
					)
					( objectStatus "U5D1.G82" )
				)
				( pin "vss(1122)"
					( attribute "PN" "G80"
						( Origin gPackager )
					)
					( objectStatus "U5D1.G80" )
				)
				( pin "vss(1123)"
					( attribute "PN" "G78"
						( Origin gPackager )
					)
					( objectStatus "U5D1.G78" )
				)
				( pin "vss(1124)"
					( attribute "PN" "G76"
						( Origin gPackager )
					)
					( objectStatus "U5D1.G76" )
				)
				( pin "vss(1125)"
					( attribute "PN" "G70"
						( Origin gPackager )
					)
					( objectStatus "U5D1.G70" )
				)
				( pin "vss(1126)"
					( attribute "PN" "G66"
						( Origin gPackager )
					)
					( objectStatus "U5D1.G66" )
				)
				( pin "vss(1127)"
					( attribute "PN" "G42"
						( Origin gPackager )
					)
					( objectStatus "U5D1.G42" )
				)
				( pin "vss(1128)"
					( attribute "PN" "G38"
						( Origin gPackager )
					)
					( objectStatus "U5D1.G38" )
				)
				( pin "vss(1129)"
					( attribute "PN" "G36"
						( Origin gPackager )
					)
					( objectStatus "U5D1.G36" )
				)
				( pin "vss(1130)"
					( attribute "PN" "G32"
						( Origin gPackager )
					)
					( objectStatus "U5D1.G32" )
				)
				( pin "vss(1131)"
					( attribute "PN" "G30"
						( Origin gPackager )
					)
					( objectStatus "U5D1.G30" )
				)
				( pin "vss(1132)"
					( attribute "PN" "G26"
						( Origin gPackager )
					)
					( objectStatus "U5D1.G26" )
				)
				( pin "vss(1133)"
					( attribute "PN" "G24"
						( Origin gPackager )
					)
					( objectStatus "U5D1.G24" )
				)
				( pin "vss(1134)"
					( attribute "PN" "G22"
						( Origin gPackager )
					)
					( objectStatus "U5D1.G22" )
				)
				( pin "vss(1135)"
					( attribute "PN" "G8"
						( Origin gPackager )
					)
					( objectStatus "U5D1.G8" )
				)
				( pin "vss(1136)"
					( attribute "PN" "G4"
						( Origin gPackager )
					)
					( objectStatus "U5D1.G4" )
				)
				( pin "vss(1137)"
					( attribute "PN" "F69"
						( Origin gPackager )
					)
					( objectStatus "U5D1.F69" )
				)
				( pin "vss(1138)"
					( attribute "PN" "F67"
						( Origin gPackager )
					)
					( objectStatus "U5D1.F67" )
				)
				( pin "vss(1139)"
					( attribute "PN" "F43"
						( Origin gPackager )
					)
					( objectStatus "U5D1.F43" )
				)
				( pin "vss(1140)"
					( attribute "PN" "F37"
						( Origin gPackager )
					)
					( objectStatus "U5D1.F37" )
				)
				( pin "vss(1141)"
					( attribute "PN" "F31"
						( Origin gPackager )
					)
					( objectStatus "U5D1.F31" )
				)
				( pin "vss(1142)"
					( attribute "PN" "F25"
						( Origin gPackager )
					)
					( objectStatus "U5D1.F25" )
				)
				( pin "vss(1143)"
					( attribute "PN" "F19"
						( Origin gPackager )
					)
					( objectStatus "U5D1.F19" )
				)
				( pin "vss(1144)"
					( attribute "PN" "F17"
						( Origin gPackager )
					)
					( objectStatus "U5D1.F17" )
				)
				( pin "vss(1145)"
					( attribute "PN" "F5"
						( Origin gPackager )
					)
					( objectStatus "U5D1.F5" )
				)
				( pin "vss(1146)"
					( attribute "PN" "E76"
						( Origin gPackager )
					)
					( objectStatus "U5D1.E76" )
				)
				( pin "vss(1147)"
					( attribute "PN" "E74"
						( Origin gPackager )
					)
					( objectStatus "U5D1.E74" )
				)
				( pin "vss(1148)"
					( attribute "PN" "E72"
						( Origin gPackager )
					)
					( objectStatus "U5D1.E72" )
				)
				( pin "vss(1149)"
					( attribute "PN" "E22"
						( Origin gPackager )
					)
					( objectStatus "U5D1.E22" )
				)
				( pin "vss(1150)"
					( attribute "PN" "E20"
						( Origin gPackager )
					)
					( objectStatus "U5D1.E20" )
				)
				( pin "vss(1151)"
					( attribute "PN" "E18"
						( Origin gPackager )
					)
					( objectStatus "U5D1.E18" )
				)
				( pin "vss(1152)"
					( attribute "PN" "E16"
						( Origin gPackager )
					)
					( objectStatus "U5D1.E16" )
				)
				( pin "vss(1153)"
					( attribute "PN" "E8"
						( Origin gPackager )
					)
					( objectStatus "U5D1.E8" )
				)
				( pin "vss(1154)"
					( attribute "PN" "E6"
						( Origin gPackager )
					)
					( objectStatus "U5D1.E6" )
				)
				( pin "vss(1155)"
					( attribute "PN" "D77"
						( Origin gPackager )
					)
					( objectStatus "U5D1.D77" )
				)
				( pin "vss(1156)"
					( attribute "PN" "D43"
						( Origin gPackager )
					)
					( objectStatus "U5D1.D43" )
				)
				( pin "vss(1157)"
					( attribute "PN" "D41"
						( Origin gPackager )
					)
					( objectStatus "U5D1.D41" )
				)
				( pin "vss(1158)"
					( attribute "PN" "D39"
						( Origin gPackager )
					)
					( objectStatus "U5D1.D39" )
				)
				( pin "vss(1159)"
					( attribute "PN" "D37"
						( Origin gPackager )
					)
					( objectStatus "U5D1.D37" )
				)
				( pin "vss(1160)"
					( attribute "PN" "D35"
						( Origin gPackager )
					)
					( objectStatus "U5D1.D35" )
				)
				( pin "vss(1161)"
					( attribute "PN" "D33"
						( Origin gPackager )
					)
					( objectStatus "U5D1.D33" )
				)
				( pin "vss(1162)"
					( attribute "PN" "D31"
						( Origin gPackager )
					)
					( objectStatus "U5D1.D31" )
				)
				( pin "vss(1163)"
					( attribute "PN" "D29"
						( Origin gPackager )
					)
					( objectStatus "U5D1.D29" )
				)
				( pin "vss(1164)"
					( attribute "PN" "D27"
						( Origin gPackager )
					)
					( objectStatus "U5D1.D27" )
				)
				( pin "vss(1165)"
					( attribute "PN" "D25"
						( Origin gPackager )
					)
					( objectStatus "U5D1.D25" )
				)
				( pin "vss(1166)"
					( attribute "PN" "D13"
						( Origin gPackager )
					)
					( objectStatus "U5D1.D13" )
				)
				( pin "vss(1167)"
					( attribute "PN" "D11"
						( Origin gPackager )
					)
					( objectStatus "U5D1.D11" )
				)
				( pin "vss(1168)"
					( attribute "PN" "CM27"
						( Origin gPackager )
					)
					( objectStatus "U5D1.CM27" )
				)
				( pin "vss(1169)"
					( attribute "PN" "C78"
						( Origin gPackager )
					)
					( objectStatus "U5D1.C78" )
				)
				( pin "vss(1170)"
					( attribute "PN" "C76"
						( Origin gPackager )
					)
					( objectStatus "U5D1.C76" )
				)
				( pin "vss(1171)"
					( attribute "PN" "C16"
						( Origin gPackager )
					)
					( objectStatus "U5D1.C16" )
				)
				( pin "vss(1172)"
					( attribute "PN" "C14"
						( Origin gPackager )
					)
					( objectStatus "U5D1.C14" )
				)
				( pin "vss(1173)"
					( attribute "PN" "C12"
						( Origin gPackager )
					)
					( objectStatus "U5D1.C12" )
				)
				( pin "vss(1174)"
					( attribute "PN" "C10"
						( Origin gPackager )
					)
					( objectStatus "U5D1.C10" )
				)
				( pin "vss(1175)"
					( attribute "PN" "C8"
						( Origin gPackager )
					)
					( objectStatus "U5D1.C8" )
				)
				( pin "vss(1176)"
					( attribute "PN" "B75"
						( Origin gPackager )
					)
					( objectStatus "U5D1.B75" )
				)
				( pin "vss(1177)"
					( attribute "PN" "B71"
						( Origin gPackager )
					)
					( objectStatus "U5D1.B71" )
				)
				( pin "vss(1178)"
					( attribute "PN" "B37"
						( Origin gPackager )
					)
					( objectStatus "U5D1.B37" )
				)
				( pin "vss(1179)"
					( attribute "PN" "B31"
						( Origin gPackager )
					)
					( objectStatus "U5D1.B31" )
				)
				( pin "vss(1180)"
					( attribute "PN" "B25"
						( Origin gPackager )
					)
					( objectStatus "U5D1.B25" )
				)
				( pin "vss(1181)"
					( attribute "PN" "A38"
						( Origin gPackager )
					)
					( objectStatus "U5D1.A38" )
				)
				( pin "vss(1182)"
					( attribute "PN" "A36"
						( Origin gPackager )
					)
					( objectStatus "U5D1.A36" )
				)
				( pin "vss(1183)"
					( attribute "PN" "A32"
						( Origin gPackager )
					)
					( objectStatus "U5D1.A32" )
				)
				( pin "vss(1184)"
					( attribute "PN" "A30"
						( Origin gPackager )
					)
					( objectStatus "U5D1.A30" )
				)
				( pin "vss(1185)"
					( attribute "PN" "A26"
						( Origin gPackager )
					)
					( objectStatus "U5D1.A26" )
				)
				( pin "vss(1186)"
					( attribute "PN" "AC58"
						( Origin gPackager )
					)
					( objectStatus "U5D1.AC58" )
				)
				( pin "vss(1187)"
					( attribute "PN" "AC60"
						( Origin gPackager )
					)
					( objectStatus "U5D1.AC60" )
				)
				( pin "vss(1188)"
					( attribute "PN" "AC62"
						( Origin gPackager )
					)
					( objectStatus "U5D1.AC62" )
				)
				( pin "vss(1189)"
					( attribute "PN" "AJ4"
						( Origin gPackager )
					)
					( objectStatus "U5D1.AJ4" )
				)
				( pin "vss(1190)"
					( attribute "PN" "AR6"
						( Origin gPackager )
					)
					( objectStatus "U5D1.AR6" )
				)
				( pin "vss(1191)"
					( attribute "PN" "CG6"
						( Origin gPackager )
					)
					( objectStatus "U5D1.CG6" )
				)
				( pin "vss(1192)"
					( attribute "PN" "CW6"
						( Origin gPackager )
					)
					( objectStatus "U5D1.CW6" )
				)
				( pin "vss(1193)"
					( attribute "PN" "DE48"
						( Origin gPackager )
					)
					( objectStatus "U5D1.DE48" )
				)
				( pin "vss(1194)"
					( attribute "PN" "DE50"
						( Origin gPackager )
					)
					( objectStatus "U5D1.DE50" )
				)
				( pin "vss(1195)"
					( attribute "PN" "DE52"
						( Origin gPackager )
					)
					( objectStatus "U5D1.DE52" )
				)
				( pin "vss(1196)"
					( attribute "PN" "DE54"
						( Origin gPackager )
					)
					( objectStatus "U5D1.DE54" )
				)
				( pin "vss(1197)"
					( attribute "PN" "DE56"
						( Origin gPackager )
					)
					( objectStatus "U5D1.DE56" )
				)
				( pin "vss(1198)"
					( attribute "PN" "DE58"
						( Origin gPackager )
					)
					( objectStatus "U5D1.DE58" )
				)
				( pin "vss(1199)"
					( attribute "PN" "DE60"
						( Origin gPackager )
					)
					( objectStatus "U5D1.DE60" )
				)
				( pin "vss(1200)"
					( attribute "PN" "DE62"
						( Origin gPackager )
					)
					( objectStatus "U5D1.DE62" )
				)
				( pin "vss(1201)"
					( attribute "PN" "DL8"
						( Origin gPackager )
					)
					( objectStatus "U5D1.DL8" )
				)
				( pin "vss(1202)"
					( attribute "PN" "DN18"
						( Origin gPackager )
					)
					( objectStatus "U5D1.DN18" )
				)
				( pin "vss(1203)"
					( attribute "PN" "DP45"
						( Origin gPackager )
					)
					( objectStatus "U5D1.DP45" )
				)
				( pin "vss(1204)"
					( attribute "PN" "DP47"
						( Origin gPackager )
					)
					( objectStatus "U5D1.DP47" )
				)
				( pin "vss(1205)"
					( attribute "PN" "DP49"
						( Origin gPackager )
					)
					( objectStatus "U5D1.DP49" )
				)
				( pin "vss(1206)"
					( attribute "PN" "DP51"
						( Origin gPackager )
					)
					( objectStatus "U5D1.DP51" )
				)
				( pin "vss(1207)"
					( attribute "PN" "DP53"
						( Origin gPackager )
					)
					( objectStatus "U5D1.DP53" )
				)
				( pin "vss(1208)"
					( attribute "PN" "DP55"
						( Origin gPackager )
					)
					( objectStatus "U5D1.DP55" )
				)
				( pin "vss(1209)"
					( attribute "PN" "DP57"
						( Origin gPackager )
					)
					( objectStatus "U5D1.DP57" )
				)
				( pin "vss(1210)"
					( attribute "PN" "DP59"
						( Origin gPackager )
					)
					( objectStatus "U5D1.DP59" )
				)
				( pin "vss(1211)"
					( attribute "PN" "DP61"
						( Origin gPackager )
					)
					( objectStatus "U5D1.DP61" )
				)
				( pin "vss(1212)"
					( attribute "PN" "DP63"
						( Origin gPackager )
					)
					( objectStatus "U5D1.DP63" )
				)
				( pin "vss(1213)"
					( attribute "PN" "DP9"
						( Origin gPackager )
					)
					( objectStatus "U5D1.DP9" )
				)
				( pin "vss(1214)"
					( attribute "PN" "DV19"
						( Origin gPackager )
					)
					( objectStatus "U5D1.DV19" )
				)
				( pin "vss(1215)"
					( attribute "PN" "DY45"
						( Origin gPackager )
					)
					( objectStatus "U5D1.DY45" )
				)
				( pin "vss(1216)"
					( attribute "PN" "DY47"
						( Origin gPackager )
					)
					( objectStatus "U5D1.DY47" )
				)
				( pin "vss(1217)"
					( attribute "PN" "DY49"
						( Origin gPackager )
					)
					( objectStatus "U5D1.DY49" )
				)
				( pin "vss(1218)"
					( attribute "PN" "DY51"
						( Origin gPackager )
					)
					( objectStatus "U5D1.DY51" )
				)
				( pin "vss(1219)"
					( attribute "PN" "DY53"
						( Origin gPackager )
					)
					( objectStatus "U5D1.DY53" )
				)
				( pin "vss(1220)"
					( attribute "PN" "DY55"
						( Origin gPackager )
					)
					( objectStatus "U5D1.DY55" )
				)
				( pin "vss(1221)"
					( attribute "PN" "DY57"
						( Origin gPackager )
					)
					( objectStatus "U5D1.DY57" )
				)
				( pin "vss(1222)"
					( attribute "PN" "DY59"
						( Origin gPackager )
					)
					( objectStatus "U5D1.DY59" )
				)
				( pin "vss(1223)"
					( attribute "PN" "DY61"
						( Origin gPackager )
					)
					( objectStatus "U5D1.DY61" )
				)
				( pin "vss(1224)"
					( attribute "PN" "DY63"
						( Origin gPackager )
					)
					( objectStatus "U5D1.DY63" )
				)
				( pin "vss(1225)"
					( attribute "PN" "EA14"
						( Origin gPackager )
					)
					( objectStatus "U5D1.EA14" )
				)
				( pin "vss(1226)"
					( attribute "PN" "L8"
						( Origin gPackager )
					)
					( objectStatus "U5D1.L8" )
				)
				( pin "vss(1227)"
					( attribute "PN" "V11"
						( Origin gPackager )
					)
					( objectStatus "U5D1.V11" )
				)
				( pin "vss(1228)"
					( attribute "PN" "E66"
						( Origin gPackager )
					)
					( objectStatus "U5D1.E66" )
				)
				( pin "vss(1229)"
					( attribute "PN" "ED69"
						( Origin gPackager )
					)
					( objectStatus "U5D1.ED69" )
				)
				( pin "vss(1230)"
					( attribute "PN" "EE80"
						( Origin gPackager )
					)
					( objectStatus "U5D1.EE80" )
				)
				( pin "vss(1231)"
					( attribute "PN" "EE8"
						( Origin gPackager )
					)
					( objectStatus "U5D1.EE8" )
				)
				( pin "vss(1232)"
					( attribute "PN" "EE40"
						( Origin gPackager )
					)
					( objectStatus "U5D1.EE40" )
				)
				( pin "vss(1233)"
					( attribute "PN" "ED81"
						( Origin gPackager )
					)
					( objectStatus "U5D1.ED81" )
				)
				( pin "vss(1234)"
					( attribute "PN" "ED7"
						( Origin gPackager )
					)
					( objectStatus "U5D1.ED7" )
				)
				( pin "vss(1235)"
					( attribute "PN" "ED41"
						( Origin gPackager )
					)
					( objectStatus "U5D1.ED41" )
				)
				( pin "vss(1236)"
					( attribute "PN" "EC82"
						( Origin gPackager )
					)
					( objectStatus "U5D1.EC82" )
				)
				( pin "vss(1237)"
					( attribute "PN" "EC6"
						( Origin gPackager )
					)
					( objectStatus "U5D1.EC6" )
				)
				( pin "vss(1238)"
					( attribute "PN" "EC42"
						( Origin gPackager )
					)
					( objectStatus "U5D1.EC42" )
				)
				( pin "vss(1239)"
					( attribute "PN" "DW2"
						( Origin gPackager )
					)
					( objectStatus "U5D1.DW2" )
				)
				( pin "vss(1240)"
					( attribute "PN" "EB83"
						( Origin gPackager )
					)
					( objectStatus "U5D1.EB83" )
				)
				( pin "vss(1241)"
					( attribute "PN" "EA84"
						( Origin gPackager )
					)
					( objectStatus "U5D1.EA84" )
				)
				( pin "vss(1242)"
					( attribute "PN" "DY85"
						( Origin gPackager )
					)
					( objectStatus "U5D1.DY85" )
				)
				( pin "vss(1243)"
					( attribute "PN" "J86"
						( Origin gPackager )
					)
					( objectStatus "U5D1.J86" )
				)
				( pin "vss(1244)"
					( attribute "PN" "E82"
						( Origin gPackager )
					)
					( objectStatus "U5D1.E82" )
				)
				( pin "vss(1245)"
					( attribute "PN" "D81"
						( Origin gPackager )
					)
					( objectStatus "U5D1.D81" )
				)
				( pin "vss(1246)"
					( attribute "PN" "D3"
						( Origin gPackager )
					)
					( objectStatus "U5D1.D3" )
				)
				( pin "vss(1247)"
					( attribute "PN" "C80"
						( Origin gPackager )
					)
					( objectStatus "U5D1.C80" )
				)
				( pin "vss(1248)"
					( attribute "PN" "C4"
						( Origin gPackager )
					)
					( objectStatus "U5D1.C4" )
				)
				( pin "vss(1249)"
					( attribute "PN" "B79"
						( Origin gPackager )
					)
					( objectStatus "U5D1.B79" )
				)
				( pin "vss(1250)"
					( attribute "PN" "B5"
						( Origin gPackager )
					)
					( objectStatus "U5D1.B5" )
				)
				( pin "vss(1251)"
					( attribute "PN" "B43"
						( Origin gPackager )
					)
					( objectStatus "U5D1.B43" )
				)
				( pin "vss(1252)"
					( attribute "PN" "A42"
						( Origin gPackager )
					)
					( objectStatus "U5D1.A42" )
				)
				( pin "vss(1253)"
					( attribute "PN" "B9"
						( Origin gPackager )
					)
					( objectStatus "U5D1.B9" )
				)
			)
			( gate "@baseboard_fab2_lib.baseboard_fab2(sch_1):page40_i21"
				( attribute "CDS_LIB" "chpset_lib"
					( Origin gPackager )
				)
				( attribute "CDS_LOCATION" "U5D1"
					( Origin gPackager )
				)
				( attribute "CDS_SEC" "24"
					( Origin gPackager )
				)
				( attribute "LOCATION" "U5D1"
					( Origin gFrontEnd )
				)
				( attribute "MATERIAL" "IC"
					( Origin gFrontEnd )
				)
				( attribute "PACK_TYPE" "BGA1"
					( Origin gFrontEnd )
				)
				( attribute "PART_NUMBER" "TBD"
					( Origin gFrontEnd )
				)
				( attribute "PHYS_PAGE" "40"
					( Origin gFrontEnd )
				)
				( attribute "ROOM" "CPU0"
					( Origin gFrontEnd )
				)
				( attribute "ROT" "0"
					( Origin gFrontEnd )
				)
				( attribute "SEC" "24"
					( Origin gFrontEnd )
				)
				( attribute "SEC_TYPE" "BGA1"
					( Origin gFrontEnd )
				)
				( attribute "VER" "24"
					( Origin gFrontEnd )
				)
				( attribute "XY" "(-5225,2575)"
					( Origin gFrontEnd )
				)
				( attribute "CHIPS_PART_NAME" "SKX_EXT_B"
					( Origin gPackager )
				)
				( attribute "CDS_PART_NAME" "SKX_EXT_B_BGA1-IC,TBD"
					( Origin gPackager )
				)
				( objectStatus "U5D1" )
				( pin "vss(934)"
					( attribute "PN" "AA16"
						( Origin gPackager )
					)
					( objectStatus "U5D1.AA16" )
				)
				( pin "vss(935)"
					( attribute "PN" "AA4"
						( Origin gPackager )
					)
					( objectStatus "U5D1.AA4" )
				)
				( pin "vss(936)"
					( attribute "PN" "Y85"
						( Origin gPackager )
					)
					( objectStatus "U5D1.Y85" )
				)
				( pin "vss(937)"
					( attribute "PN" "Y83"
						( Origin gPackager )
					)
					( objectStatus "U5D1.Y83" )
				)
				( pin "vss(938)"
					( attribute "PN" "Y81"
						( Origin gPackager )
					)
					( objectStatus "U5D1.Y81" )
				)
				( pin "vss(939)"
					( attribute "PN" "Y79"
						( Origin gPackager )
					)
					( objectStatus "U5D1.Y79" )
				)
				( pin "vss(940)"
					( attribute "PN" "Y73"
						( Origin gPackager )
					)
					( objectStatus "U5D1.Y73" )
				)
				( pin "vss(941)"
					( attribute "PN" "Y71"
						( Origin gPackager )
					)
					( objectStatus "U5D1.Y71" )
				)
				( pin "vss(942)"
					( attribute "PN" "Y9"
						( Origin gPackager )
					)
					( objectStatus "U5D1.Y9" )
				)
				( pin "vss(943)"
					( attribute "PN" "Y7"
						( Origin gPackager )
					)
					( objectStatus "U5D1.Y7" )
				)
				( pin "vss(944)"
					( attribute "PN" "Y67"
						( Origin gPackager )
					)
					( objectStatus "U5D1.Y67" )
				)
				( pin "vss(945)"
					( attribute "PN" "Y5"
						( Origin gPackager )
					)
					( objectStatus "U5D1.Y5" )
				)
				( pin "vss(946)"
					( attribute "PN" "Y17"
						( Origin gPackager )
					)
					( objectStatus "U5D1.Y17" )
				)
				( pin "vss(947)"
					( attribute "PN" "Y15"
						( Origin gPackager )
					)
					( objectStatus "U5D1.Y15" )
				)
				( pin "vss(948)"
					( attribute "PN" "W82"
						( Origin gPackager )
					)
					( objectStatus "U5D1.W82" )
				)
				( pin "vss(949)"
					( attribute "PN" "W78"
						( Origin gPackager )
					)
					( objectStatus "U5D1.W78" )
				)
				( pin "vss(950)"
					( attribute "PN" "W74"
						( Origin gPackager )
					)
					( objectStatus "U5D1.W74" )
				)
				( pin "vss(951)"
					( attribute "PN" "W68"
						( Origin gPackager )
					)
					( objectStatus "U5D1.W68" )
				)
				( pin "vss(952)"
					( attribute "PN" "W42"
						( Origin gPackager )
					)
					( objectStatus "U5D1.W42" )
				)
				( pin "vss(953)"
					( attribute "PN" "W40"
						( Origin gPackager )
					)
					( objectStatus "U5D1.W40" )
				)
				( pin "vss(954)"
					( attribute "PN" "W38"
						( Origin gPackager )
					)
					( objectStatus "U5D1.W38" )
				)
				( pin "vss(955)"
					( attribute "PN" "W36"
						( Origin gPackager )
					)
					( objectStatus "U5D1.W36" )
				)
				( pin "vss(956)"
					( attribute "PN" "W34"
						( Origin gPackager )
					)
					( objectStatus "U5D1.W34" )
				)
				( pin "vss(957)"
					( attribute "PN" "W32"
						( Origin gPackager )
					)
					( objectStatus "U5D1.W32" )
				)
				( pin "vss(958)"
					( attribute "PN" "W30"
						( Origin gPackager )
					)
					( objectStatus "U5D1.W30" )
				)
				( pin "vss(959)"
					( attribute "PN" "W28"
						( Origin gPackager )
					)
					( objectStatus "U5D1.W28" )
				)
				( pin "vss(960)"
					( attribute "PN" "W26"
						( Origin gPackager )
					)
					( objectStatus "U5D1.W26" )
				)
				( pin "vss(961)"
					( attribute "PN" "W24"
						( Origin gPackager )
					)
					( objectStatus "U5D1.W24" )
				)
				( pin "vss(962)"
					( attribute "PN" "W22"
						( Origin gPackager )
					)
					( objectStatus "U5D1.W22" )
				)
				( pin "vss(963)"
					( attribute "PN" "W12"
						( Origin gPackager )
					)
					( objectStatus "U5D1.W12" )
				)
				( pin "vss(964)"
					( attribute "PN" "AC56"
						( Origin gPackager )
					)
					( objectStatus "U5D1.AC56" )
				)
				( pin "vss(965)"
					( attribute "PN" "W8"
						( Origin gPackager )
					)
					( objectStatus "U5D1.W8" )
				)
				( pin "vss(966)"
					( attribute "PN" "V83"
						( Origin gPackager )
					)
					( objectStatus "U5D1.V83" )
				)
				( pin "vss(967)"
					( attribute "PN" "V77"
						( Origin gPackager )
					)
					( objectStatus "U5D1.V77" )
				)
				( pin "vss(968)"
					( attribute "PN" "V75"
						( Origin gPackager )
					)
					( objectStatus "U5D1.V75" )
				)
				( pin "vss(969)"
					( attribute "PN" "V73"
						( Origin gPackager )
					)
					( objectStatus "U5D1.V73" )
				)
				( pin "vss(970)"
					( attribute "PN" "V43"
						( Origin gPackager )
					)
					( objectStatus "U5D1.V43" )
				)
				( pin "vss(971)"
					( attribute "PN" "V23"
						( Origin gPackager )
					)
					( objectStatus "U5D1.V23" )
				)
				( pin "vss(972)"
					( attribute "PN" "V21"
						( Origin gPackager )
					)
					( objectStatus "U5D1.V21" )
				)
				( pin "vss(973)"
					( attribute "PN" "V15"
						( Origin gPackager )
					)
					( objectStatus "U5D1.V15" )
				)
				( pin "vss(974)"
					( attribute "PN" "V13"
						( Origin gPackager )
					)
					( objectStatus "U5D1.V13" )
				)
				( pin "vss(975)"
					( attribute "PN" "V9"
						( Origin gPackager )
					)
					( objectStatus "U5D1.V9" )
				)
				( pin "vss(976)"
					( attribute "PN" "V5"
						( Origin gPackager )
					)
					( objectStatus "U5D1.V5" )
				)
				( pin "vss(977)"
					( attribute "PN" "V1"
						( Origin gPackager )
					)
					( objectStatus "U5D1.V1" )
				)
				( pin "vss(978)"
					( attribute "PN" "U86"
						( Origin gPackager )
					)
					( objectStatus "U5D1.U86" )
				)
				( pin "vss(979)"
					( attribute "PN" "U80"
						( Origin gPackager )
					)
					( objectStatus "U5D1.U80" )
				)
				( pin "vss(980)"
					( attribute "PN" "U78"
						( Origin gPackager )
					)
					( objectStatus "U5D1.U78" )
				)
				( pin "vss(981)"
					( attribute "PN" "U76"
						( Origin gPackager )
					)
					( objectStatus "U5D1.U76" )
				)
				( pin "vss(982)"
					( attribute "PN" "U74"
						( Origin gPackager )
					)
					( objectStatus "U5D1.U74" )
				)
				( pin "vss(983)"
					( attribute "PN" "U70"
						( Origin gPackager )
					)
					( objectStatus "U5D1.U70" )
				)
				( pin "vss(984)"
					( attribute "PN" "U68"
						( Origin gPackager )
					)
					( objectStatus "U5D1.U68" )
				)
				( pin "vss(985)"
					( attribute "PN" "U42"
						( Origin gPackager )
					)
					( objectStatus "U5D1.U42" )
				)
				( pin "vss(986)"
					( attribute "PN" "U36"
						( Origin gPackager )
					)
					( objectStatus "U5D1.U36" )
				)
				( pin "vss(987)"
					( attribute "PN" "U30"
						( Origin gPackager )
					)
					( objectStatus "U5D1.U30" )
				)
				( pin "vss(988)"
					( attribute "PN" "U24"
						( Origin gPackager )
					)
					( objectStatus "U5D1.U24" )
				)
				( pin "vss(989)"
					( attribute "PN" "U22"
						( Origin gPackager )
					)
					( objectStatus "U5D1.U22" )
				)
				( pin "vss(990)"
					( attribute "PN" "U20"
						( Origin gPackager )
					)
					( objectStatus "U5D1.U20" )
				)
				( pin "vss(991)"
					( attribute "PN" "U6"
						( Origin gPackager )
					)
					( objectStatus "U5D1.U6" )
				)
				( pin "vss(992)"
					( attribute "PN" "U4"
						( Origin gPackager )
					)
					( objectStatus "U5D1.U4" )
				)
				( pin "vss(993)"
					( attribute "PN" "U2"
						( Origin gPackager )
					)
					( objectStatus "U5D1.U2" )
				)
				( pin "vss(994)"
					( attribute "PN" "T85"
						( Origin gPackager )
					)
					( objectStatus "U5D1.T85" )
				)
				( pin "vss(995)"
					( attribute "PN" "T83"
						( Origin gPackager )
					)
					( objectStatus "U5D1.T83" )
				)
				( pin "vss(996)"
					( attribute "PN" "T77"
						( Origin gPackager )
					)
					( objectStatus "U5D1.T77" )
				)
				( pin "vss(997)"
					( attribute "PN" "T73"
						( Origin gPackager )
					)
					( objectStatus "U5D1.T73" )
				)
				( pin "vss(998)"
					( attribute "PN" "T65"
						( Origin gPackager )
					)
					( objectStatus "U5D1.T65" )
				)
				( pin "vss(999)"
					( attribute "PN" "T41"
						( Origin gPackager )
					)
					( objectStatus "U5D1.T41" )
				)
				( pin "vss(1000)"
					( attribute "PN" "T37"
						( Origin gPackager )
					)
					( objectStatus "U5D1.T37" )
				)
				( pin "vss(1001)"
					( attribute "PN" "T35"
						( Origin gPackager )
					)
					( objectStatus "U5D1.T35" )
				)
				( pin "vss(1002)"
					( attribute "PN" "T31"
						( Origin gPackager )
					)
					( objectStatus "U5D1.T31" )
				)
				( pin "vss(1003)"
					( attribute "PN" "T29"
						( Origin gPackager )
					)
					( objectStatus "U5D1.T29" )
				)
				( pin "vss(1004)"
					( attribute "PN" "T25"
						( Origin gPackager )
					)
					( objectStatus "U5D1.T25" )
				)
				( pin "vss(1005)"
					( attribute "PN" "T17"
						( Origin gPackager )
					)
					( objectStatus "U5D1.T17" )
				)
				( pin "vss(1006)"
					( attribute "PN" "T13"
						( Origin gPackager )
					)
					( objectStatus "U5D1.T13" )
				)
				( pin "vss(1007)"
					( attribute "PN" "R86"
						( Origin gPackager )
					)
					( objectStatus "U5D1.R86" )
				)
				( pin "vss(1008)"
					( attribute "PN" "R78"
						( Origin gPackager )
					)
					( objectStatus "U5D1.R78" )
				)
				( pin "vss(1009)"
					( attribute "PN" "R72"
						( Origin gPackager )
					)
					( objectStatus "U5D1.R72" )
				)
				( pin "vss(1010)"
					( attribute "PN" "R68"
						( Origin gPackager )
					)
					( objectStatus "U5D1.R68" )
				)
				( pin "vss(1011)"
					( attribute "PN" "R40"
						( Origin gPackager )
					)
					( objectStatus "U5D1.R40" )
				)
				( pin "vss(1012)"
					( attribute "PN" "R38"
						( Origin gPackager )
					)
					( objectStatus "U5D1.R38" )
				)
				( pin "vss(1013)"
					( attribute "PN" "R34"
						( Origin gPackager )
					)
					( objectStatus "U5D1.R34" )
				)
				( pin "vss(1014)"
					( attribute "PN" "R32"
						( Origin gPackager )
					)
					( objectStatus "U5D1.R32" )
				)
				( pin "vss(1015)"
					( attribute "PN" "R28"
						( Origin gPackager )
					)
					( objectStatus "U5D1.R28" )
				)
				( pin "vss(1016)"
					( attribute "PN" "R26"
						( Origin gPackager )
					)
					( objectStatus "U5D1.R26" )
				)
				( pin "vss(1017)"
					( attribute "PN" "R22"
						( Origin gPackager )
					)
					( objectStatus "U5D1.R22" )
				)
				( pin "vss(1018)"
					( attribute "PN" "R4"
						( Origin gPackager )
					)
					( objectStatus "U5D1.R4" )
				)
				( pin "vss(1019)"
					( attribute "PN" "R2"
						( Origin gPackager )
					)
					( objectStatus "U5D1.R2" )
				)
				( pin "vss(1020)"
					( attribute "PN" "R18"
						( Origin gPackager )
					)
					( objectStatus "U5D1.R18" )
				)
				( pin "vss(1021)"
					( attribute "PN" "R14"
						( Origin gPackager )
					)
					( objectStatus "U5D1.R14" )
				)
				( pin "vss(1022)"
					( attribute "PN" "P83"
						( Origin gPackager )
					)
					( objectStatus "U5D1.P83" )
				)
				( pin "vss(1023)"
					( attribute "PN" "P81"
						( Origin gPackager )
					)
					( objectStatus "U5D1.P81" )
				)
				( pin "vss(1024)"
					( attribute "PN" "P71"
						( Origin gPackager )
					)
					( objectStatus "U5D1.P71" )
				)
				( pin "vss(1025)"
					( attribute "PN" "P69"
						( Origin gPackager )
					)
					( objectStatus "U5D1.P69" )
				)
				( pin "vss(1026)"
					( attribute "PN" "P67"
						( Origin gPackager )
					)
					( objectStatus "U5D1.P67" )
				)
				( pin "vss(1027)"
					( attribute "PN" "P39"
						( Origin gPackager )
					)
					( objectStatus "U5D1.P39" )
				)
				( pin "vss(1028)"
					( attribute "PN" "P33"
						( Origin gPackager )
					)
					( objectStatus "U5D1.P33" )
				)
				( pin "vss(1029)"
					( attribute "PN" "P27"
						( Origin gPackager )
					)
					( objectStatus "U5D1.P27" )
				)
				( pin "vss(1030)"
					( attribute "PN" "P15"
						( Origin gPackager )
					)
					( objectStatus "U5D1.P15" )
				)
				( pin "vss(1031)"
					( attribute "PN" "P11"
						( Origin gPackager )
					)
					( objectStatus "U5D1.P11" )
				)
				( pin "vss(1032)"
					( attribute "PN" "N8"
						( Origin gPackager )
					)
					( objectStatus "U5D1.N8" )
				)
				( pin "vss(1033)"
					( attribute "PN" "N4"
						( Origin gPackager )
					)
					( objectStatus "U5D1.N4" )
				)
				( pin "vss(1034)"
					( attribute "PN" "N78"
						( Origin gPackager )
					)
					( objectStatus "U5D1.N78" )
				)
				( pin "vss(1035)"
					( attribute "PN" "N76"
						( Origin gPackager )
					)
					( objectStatus "U5D1.N76" )
				)
				( pin "vss(1036)"
					( attribute "PN" "N74"
						( Origin gPackager )
					)
					( objectStatus "U5D1.N74" )
				)
				( pin "vss(1037)"
					( attribute "PN" "N72"
						( Origin gPackager )
					)
					( objectStatus "U5D1.N72" )
				)
				( pin "vss(1038)"
					( attribute "PN" "N70"
						( Origin gPackager )
					)
					( objectStatus "U5D1.N70" )
				)
				( pin "vss(1039)"
					( attribute "PN" "N66"
						( Origin gPackager )
					)
					( objectStatus "U5D1.N66" )
				)
				( pin "vss(1040)"
					( attribute "PN" "N6"
						( Origin gPackager )
					)
					( objectStatus "U5D1.N6" )
				)
				( pin "vss(1041)"
					( attribute "PN" "N22"
						( Origin gPackager )
					)
					( objectStatus "U5D1.N22" )
				)
				( pin "vss(1042)"
					( attribute "PN" "N20"
						( Origin gPackager )
					)
					( objectStatus "U5D1.N20" )
				)
				( pin "vss(1043)"
					( attribute "PN" "DM19"
						( Origin gPackager )
					)
					( objectStatus "U5D1.DM19" )
				)
				( pin "vss(1044)"
					( attribute "PN" "M85"
						( Origin gPackager )
					)
					( objectStatus "U5D1.M85" )
				)
				( pin "vss(1045)"
					( attribute "PN" "M83"
						( Origin gPackager )
					)
					( objectStatus "U5D1.M83" )
				)
				( pin "vss(1046)"
					( attribute "PN" "M79"
						( Origin gPackager )
					)
					( objectStatus "U5D1.M79" )
				)
				( pin "vss(1047)"
					( attribute "PN" "M71"
						( Origin gPackager )
					)
					( objectStatus "U5D1.M71" )
				)
				( pin "vss(1048)"
					( attribute "PN" "M65"
						( Origin gPackager )
					)
					( objectStatus "U5D1.M65" )
				)
				( pin "vss(1049)"
					( attribute "PN" "M43"
						( Origin gPackager )
					)
					( objectStatus "U5D1.M43" )
				)
				( pin "vss(1050)"
					( attribute "PN" "M41"
						( Origin gPackager )
					)
					( objectStatus "U5D1.M41" )
				)
				( pin "vss(1051)"
					( attribute "PN" "M39"
						( Origin gPackager )
					)
					( objectStatus "U5D1.M39" )
				)
				( pin "vss(1052)"
					( attribute "PN" "M37"
						( Origin gPackager )
					)
					( objectStatus "U5D1.M37" )
				)
				( pin "vss(1053)"
					( attribute "PN" "M35"
						( Origin gPackager )
					)
					( objectStatus "U5D1.M35" )
				)
				( pin "vss(1054)"
					( attribute "PN" "M33"
						( Origin gPackager )
					)
					( objectStatus "U5D1.M33" )
				)
				( pin "vss(1055)"
					( attribute "PN" "M31"
						( Origin gPackager )
					)
					( objectStatus "U5D1.M31" )
				)
				( pin "vss(1056)"
					( attribute "PN" "M29"
						( Origin gPackager )
					)
					( objectStatus "U5D1.M29" )
				)
				( pin "vss(1057)"
					( attribute "PN" "M27"
						( Origin gPackager )
					)
					( objectStatus "U5D1.M27" )
				)
				( pin "vss(1058)"
					( attribute "PN" "M25"
						( Origin gPackager )
					)
					( objectStatus "U5D1.M25" )
				)
				( pin "vss(1059)"
					( attribute "PN" "M23"
						( Origin gPackager )
					)
					( objectStatus "U5D1.M23" )
				)
				( pin "vss(1060)"
					( attribute "PN" "M19"
						( Origin gPackager )
					)
					( objectStatus "U5D1.M19" )
				)
				( pin "vss(1061)"
					( attribute "PN" "M17"
						( Origin gPackager )
					)
					( objectStatus "U5D1.M17" )
				)
				( pin "vss(1062)"
					( attribute "PN" "M15"
						( Origin gPackager )
					)
					( objectStatus "U5D1.M15" )
				)
				( pin "vss(1063)"
					( attribute "PN" "CT7"
						( Origin gPackager )
					)
					( objectStatus "U5D1.CT7" )
				)
				( pin "vss(1064)"
					( attribute "PN" "BT9"
						( Origin gPackager )
					)
					( objectStatus "U5D1.BT9" )
				)
				( pin "vss(1065)"
					( attribute "PN" "L82"
						( Origin gPackager )
					)
					( objectStatus "U5D1.L82" )
				)
				( pin "vss(1066)"
					( attribute "PN" "L80"
						( Origin gPackager )
					)
					( objectStatus "U5D1.L80" )
				)
				( pin "vss(1067)"
					( attribute "PN" "L78"
						( Origin gPackager )
					)
					( objectStatus "U5D1.L78" )
				)
				( pin "vss(1068)"
					( attribute "PN" "L72"
						( Origin gPackager )
					)
					( objectStatus "U5D1.L72" )
				)
				( pin "vss(1069)"
					( attribute "PN" "L22"
						( Origin gPackager )
					)
					( objectStatus "U5D1.L22" )
				)
				( pin "vss(1070)"
					( attribute "PN" "L20"
						( Origin gPackager )
					)
					( objectStatus "U5D1.L20" )
				)
				( pin "vss(1071)"
					( attribute "PN" "L6"
						( Origin gPackager )
					)
					( objectStatus "U5D1.L6" )
				)
				( pin "vss(1072)"
					( attribute "PN" "L2"
						( Origin gPackager )
					)
					( objectStatus "U5D1.L2" )
				)
				( pin "vss(1073)"
					( attribute "PN" "L10"
						( Origin gPackager )
					)
					( objectStatus "U5D1.L10" )
				)
				( pin "vss(1074)"
					( attribute "PN" "K85"
						( Origin gPackager )
					)
					( objectStatus "U5D1.K85" )
				)
				( pin "vss(1075)"
					( attribute "PN" "K83"
						( Origin gPackager )
					)
					( objectStatus "U5D1.K83" )
				)
				( pin "vss(1076)"
					( attribute "PN" "K81"
						( Origin gPackager )
					)
					( objectStatus "U5D1.K81" )
				)
				( pin "vss(1077)"
					( attribute "PN" "K77"
						( Origin gPackager )
					)
					( objectStatus "U5D1.K77" )
				)
				( pin "vss(1078)"
					( attribute "PN" "K73"
						( Origin gPackager )
					)
					( objectStatus "U5D1.K73" )
				)
				( pin "vss(1079)"
					( attribute "PN" "K71"
						( Origin gPackager )
					)
					( objectStatus "U5D1.K71" )
				)
				( pin "vss(1080)"
					( attribute "PN" "K69"
						( Origin gPackager )
					)
					( objectStatus "U5D1.K69" )
				)
				( pin "vss(1081)"
					( attribute "PN" "K67"
						( Origin gPackager )
					)
					( objectStatus "U5D1.K67" )
				)
				( pin "vss(1082)"
					( attribute "PN" "K65"
						( Origin gPackager )
					)
					( objectStatus "U5D1.K65" )
				)
				( pin "vss(1083)"
					( attribute "PN" "K39"
						( Origin gPackager )
					)
					( objectStatus "U5D1.K39" )
				)
				( pin "vss(1084)"
					( attribute "PN" "K33"
						( Origin gPackager )
					)
					( objectStatus "U5D1.K33" )
				)
				( pin "vss(1085)"
					( attribute "PN" "K27"
						( Origin gPackager )
					)
					( objectStatus "U5D1.K27" )
				)
				( pin "vss(1086)"
					( attribute "PN" "DB7"
						( Origin gPackager )
					)
					( objectStatus "U5D1.DB7" )
				)
				( pin "vss(1087)"
					( attribute "PN" "K17"
						( Origin gPackager )
					)
					( objectStatus "U5D1.K17" )
				)
				( pin "vss(1088)"
					( attribute "PN" "K13"
						( Origin gPackager )
					)
					( objectStatus "U5D1.K13" )
				)
				( pin "vss(1089)"
					( attribute "PN" "K11"
						( Origin gPackager )
					)
					( objectStatus "U5D1.K11" )
				)
				( pin "vss(1090)"
					( attribute "PN" "K1"
						( Origin gPackager )
					)
					( objectStatus "U5D1.K1" )
				)
				( pin "vss(1091)"
					( attribute "PN" "J84"
						( Origin gPackager )
					)
					( objectStatus "U5D1.J84" )
				)
				( pin "vss(1092)"
					( attribute "PN" "J82"
						( Origin gPackager )
					)
					( objectStatus "U5D1.J82" )
				)
				( pin "vss(1093)"
					( attribute "PN" "J76"
						( Origin gPackager )
					)
					( objectStatus "U5D1.J76" )
				)
			)
			( gate "@baseboard_fab2_lib.baseboard_fab2(sch_1):page40_i22"
				( attribute "CDS_LIB" "chpset_lib"
					( Origin gPackager )
				)
				( attribute "CDS_LOCATION" "U5D1"
					( Origin gPackager )
				)
				( attribute "CDS_SEC" "25"
					( Origin gPackager )
				)
				( attribute "LOCATION" "U5D1"
					( Origin gFrontEnd )
				)
				( attribute "MATERIAL" "IC"
					( Origin gFrontEnd )
				)
				( attribute "PACK_TYPE" "BGA1"
					( Origin gFrontEnd )
				)
				( attribute "PART_NUMBER" "TBD"
					( Origin gFrontEnd )
				)
				( attribute "PHYS_PAGE" "40"
					( Origin gFrontEnd )
				)
				( attribute "ROOM" "CPU0"
					( Origin gFrontEnd )
				)
				( attribute "ROT" "0"
					( Origin gFrontEnd )
				)
				( attribute "SEC" "25"
					( Origin gFrontEnd )
				)
				( attribute "SEC_TYPE" "BGA1"
					( Origin gFrontEnd )
				)
				( attribute "VER" "25"
					( Origin gFrontEnd )
				)
				( attribute "XY" "(-3400,2575)"
					( Origin gFrontEnd )
				)
				( attribute "CHIPS_PART_NAME" "SKX_EXT_B"
					( Origin gPackager )
				)
				( attribute "CDS_PART_NAME" "SKX_EXT_B_BGA1-IC,TBD"
					( Origin gPackager )
				)
				( objectStatus "U5D1" )
				( pin "vss(774)"
					( attribute "PN" "AL68"
						( Origin gPackager )
					)
					( objectStatus "U5D1.AL68" )
				)
				( pin "vss(775)"
					( attribute "PN" "AL64"
						( Origin gPackager )
					)
					( objectStatus "U5D1.AL64" )
				)
				( pin "vss(776)"
					( attribute "PN" "AL56"
						( Origin gPackager )
					)
					( objectStatus "U5D1.AL56" )
				)
				( pin "vss(777)"
					( attribute "PN" "AL32"
						( Origin gPackager )
					)
					( objectStatus "U5D1.AL32" )
				)
				( pin "vss(778)"
					( attribute "PN" "AL30"
						( Origin gPackager )
					)
					( objectStatus "U5D1.AL30" )
				)
				( pin "vss(779)"
					( attribute "PN" "AL24"
						( Origin gPackager )
					)
					( objectStatus "U5D1.AL24" )
				)
				( pin "vss(780)"
					( attribute "PN" "AL10"
						( Origin gPackager )
					)
					( objectStatus "U5D1.AL10" )
				)
				( pin "vss(781)"
					( attribute "PN" "AL4"
						( Origin gPackager )
					)
					( objectStatus "U5D1.AL4" )
				)
				( pin "vss(782)"
					( attribute "PN" "AK85"
						( Origin gPackager )
					)
					( objectStatus "U5D1.AK85" )
				)
				( pin "vss(783)"
					( attribute "PN" "AK83"
						( Origin gPackager )
					)
					( objectStatus "U5D1.AK83" )
				)
				( pin "vss(784)"
					( attribute "PN" "AK81"
						( Origin gPackager )
					)
					( objectStatus "U5D1.AK81" )
				)
				( pin "vss(785)"
					( attribute "PN" "AK79"
						( Origin gPackager )
					)
					( objectStatus "U5D1.AK79" )
				)
				( pin "vss(786)"
					( attribute "PN" "AK73"
						( Origin gPackager )
					)
					( objectStatus "U5D1.AK73" )
				)
				( pin "vss(787)"
					( attribute "PN" "AK67"
						( Origin gPackager )
					)
					( objectStatus "U5D1.AK67" )
				)
				( pin "vss(788)"
					( attribute "PN" "AK65"
						( Origin gPackager )
					)
					( objectStatus "U5D1.AK65" )
				)
				( pin "vss(789)"
					( attribute "PN" "AK55"
						( Origin gPackager )
					)
					( objectStatus "U5D1.AK55" )
				)
				( pin "vss(790)"
					( attribute "PN" "AK33"
						( Origin gPackager )
					)
					( objectStatus "U5D1.AK33" )
				)
				( pin "vss(791)"
					( attribute "PN" "AK31"
						( Origin gPackager )
					)
					( objectStatus "U5D1.AK31" )
				)
				( pin "vss(792)"
					( attribute "PN" "AK29"
						( Origin gPackager )
					)
					( objectStatus "U5D1.AK29" )
				)
				( pin "vss(793)"
					( attribute "PN" "AK25"
						( Origin gPackager )
					)
					( objectStatus "U5D1.AK25" )
				)
				( pin "vss(794)"
					( attribute "PN" "AK23"
						( Origin gPackager )
					)
					( objectStatus "U5D1.AK23" )
				)
				( pin "vss(795)"
					( attribute "PN" "AK19"
						( Origin gPackager )
					)
					( objectStatus "U5D1.AK19" )
				)
				( pin "vss(796)"
					( attribute "PN" "AK13"
						( Origin gPackager )
					)
					( objectStatus "U5D1.AK13" )
				)
				( pin "vss(797)"
					( attribute "PN" "AK9"
						( Origin gPackager )
					)
					( objectStatus "U5D1.AK9" )
				)
				( pin "vss(798)"
					( attribute "PN" "AJ86"
						( Origin gPackager )
					)
					( objectStatus "U5D1.AJ86" )
				)
				( pin "vss(799)"
					( attribute "PN" "AJ82"
						( Origin gPackager )
					)
					( objectStatus "U5D1.AJ82" )
				)
				( pin "vss(800)"
					( attribute "PN" "AJ78"
						( Origin gPackager )
					)
					( objectStatus "U5D1.AJ78" )
				)
				( pin "vss(801)"
					( attribute "PN" "AJ74"
						( Origin gPackager )
					)
					( objectStatus "U5D1.AJ74" )
				)
				( pin "vss(802)"
					( attribute "PN" "AJ68"
						( Origin gPackager )
					)
					( objectStatus "U5D1.AJ68" )
				)
				( pin "vss(803)"
					( attribute "PN" "AJ66"
						( Origin gPackager )
					)
					( objectStatus "U5D1.AJ66" )
				)
				( pin "vss(804)"
					( attribute "PN" "AJ54"
						( Origin gPackager )
					)
					( objectStatus "U5D1.AJ54" )
				)
				( pin "vss(805)"
					( attribute "PN" "AJ52"
						( Origin gPackager )
					)
					( objectStatus "U5D1.AJ52" )
				)
				( pin "vss(806)"
					( attribute "PN" "AJ50"
						( Origin gPackager )
					)
					( objectStatus "U5D1.AJ50" )
				)
				( pin "vss(807)"
					( attribute "PN" "AJ48"
						( Origin gPackager )
					)
					( objectStatus "U5D1.AJ48" )
				)
				( pin "vss(808)"
					( attribute "PN" "AJ46"
						( Origin gPackager )
					)
					( objectStatus "U5D1.AJ46" )
				)
				( pin "vss(809)"
					( attribute "PN" "AJ34"
						( Origin gPackager )
					)
					( objectStatus "U5D1.AJ34" )
				)
				( pin "vss(810)"
					( attribute "PN" "AJ32"
						( Origin gPackager )
					)
					( objectStatus "U5D1.AJ32" )
				)
				( pin "vss(811)"
					( attribute "PN" "AJ28"
						( Origin gPackager )
					)
					( objectStatus "U5D1.AJ28" )
				)
				( pin "vss(812)"
					( attribute "PN" "AJ26"
						( Origin gPackager )
					)
					( objectStatus "U5D1.AJ26" )
				)
				( pin "vss(813)"
					( attribute "PN" "AJ22"
						( Origin gPackager )
					)
					( objectStatus "U5D1.AJ22" )
				)
				( pin "vss(814)"
					( attribute "PN" "AJ8"
						( Origin gPackager )
					)
					( objectStatus "U5D1.AJ8" )
				)
				( pin "vss(815)"
					( attribute "PN" "AH83"
						( Origin gPackager )
					)
					( objectStatus "U5D1.AH83" )
				)
				( pin "vss(816)"
					( attribute "PN" "AH77"
						( Origin gPackager )
					)
					( objectStatus "U5D1.AH77" )
				)
				( pin "vss(817)"
					( attribute "PN" "AH75"
						( Origin gPackager )
					)
					( objectStatus "U5D1.AH75" )
				)
				( pin "vss(818)"
					( attribute "PN" "AH69"
						( Origin gPackager )
					)
					( objectStatus "U5D1.AH69" )
				)
				( pin "vss(819)"
					( attribute "PN" "AH65"
						( Origin gPackager )
					)
					( objectStatus "U5D1.AH65" )
				)
				( pin "vss(820)"
					( attribute "PN" "AH61"
						( Origin gPackager )
					)
					( objectStatus "U5D1.AH61" )
				)
				( pin "vss(821)"
					( attribute "PN" "AH59"
						( Origin gPackager )
					)
					( objectStatus "U5D1.AH59" )
				)
				( pin "vss(822)"
					( attribute "PN" "AH53"
						( Origin gPackager )
					)
					( objectStatus "U5D1.AH53" )
				)
				( pin "vss(823)"
					( attribute "PN" "AH51"
						( Origin gPackager )
					)
					( objectStatus "U5D1.AH51" )
				)
				( pin "vss(824)"
					( attribute "PN" "AH49"
						( Origin gPackager )
					)
					( objectStatus "U5D1.AH49" )
				)
				( pin "vss(825)"
					( attribute "PN" "AH47"
						( Origin gPackager )
					)
					( objectStatus "U5D1.AH47" )
				)
				( pin "vss(826)"
					( attribute "PN" "AH45"
						( Origin gPackager )
					)
					( objectStatus "U5D1.AH45" )
				)
				( pin "vss(827)"
					( attribute "PN" "AH35"
						( Origin gPackager )
					)
					( objectStatus "U5D1.AH35" )
				)
				( pin "vss(828)"
					( attribute "PN" "AH33"
						( Origin gPackager )
					)
					( objectStatus "U5D1.AH33" )
				)
				( pin "vss(829)"
					( attribute "PN" "AH27"
						( Origin gPackager )
					)
					( objectStatus "U5D1.AH27" )
				)
				( pin "vss(830)"
					( attribute "PN" "AH21"
						( Origin gPackager )
					)
					( objectStatus "U5D1.AH21" )
				)
				( pin "vss(831)"
					( attribute "PN" "AH5"
						( Origin gPackager )
					)
					( objectStatus "U5D1.AH5" )
				)
				( pin "vss(832)"
					( attribute "PN" "AH1"
						( Origin gPackager )
					)
					( objectStatus "U5D1.AH1" )
				)
				( pin "vss(833)"
					( attribute "PN" "AG80"
						( Origin gPackager )
					)
					( objectStatus "U5D1.AG80" )
				)
				( pin "vss(834)"
					( attribute "PN" "AG78"
						( Origin gPackager )
					)
					( objectStatus "U5D1.AG78" )
				)
				( pin "vss(835)"
					( attribute "PN" "AG76"
						( Origin gPackager )
					)
					( objectStatus "U5D1.AG76" )
				)
				( pin "vss(836)"
					( attribute "PN" "AG74"
						( Origin gPackager )
					)
					( objectStatus "U5D1.AG74" )
				)
				( pin "vss(837)"
					( attribute "PN" "AG70"
						( Origin gPackager )
					)
					( objectStatus "U5D1.AG70" )
				)
				( pin "vss(838)"
					( attribute "PN" "AG64"
						( Origin gPackager )
					)
					( objectStatus "U5D1.AG64" )
				)
				( pin "vss(839)"
					( attribute "PN" "AG36"
						( Origin gPackager )
					)
					( objectStatus "U5D1.AG36" )
				)
				( pin "vss(840)"
					( attribute "PN" "AG18"
						( Origin gPackager )
					)
					( objectStatus "U5D1.AG18" )
				)
				( pin "vss(841)"
					( attribute "PN" "AG14"
						( Origin gPackager )
					)
					( objectStatus "U5D1.AG14" )
				)
				( pin "vss(842)"
					( attribute "PN" "AG12"
						( Origin gPackager )
					)
					( objectStatus "U5D1.AG12" )
				)
				( pin "vss(843)"
					( attribute "PN" "AF85"
						( Origin gPackager )
					)
					( objectStatus "U5D1.AF85" )
				)
				( pin "vss(844)"
					( attribute "PN" "AF83"
						( Origin gPackager )
					)
					( objectStatus "U5D1.AF83" )
				)
				( pin "vss(845)"
					( attribute "PN" "AF77"
						( Origin gPackager )
					)
					( objectStatus "U5D1.AF77" )
				)
				( pin "vss(846)"
					( attribute "PN" "AF73"
						( Origin gPackager )
					)
					( objectStatus "U5D1.AF73" )
				)
				( pin "vss(847)"
					( attribute "PN" "AF41"
						( Origin gPackager )
					)
					( objectStatus "U5D1.AF41" )
				)
				( pin "vss(848)"
					( attribute "PN" "AF39"
						( Origin gPackager )
					)
					( objectStatus "U5D1.AF39" )
				)
				( pin "vss(849)"
					( attribute "PN" "AF37"
						( Origin gPackager )
					)
					( objectStatus "U5D1.AF37" )
				)
				( pin "vss(850)"
					( attribute "PN" "AF33"
						( Origin gPackager )
					)
					( objectStatus "U5D1.AF33" )
				)
				( pin "vss(851)"
					( attribute "PN" "AF31"
						( Origin gPackager )
					)
					( objectStatus "U5D1.AF31" )
				)
				( pin "vss(852)"
					( attribute "PN" "AF29"
						( Origin gPackager )
					)
					( objectStatus "U5D1.AF29" )
				)
				( pin "vss(853)"
					( attribute "PN" "AF27"
						( Origin gPackager )
					)
					( objectStatus "U5D1.AF27" )
				)
				( pin "vss(854)"
					( attribute "PN" "AF25"
						( Origin gPackager )
					)
					( objectStatus "U5D1.AF25" )
				)
				( pin "vss(855)"
					( attribute "PN" "AF23"
						( Origin gPackager )
					)
					( objectStatus "U5D1.AF23" )
				)
				( pin "vss(856)"
					( attribute "PN" "AF21"
						( Origin gPackager )
					)
					( objectStatus "U5D1.AF21" )
				)
				( pin "vss(857)"
					( attribute "PN" "AF9"
						( Origin gPackager )
					)
					( objectStatus "U5D1.AF9" )
				)
				( pin "vss(858)"
					( attribute "PN" "AC52"
						( Origin gPackager )
					)
					( objectStatus "U5D1.AC52" )
				)
				( pin "vss(859)"
					( attribute "PN" "AF1"
						( Origin gPackager )
					)
					( objectStatus "U5D1.AF1" )
				)
				( pin "vss(860)"
					( attribute "PN" "AE78"
						( Origin gPackager )
					)
					( objectStatus "U5D1.AE78" )
				)
				( pin "vss(861)"
					( attribute "PN" "AE70"
						( Origin gPackager )
					)
					( objectStatus "U5D1.AE70" )
				)
				( pin "vss(862)"
					( attribute "PN" "AE68"
						( Origin gPackager )
					)
					( objectStatus "U5D1.AE68" )
				)
				( pin "vss(863)"
					( attribute "PN" "AE66"
						( Origin gPackager )
					)
					( objectStatus "U5D1.AE66" )
				)
				( pin "vss(864)"
					( attribute "PN" "AE64"
						( Origin gPackager )
					)
					( objectStatus "U5D1.AE64" )
				)
				( pin "vss(865)"
					( attribute "PN" "AE42"
						( Origin gPackager )
					)
					( objectStatus "U5D1.AE42" )
				)
				( pin "vss(866)"
					( attribute "PN" "AE40"
						( Origin gPackager )
					)
					( objectStatus "U5D1.AE40" )
				)
				( pin "vss(867)"
					( attribute "PN" "AE38"
						( Origin gPackager )
					)
					( objectStatus "U5D1.AE38" )
				)
				( pin "vss(868)"
					( attribute "PN" "AE16"
						( Origin gPackager )
					)
					( objectStatus "U5D1.AE16" )
				)
				( pin "vss(869)"
					( attribute "PN" "AC54"
						( Origin gPackager )
					)
					( objectStatus "U5D1.AC54" )
				)
				( pin "vss(870)"
					( attribute "PN" "AE8"
						( Origin gPackager )
					)
					( objectStatus "U5D1.AE8" )
				)
				( pin "vss(871)"
					( attribute "PN" "AE4"
						( Origin gPackager )
					)
					( objectStatus "U5D1.AE4" )
				)
				( pin "vss(872)"
					( attribute "PN" "AD85"
						( Origin gPackager )
					)
					( objectStatus "U5D1.AD85" )
				)
				( pin "vss(873)"
					( attribute "PN" "AD83"
						( Origin gPackager )
					)
					( objectStatus "U5D1.AD83" )
				)
				( pin "vss(874)"
					( attribute "PN" "AD81"
						( Origin gPackager )
					)
					( objectStatus "U5D1.AD81" )
				)
				( pin "vss(875)"
					( attribute "PN" "AD75"
						( Origin gPackager )
					)
					( objectStatus "U5D1.AD75" )
				)
				( pin "vss(876)"
					( attribute "PN" "AD73"
						( Origin gPackager )
					)
					( objectStatus "U5D1.AD73" )
				)
				( pin "vss(877)"
					( attribute "PN" "AD71"
						( Origin gPackager )
					)
					( objectStatus "U5D1.AD71" )
				)
				( pin "vss(878)"
					( attribute "PN" "AD43"
						( Origin gPackager )
					)
					( objectStatus "U5D1.AD43" )
				)
				( pin "vss(879)"
					( attribute "PN" "AD39"
						( Origin gPackager )
					)
					( objectStatus "U5D1.AD39" )
				)
				( pin "vss(880)"
					( attribute "PN" "AD33"
						( Origin gPackager )
					)
					( objectStatus "U5D1.AD33" )
				)
				( pin "vss(881)"
					( attribute "PN" "AD27"
						( Origin gPackager )
					)
					( objectStatus "U5D1.AD27" )
				)
				( pin "vss(882)"
					( attribute "PN" "AD21"
						( Origin gPackager )
					)
					( objectStatus "U5D1.AD21" )
				)
				( pin "vss(883)"
					( attribute "PN" "AD19"
						( Origin gPackager )
					)
					( objectStatus "U5D1.AD19" )
				)
				( pin "vss(884)"
					( attribute "PN" "AD15"
						( Origin gPackager )
					)
					( objectStatus "U5D1.AD15" )
				)
				( pin "vss(885)"
					( attribute "PN" "AD13"
						( Origin gPackager )
					)
					( objectStatus "U5D1.AD13" )
				)
				( pin "vss(886)"
					( attribute "PN" "AD11"
						( Origin gPackager )
					)
					( objectStatus "U5D1.AD11" )
				)
				( pin "vss(887)"
					( attribute "PN" "AD9"
						( Origin gPackager )
					)
					( objectStatus "U5D1.AD9" )
				)
				( pin "vss(888)"
					( attribute "PN" "AD7"
						( Origin gPackager )
					)
					( objectStatus "U5D1.AD7" )
				)
				( pin "vss(889)"
					( attribute "PN" "AD3"
						( Origin gPackager )
					)
					( objectStatus "U5D1.AD3" )
				)
				( pin "vss(890)"
					( attribute "PN" "AC86"
						( Origin gPackager )
					)
					( objectStatus "U5D1.AC86" )
				)
				( pin "vss(891)"
					( attribute "PN" "AC84"
						( Origin gPackager )
					)
					( objectStatus "U5D1.AC84" )
				)
				( pin "vss(892)"
					( attribute "PN" "AC78"
						( Origin gPackager )
					)
					( objectStatus "U5D1.AC78" )
				)
				( pin "vss(893)"
					( attribute "PN" "AC72"
						( Origin gPackager )
					)
					( objectStatus "U5D1.AC72" )
				)
				( pin "vss(894)"
					( attribute "PN" "AC70"
						( Origin gPackager )
					)
					( objectStatus "U5D1.AC70" )
				)
				( pin "vss(895)"
					( attribute "PN" "AC64"
						( Origin gPackager )
					)
					( objectStatus "U5D1.AC64" )
				)
				( pin "vss(896)"
					( attribute "PN" "AC40"
						( Origin gPackager )
					)
					( objectStatus "U5D1.AC40" )
				)
				( pin "vss(897)"
					( attribute "PN" "AC38"
						( Origin gPackager )
					)
					( objectStatus "U5D1.AC38" )
				)
				( pin "vss(898)"
					( attribute "PN" "AC34"
						( Origin gPackager )
					)
					( objectStatus "U5D1.AC34" )
				)
				( pin "vss(899)"
					( attribute "PN" "AC32"
						( Origin gPackager )
					)
					( objectStatus "U5D1.AC32" )
				)
				( pin "vss(900)"
					( attribute "PN" "AC28"
						( Origin gPackager )
					)
					( objectStatus "U5D1.AC28" )
				)
				( pin "vss(901)"
					( attribute "PN" "AC26"
						( Origin gPackager )
					)
					( objectStatus "U5D1.AC26" )
				)
				( pin "vss(902)"
					( attribute "PN" "AC22"
						( Origin gPackager )
					)
					( objectStatus "U5D1.AC22" )
				)
				( pin "vss(903)"
					( attribute "PN" "AC18"
						( Origin gPackager )
					)
					( objectStatus "U5D1.AC18" )
				)
				( pin "vss(904)"
					( attribute "PN" "AB85"
						( Origin gPackager )
					)
					( objectStatus "U5D1.AB85" )
				)
				( pin "vss(905)"
					( attribute "PN" "AB83"
						( Origin gPackager )
					)
					( objectStatus "U5D1.AB83" )
				)
				( pin "vss(906)"
					( attribute "PN" "AB79"
						( Origin gPackager )
					)
					( objectStatus "U5D1.AB79" )
				)
				( pin "vss(907)"
					( attribute "PN" "AB73"
						( Origin gPackager )
					)
					( objectStatus "U5D1.AB73" )
				)
				( pin "vss(908)"
					( attribute "PN" "AB69"
						( Origin gPackager )
					)
					( objectStatus "U5D1.AB69" )
				)
				( pin "vss(909)"
					( attribute "PN" "AB65"
						( Origin gPackager )
					)
					( objectStatus "U5D1.AB65" )
				)
				( pin "vss(910)"
					( attribute "PN" "AB41"
						( Origin gPackager )
					)
					( objectStatus "U5D1.AB41" )
				)
				( pin "vss(911)"
					( attribute "PN" "AB37"
						( Origin gPackager )
					)
					( objectStatus "U5D1.AB37" )
				)
				( pin "vss(912)"
					( attribute "PN" "AB35"
						( Origin gPackager )
					)
					( objectStatus "U5D1.AB35" )
				)
				( pin "vss(913)"
					( attribute "PN" "AB31"
						( Origin gPackager )
					)
					( objectStatus "U5D1.AB31" )
				)
				( pin "vss(914)"
					( attribute "PN" "AB29"
						( Origin gPackager )
					)
					( objectStatus "U5D1.AB29" )
				)
				( pin "vss(915)"
					( attribute "PN" "AB25"
						( Origin gPackager )
					)
					( objectStatus "U5D1.AB25" )
				)
				( pin "vss(916)"
					( attribute "PN" "AB23"
						( Origin gPackager )
					)
					( objectStatus "U5D1.AB23" )
				)
				( pin "vss(917)"
					( attribute "PN" "AB21"
						( Origin gPackager )
					)
					( objectStatus "U5D1.AB21" )
				)
				( pin "vss(918)"
					( attribute "PN" "AB11"
						( Origin gPackager )
					)
					( objectStatus "U5D1.AB11" )
				)
				( pin "vss(919)"
					( attribute "PN" "AB5"
						( Origin gPackager )
					)
					( objectStatus "U5D1.AB5" )
				)
				( pin "vss(920)"
					( attribute "PN" "AB1"
						( Origin gPackager )
					)
					( objectStatus "U5D1.AB1" )
				)
				( pin "vss(921)"
					( attribute "PN" "AA82"
						( Origin gPackager )
					)
					( objectStatus "U5D1.AA82" )
				)
				( pin "vss(922)"
					( attribute "PN" "AA80"
						( Origin gPackager )
					)
					( objectStatus "U5D1.AA80" )
				)
				( pin "vss(923)"
					( attribute "PN" "AA78"
						( Origin gPackager )
					)
					( objectStatus "U5D1.AA78" )
				)
				( pin "vss(924)"
					( attribute "PN" "AA76"
						( Origin gPackager )
					)
					( objectStatus "U5D1.AA76" )
				)
				( pin "vss(925)"
					( attribute "PN" "AA68"
						( Origin gPackager )
					)
					( objectStatus "U5D1.AA68" )
				)
				( pin "vss(926)"
					( attribute "PN" "AA66"
						( Origin gPackager )
					)
					( objectStatus "U5D1.AA66" )
				)
				( pin "vss(927)"
					( attribute "PN" "AA64"
						( Origin gPackager )
					)
					( objectStatus "U5D1.AA64" )
				)
				( pin "vss(928)"
					( attribute "PN" "AA42"
						( Origin gPackager )
					)
					( objectStatus "U5D1.AA42" )
				)
				( pin "vss(929)"
					( attribute "PN" "AA36"
						( Origin gPackager )
					)
					( objectStatus "U5D1.AA36" )
				)
				( pin "vss(930)"
					( attribute "PN" "AA30"
						( Origin gPackager )
					)
					( objectStatus "U5D1.AA30" )
				)
				( pin "vss(931)"
					( attribute "PN" "AA24"
						( Origin gPackager )
					)
					( objectStatus "U5D1.AA24" )
				)
				( pin "vss(932)"
					( attribute "PN" "AA22"
						( Origin gPackager )
					)
					( objectStatus "U5D1.AA22" )
				)
				( pin "vss(933)"
					( attribute "PN" "AA18"
						( Origin gPackager )
					)
					( objectStatus "U5D1.AA18" )
				)
			)
			( gate "@baseboard_fab2_lib.baseboard_fab2(sch_1):page40_i23"
				( attribute "CDS_LIB" "chpset_lib"
					( Origin gPackager )
				)
				( attribute "CDS_LOCATION" "U5D1"
					( Origin gPackager )
				)
				( attribute "CDS_SEC" "26"
					( Origin gPackager )
				)
				( attribute "LOCATION" "U5D1"
					( Origin gFrontEnd )
				)
				( attribute "MATERIAL" "IC"
					( Origin gFrontEnd )
				)
				( attribute "PACK_TYPE" "BGA1"
					( Origin gFrontEnd )
				)
				( attribute "PART_NUMBER" "TBD"
					( Origin gFrontEnd )
				)
				( attribute "PHYS_PAGE" "40"
					( Origin gFrontEnd )
				)
				( attribute "ROOM" "CPU0"
					( Origin gFrontEnd )
				)
				( attribute "ROT" "0"
					( Origin gFrontEnd )
				)
				( attribute "SEC" "26"
					( Origin gFrontEnd )
				)
				( attribute "SEC_TYPE" "BGA1"
					( Origin gFrontEnd )
				)
				( attribute "VER" "26"
					( Origin gFrontEnd )
				)
				( attribute "XY" "(-1550,2575)"
					( Origin gFrontEnd )
				)
				( attribute "CHIPS_PART_NAME" "SKX_EXT_B"
					( Origin gPackager )
				)
				( attribute "CDS_PART_NAME" "SKX_EXT_B_BGA1-IC,TBD"
					( Origin gPackager )
				)
				( objectStatus "U5D1" )
				( pin "vss(614)"
					( attribute "PN" "BG72"
						( Origin gPackager )
					)
					( objectStatus "U5D1.BG72" )
				)
				( pin "vss(615)"
					( attribute "PN" "BG24"
						( Origin gPackager )
					)
					( objectStatus "U5D1.BG24" )
				)
				( pin "vss(616)"
					( attribute "PN" "BG22"
						( Origin gPackager )
					)
					( objectStatus "U5D1.BG22" )
				)
				( pin "vss(617)"
					( attribute "PN" "BG10"
						( Origin gPackager )
					)
					( objectStatus "U5D1.BG10" )
				)
				( pin "vss(618)"
					( attribute "PN" "BG8"
						( Origin gPackager )
					)
					( objectStatus "U5D1.BG8" )
				)
				( pin "vss(619)"
					( attribute "PN" "BG6"
						( Origin gPackager )
					)
					( objectStatus "U5D1.BG6" )
				)
				( pin "vss(620)"
					( attribute "PN" "BF71"
						( Origin gPackager )
					)
					( objectStatus "U5D1.BF71" )
				)
				( pin "vss(621)"
					( attribute "PN" "BF69"
						( Origin gPackager )
					)
					( objectStatus "U5D1.BF69" )
				)
				( pin "vss(622)"
					( attribute "PN" "BF67"
						( Origin gPackager )
					)
					( objectStatus "U5D1.BF67" )
				)
				( pin "vss(623)"
					( attribute "PN" "BF65"
						( Origin gPackager )
					)
					( objectStatus "U5D1.BF65" )
				)
				( pin "vss(624)"
					( attribute "PN" "BF63"
						( Origin gPackager )
					)
					( objectStatus "U5D1.BF63" )
				)
				( pin "vss(625)"
					( attribute "PN" "BF25"
						( Origin gPackager )
					)
					( objectStatus "U5D1.BF25" )
				)
				( pin "vss(626)"
					( attribute "PN" "BF19"
						( Origin gPackager )
					)
					( objectStatus "U5D1.BF19" )
				)
				( pin "vss(627)"
					( attribute "PN" "BF17"
						( Origin gPackager )
					)
					( objectStatus "U5D1.BF17" )
				)
				( pin "vss(628)"
					( attribute "PN" "BF15"
						( Origin gPackager )
					)
					( objectStatus "U5D1.BF15" )
				)
				( pin "vss(629)"
					( attribute "PN" "BF9"
						( Origin gPackager )
					)
					( objectStatus "U5D1.BF9" )
				)
				( pin "vss(630)"
					( attribute "PN" "BE70"
						( Origin gPackager )
					)
					( objectStatus "U5D1.BE70" )
				)
				( pin "vss(631)"
					( attribute "PN" "BE68"
						( Origin gPackager )
					)
					( objectStatus "U5D1.BE68" )
				)
				( pin "vss(632)"
					( attribute "PN" "BE66"
						( Origin gPackager )
					)
					( objectStatus "U5D1.BE66" )
				)
				( pin "vss(633)"
					( attribute "PN" "BE64"
						( Origin gPackager )
					)
					( objectStatus "U5D1.BE64" )
				)
				( pin "vss(634)"
					( attribute "PN" "BE26"
						( Origin gPackager )
					)
					( objectStatus "U5D1.BE26" )
				)
				( pin "vss(635)"
					( attribute "PN" "BE10"
						( Origin gPackager )
					)
					( objectStatus "U5D1.BE10" )
				)
				( pin "vss(636)"
					( attribute "PN" "BE8"
						( Origin gPackager )
					)
					( objectStatus "U5D1.BE8" )
				)
				( pin "vss(637)"
					( attribute "PN" "BE6"
						( Origin gPackager )
					)
					( objectStatus "U5D1.BE6" )
				)
				( pin "vss(638)"
					( attribute "PN" "BE4"
						( Origin gPackager )
					)
					( objectStatus "U5D1.BE4" )
				)
				( pin "vss(639)"
					( attribute "PN" "BD71"
						( Origin gPackager )
					)
					( objectStatus "U5D1.BD71" )
				)
				( pin "vss(640)"
					( attribute "PN" "BD63"
						( Origin gPackager )
					)
					( objectStatus "U5D1.BD63" )
				)
				( pin "vss(641)"
					( attribute "PN" "BD27"
						( Origin gPackager )
					)
					( objectStatus "U5D1.BD27" )
				)
				( pin "vss(642)"
					( attribute "PN" "BD21"
						( Origin gPackager )
					)
					( objectStatus "U5D1.BD21" )
				)
				( pin "vss(643)"
					( attribute "PN" "BD15"
						( Origin gPackager )
					)
					( objectStatus "U5D1.BD15" )
				)
				( pin "vss(644)"
					( attribute "PN" "BD11"
						( Origin gPackager )
					)
					( objectStatus "U5D1.BD11" )
				)
				( pin "vss(645)"
					( attribute "PN" "BD5"
						( Origin gPackager )
					)
					( objectStatus "U5D1.BD5" )
				)
				( pin "vss(646)"
					( attribute "PN" "BC82"
						( Origin gPackager )
					)
					( objectStatus "U5D1.BC82" )
				)
				( pin "vss(647)"
					( attribute "PN" "BC80"
						( Origin gPackager )
					)
					( objectStatus "U5D1.BC80" )
				)
				( pin "vss(648)"
					( attribute "PN" "BC78"
						( Origin gPackager )
					)
					( objectStatus "U5D1.BC78" )
				)
				( pin "vss(649)"
					( attribute "PN" "BC76"
						( Origin gPackager )
					)
					( objectStatus "U5D1.BC76" )
				)
				( pin "vss(650)"
					( attribute "PN" "BC74"
						( Origin gPackager )
					)
					( objectStatus "U5D1.BC74" )
				)
				( pin "vss(651)"
					( attribute "PN" "BC72"
						( Origin gPackager )
					)
					( objectStatus "U5D1.BC72" )
				)
				( pin "vss(652)"
					( attribute "PN" "BC70"
						( Origin gPackager )
					)
					( objectStatus "U5D1.BC70" )
				)
				( pin "vss(653)"
					( attribute "PN" "BC16"
						( Origin gPackager )
					)
					( objectStatus "U5D1.BC16" )
				)
				( pin "vss(654)"
					( attribute "PN" "BC12"
						( Origin gPackager )
					)
					( objectStatus "U5D1.BC12" )
				)
				( pin "vss(655)"
					( attribute "PN" "BC8"
						( Origin gPackager )
					)
					( objectStatus "U5D1.BC8" )
				)
				( pin "vss(656)"
					( attribute "PN" "BC4"
						( Origin gPackager )
					)
					( objectStatus "U5D1.BC4" )
				)
				( pin "vss(657)"
					( attribute "PN" "BB83"
						( Origin gPackager )
					)
					( objectStatus "U5D1.BB83" )
				)
				( pin "vss(658)"
					( attribute "PN" "BB81"
						( Origin gPackager )
					)
					( objectStatus "U5D1.BB81" )
				)
				( pin "vss(659)"
					( attribute "PN" "BB79"
						( Origin gPackager )
					)
					( objectStatus "U5D1.BB79" )
				)
				( pin "vss(660)"
					( attribute "PN" "BB77"
						( Origin gPackager )
					)
					( objectStatus "U5D1.BB77" )
				)
				( pin "vss(661)"
					( attribute "PN" "BB75"
						( Origin gPackager )
					)
					( objectStatus "U5D1.BB75" )
				)
				( pin "vss(662)"
					( attribute "PN" "BB73"
						( Origin gPackager )
					)
					( objectStatus "U5D1.BB73" )
				)
				( pin "vss(663)"
					( attribute "PN" "BB69"
						( Origin gPackager )
					)
					( objectStatus "U5D1.BB69" )
				)
				( pin "vss(664)"
					( attribute "PN" "BB63"
						( Origin gPackager )
					)
					( objectStatus "U5D1.BB63" )
				)
				( pin "vss(665)"
					( attribute "PN" "BB23"
						( Origin gPackager )
					)
					( objectStatus "U5D1.BB23" )
				)
				( pin "vss(666)"
					( attribute "PN" "BB19"
						( Origin gPackager )
					)
					( objectStatus "U5D1.BB19" )
				)
				( pin "vss(667)"
					( attribute "PN" "BA84"
						( Origin gPackager )
					)
					( objectStatus "U5D1.BA84" )
				)
				( pin "vss(668)"
					( attribute "PN" "BA80"
						( Origin gPackager )
					)
					( objectStatus "U5D1.BA80" )
				)
				( pin "vss(669)"
					( attribute "PN" "BA74"
						( Origin gPackager )
					)
					( objectStatus "U5D1.BA74" )
				)
				( pin "vss(670)"
					( attribute "PN" "BA68"
						( Origin gPackager )
					)
					( objectStatus "U5D1.BA68" )
				)
				( pin "vss(671)"
					( attribute "PN" "BA62"
						( Origin gPackager )
					)
					( objectStatus "U5D1.BA62" )
				)
				( pin "vss(672)"
					( attribute "PN" "BA12"
						( Origin gPackager )
					)
					( objectStatus "U5D1.BA12" )
				)
				( pin "vss(673)"
					( attribute "PN" "BA6"
						( Origin gPackager )
					)
					( objectStatus "U5D1.BA6" )
				)
				( pin "vss(674)"
					( attribute "PN" "BA2"
						( Origin gPackager )
					)
					( objectStatus "U5D1.BA2" )
				)
				( pin "vss(675)"
					( attribute "PN" "AY81"
						( Origin gPackager )
					)
					( objectStatus "U5D1.AY81" )
				)
				( pin "vss(676)"
					( attribute "PN" "AY79"
						( Origin gPackager )
					)
					( objectStatus "U5D1.AY79" )
				)
				( pin "vss(677)"
					( attribute "PN" "AY63"
						( Origin gPackager )
					)
					( objectStatus "U5D1.AY63" )
				)
				( pin "vss(678)"
					( attribute "PN" "AY25"
						( Origin gPackager )
					)
					( objectStatus "U5D1.AY25" )
				)
				( pin "vss(679)"
					( attribute "PN" "AY23"
						( Origin gPackager )
					)
					( objectStatus "U5D1.AY23" )
				)
				( pin "vss(680)"
					( attribute "PN" "AY21"
						( Origin gPackager )
					)
					( objectStatus "U5D1.AY21" )
				)
				( pin "vss(681)"
					( attribute "PN" "AY17"
						( Origin gPackager )
					)
					( objectStatus "U5D1.AY17" )
				)
				( pin "vss(682)"
					( attribute "PN" "AY15"
						( Origin gPackager )
					)
					( objectStatus "U5D1.AY15" )
				)
				( pin "vss(683)"
					( attribute "PN" "AY5"
						( Origin gPackager )
					)
					( objectStatus "U5D1.AY5" )
				)
				( pin "vss(684)"
					( attribute "PN" "AW84"
						( Origin gPackager )
					)
					( objectStatus "U5D1.AW84" )
				)
				( pin "vss(685)"
					( attribute "PN" "AW82"
						( Origin gPackager )
					)
					( objectStatus "U5D1.AW82" )
				)
				( pin "vss(686)"
					( attribute "PN" "AW78"
						( Origin gPackager )
					)
					( objectStatus "U5D1.AW78" )
				)
				( pin "vss(687)"
					( attribute "PN" "AW74"
						( Origin gPackager )
					)
					( objectStatus "U5D1.AW74" )
				)
				( pin "vss(688)"
					( attribute "PN" "AW72"
						( Origin gPackager )
					)
					( objectStatus "U5D1.AW72" )
				)
				( pin "vss(689)"
					( attribute "PN" "AW70"
						( Origin gPackager )
					)
					( objectStatus "U5D1.AW70" )
				)
				( pin "vss(690)"
					( attribute "PN" "AW68"
						( Origin gPackager )
					)
					( objectStatus "U5D1.AW68" )
				)
				( pin "vss(691)"
					( attribute "PN" "AW66"
						( Origin gPackager )
					)
					( objectStatus "U5D1.AW66" )
				)
				( pin "vss(692)"
					( attribute "PN" "AW62"
						( Origin gPackager )
					)
					( objectStatus "U5D1.AW62" )
				)
				( pin "vss(693)"
					( attribute "PN" "AW10"
						( Origin gPackager )
					)
					( objectStatus "U5D1.AW10" )
				)
				( pin "vss(694)"
					( attribute "PN" "AW2"
						( Origin gPackager )
					)
					( objectStatus "U5D1.AW2" )
				)
				( pin "vss(695)"
					( attribute "PN" "AV83"
						( Origin gPackager )
					)
					( objectStatus "U5D1.AV83" )
				)
				( pin "vss(696)"
					( attribute "PN" "AV75"
						( Origin gPackager )
					)
					( objectStatus "U5D1.AV75" )
				)
				( pin "vss(697)"
					( attribute "PN" "AV67"
						( Origin gPackager )
					)
					( objectStatus "U5D1.AV67" )
				)
				( pin "vss(698)"
					( attribute "PN" "AV65"
						( Origin gPackager )
					)
					( objectStatus "U5D1.AV65" )
				)
				( pin "vss(699)"
					( attribute "PN" "AV63"
						( Origin gPackager )
					)
					( objectStatus "U5D1.AV63" )
				)
				( pin "vss(700)"
					( attribute "PN" "AV25"
						( Origin gPackager )
					)
					( objectStatus "U5D1.AV25" )
				)
				( pin "vss(701)"
					( attribute "PN" "AV23"
						( Origin gPackager )
					)
					( objectStatus "U5D1.AV23" )
				)
				( pin "vss(702)"
					( attribute "PN" "AV19"
						( Origin gPackager )
					)
					( objectStatus "U5D1.AV19" )
				)
				( pin "vss(703)"
					( attribute "PN" "AV13"
						( Origin gPackager )
					)
					( objectStatus "U5D1.AV13" )
				)
				( pin "vss(704)"
					( attribute "PN" "AV11"
						( Origin gPackager )
					)
					( objectStatus "U5D1.AV11" )
				)
				( pin "vss(705)"
					( attribute "PN" "AV7"
						( Origin gPackager )
					)
					( objectStatus "U5D1.AV7" )
				)
				( pin "vss(706)"
					( attribute "PN" "AV3"
						( Origin gPackager )
					)
					( objectStatus "U5D1.AV3" )
				)
				( pin "vss(707)"
					( attribute "PN" "AV1"
						( Origin gPackager )
					)
					( objectStatus "U5D1.AV1" )
				)
				( pin "vss(708)"
					( attribute "PN" "AU86"
						( Origin gPackager )
					)
					( objectStatus "U5D1.AU86" )
				)
				( pin "vss(709)"
					( attribute "PN" "AU84"
						( Origin gPackager )
					)
					( objectStatus "U5D1.AU84" )
				)
				( pin "vss(710)"
					( attribute "PN" "AU80"
						( Origin gPackager )
					)
					( objectStatus "U5D1.AU80" )
				)
				( pin "vss(711)"
					( attribute "PN" "AU78"
						( Origin gPackager )
					)
					( objectStatus "U5D1.AU78" )
				)
				( pin "vss(712)"
					( attribute "PN" "AU76"
						( Origin gPackager )
					)
					( objectStatus "U5D1.AU76" )
				)
				( pin "vss(713)"
					( attribute "PN" "AU74"
						( Origin gPackager )
					)
					( objectStatus "U5D1.AU74" )
				)
				( pin "vss(714)"
					( attribute "PN" "AU68"
						( Origin gPackager )
					)
					( objectStatus "U5D1.AU68" )
				)
				( pin "vss(715)"
					( attribute "PN" "AU64"
						( Origin gPackager )
					)
					( objectStatus "U5D1.AU64" )
				)
				( pin "vss(716)"
					( attribute "PN" "AU62"
						( Origin gPackager )
					)
					( objectStatus "U5D1.AU62" )
				)
				( pin "vss(717)"
					( attribute "PN" "AU28"
						( Origin gPackager )
					)
					( objectStatus "U5D1.AU28" )
				)
				( pin "vss(718)"
					( attribute "PN" "AU26"
						( Origin gPackager )
					)
					( objectStatus "U5D1.AU26" )
				)
				( pin "vss(719)"
					( attribute "PN" "AU6"
						( Origin gPackager )
					)
					( objectStatus "U5D1.AU6" )
				)
				( pin "vss(720)"
					( attribute "PN" "AU2"
						( Origin gPackager )
					)
					( objectStatus "U5D1.AU2" )
				)
				( pin "vss(721)"
					( attribute "PN" "AT85"
						( Origin gPackager )
					)
					( objectStatus "U5D1.AT85" )
				)
				( pin "vss(722)"
					( attribute "PN" "AT83"
						( Origin gPackager )
					)
					( objectStatus "U5D1.AT83" )
				)
				( pin "vss(723)"
					( attribute "PN" "AT77"
						( Origin gPackager )
					)
					( objectStatus "U5D1.AT77" )
				)
				( pin "vss(724)"
					( attribute "PN" "AT73"
						( Origin gPackager )
					)
					( objectStatus "U5D1.AT73" )
				)
				( pin "vss(725)"
					( attribute "PN" "AT69"
						( Origin gPackager )
					)
					( objectStatus "U5D1.AT69" )
				)
				( pin "vss(726)"
					( attribute "PN" "AT63"
						( Origin gPackager )
					)
					( objectStatus "U5D1.AT63" )
				)
				( pin "vss(727)"
					( attribute "PN" "AT61"
						( Origin gPackager )
					)
					( objectStatus "U5D1.AT61" )
				)
				( pin "vss(728)"
					( attribute "PN" "AT27"
						( Origin gPackager )
					)
					( objectStatus "U5D1.AT27" )
				)
				( pin "vss(729)"
					( attribute "PN" "AT21"
						( Origin gPackager )
					)
					( objectStatus "U5D1.AT21" )
				)
				( pin "vss(730)"
					( attribute "PN" "AT17"
						( Origin gPackager )
					)
					( objectStatus "U5D1.AT17" )
				)
				( pin "vss(731)"
					( attribute "PN" "AT15"
						( Origin gPackager )
					)
					( objectStatus "U5D1.AT15" )
				)
				( pin "vss(732)"
					( attribute "PN" "P63"
						( Origin gPackager )
					)
					( objectStatus "U5D1.P63" )
				)
				( pin "vss(733)"
					( attribute "PN" "AC48"
						( Origin gPackager )
					)
					( objectStatus "U5D1.AC48" )
				)
				( pin "vss(734)"
					( attribute "PN" "AR78"
						( Origin gPackager )
					)
					( objectStatus "U5D1.AR78" )
				)
				( pin "vss(735)"
					( attribute "PN" "AR72"
						( Origin gPackager )
					)
					( objectStatus "U5D1.AR72" )
				)
				( pin "vss(736)"
					( attribute "PN" "AR60"
						( Origin gPackager )
					)
					( objectStatus "U5D1.AR60" )
				)
				( pin "vss(737)"
					( attribute "PN" "AR30"
						( Origin gPackager )
					)
					( objectStatus "U5D1.AR30" )
				)
				( pin "vss(738)"
					( attribute "PN" "AR24"
						( Origin gPackager )
					)
					( objectStatus "U5D1.AR24" )
				)
				( pin "vss(739)"
					( attribute "PN" "AR10"
						( Origin gPackager )
					)
					( objectStatus "U5D1.AR10" )
				)
				( pin "vss(740)"
					( attribute "PN" "AP85"
						( Origin gPackager )
					)
					( objectStatus "U5D1.AP85" )
				)
				( pin "vss(741)"
					( attribute "PN" "AP83"
						( Origin gPackager )
					)
					( objectStatus "U5D1.AP83" )
				)
				( pin "vss(742)"
					( attribute "PN" "AP81"
						( Origin gPackager )
					)
					( objectStatus "U5D1.AP81" )
				)
				( pin "vss(743)"
					( attribute "PN" "AP75"
						( Origin gPackager )
					)
					( objectStatus "U5D1.AP75" )
				)
				( pin "vss(744)"
					( attribute "PN" "AP73"
						( Origin gPackager )
					)
					( objectStatus "U5D1.AP73" )
				)
				( pin "vss(745)"
					( attribute "PN" "AP69"
						( Origin gPackager )
					)
					( objectStatus "U5D1.AP69" )
				)
				( pin "vss(746)"
					( attribute "PN" "AP67"
						( Origin gPackager )
					)
					( objectStatus "U5D1.AP67" )
				)
				( pin "vss(747)"
					( attribute "PN" "AP65"
						( Origin gPackager )
					)
					( objectStatus "U5D1.AP65" )
				)
				( pin "vss(748)"
					( attribute "PN" "AP63"
						( Origin gPackager )
					)
					( objectStatus "U5D1.AP63" )
				)
				( pin "vss(749)"
					( attribute "PN" "AP59"
						( Origin gPackager )
					)
					( objectStatus "U5D1.AP59" )
				)
				( pin "vss(750)"
					( attribute "PN" "AP31"
						( Origin gPackager )
					)
					( objectStatus "U5D1.AP31" )
				)
				( pin "vss(751)"
					( attribute "PN" "AP19"
						( Origin gPackager )
					)
					( objectStatus "U5D1.AP19" )
				)
				( pin "vss(752)"
					( attribute "PN" "AP13"
						( Origin gPackager )
					)
					( objectStatus "U5D1.AP13" )
				)
				( pin "vss(753)"
					( attribute "PN" "AP9"
						( Origin gPackager )
					)
					( objectStatus "U5D1.AP9" )
				)
				( pin "vss(754)"
					( attribute "PN" "AP5"
						( Origin gPackager )
					)
					( objectStatus "U5D1.AP5" )
				)
				( pin "vss(755)"
					( attribute "PN" "AN78"
						( Origin gPackager )
					)
					( objectStatus "U5D1.AN78" )
				)
				( pin "vss(756)"
					( attribute "PN" "AN58"
						( Origin gPackager )
					)
					( objectStatus "U5D1.AN58" )
				)
				( pin "vss(757)"
					( attribute "PN" "AN28"
						( Origin gPackager )
					)
					( objectStatus "U5D1.AN28" )
				)
				( pin "vss(758)"
					( attribute "PN" "AN6"
						( Origin gPackager )
					)
					( objectStatus "U5D1.AN6" )
				)
				( pin "vss(759)"
					( attribute "PN" "AN2"
						( Origin gPackager )
					)
					( objectStatus "U5D1.AN2" )
				)
				( pin "vss(760)"
					( attribute "PN" "AM83"
						( Origin gPackager )
					)
					( objectStatus "U5D1.AM83" )
				)
				( pin "vss(761)"
					( attribute "PN" "AM79"
						( Origin gPackager )
					)
					( objectStatus "U5D1.AM79" )
				)
				( pin "vss(762)"
					( attribute "PN" "AM73"
						( Origin gPackager )
					)
					( objectStatus "U5D1.AM73" )
				)
				( pin "vss(763)"
					( attribute "PN" "AM69"
						( Origin gPackager )
					)
					( objectStatus "U5D1.AM69" )
				)
				( pin "vss(764)"
					( attribute "PN" "AM63"
						( Origin gPackager )
					)
					( objectStatus "U5D1.AM63" )
				)
				( pin "vss(765)"
					( attribute "PN" "AM57"
						( Origin gPackager )
					)
					( objectStatus "U5D1.AM57" )
				)
				( pin "vss(766)"
					( attribute "PN" "AM31"
						( Origin gPackager )
					)
					( objectStatus "U5D1.AM31" )
				)
				( pin "vss(767)"
					( attribute "PN" "AC50"
						( Origin gPackager )
					)
					( objectStatus "U5D1.AC50" )
				)
				( pin "vss(768)"
					( attribute "PN" "AM1"
						( Origin gPackager )
					)
					( objectStatus "U5D1.AM1" )
				)
				( pin "vss(769)"
					( attribute "PN" "AL86"
						( Origin gPackager )
					)
					( objectStatus "U5D1.AL86" )
				)
				( pin "vss(770)"
					( attribute "PN" "AL82"
						( Origin gPackager )
					)
					( objectStatus "U5D1.AL82" )
				)
				( pin "vss(771)"
					( attribute "PN" "AL80"
						( Origin gPackager )
					)
					( objectStatus "U5D1.AL80" )
				)
				( pin "vss(772)"
					( attribute "PN" "AL78"
						( Origin gPackager )
					)
					( objectStatus "U5D1.AL78" )
				)
				( pin "vss(773)"
					( attribute "PN" "AL76"
						( Origin gPackager )
					)
					( objectStatus "U5D1.AL76" )
				)
			)
			( gate "@baseboard_fab2_lib.baseboard_fab2(sch_1):page41_i283"
				( attribute "CDS_LIB" "chpset_lib"
					( Origin gPackager )
				)
				( attribute "CDS_LOCATION" "U5D1"
					( Origin gPackager )
				)
				( attribute "CDS_SEC" "27"
					( Origin gPackager )
				)
				( attribute "LOCATION" "U5D1"
					( Origin gFrontEnd )
				)
				( attribute "MATERIAL" "IC"
					( Origin gFrontEnd )
				)
				( attribute "PACK_TYPE" "BGA1"
					( Origin gFrontEnd )
				)
				( attribute "PART_NUMBER" "TBD"
					( Origin gFrontEnd )
				)
				( attribute "PHYS_PAGE" "41"
					( Origin gFrontEnd )
				)
				( attribute "ROOM" "CPU0"
					( Origin gFrontEnd )
				)
				( attribute "ROT" "0"
					( Origin gFrontEnd )
				)
				( attribute "SEC" "27"
					( Origin gFrontEnd )
				)
				( attribute "SEC_TYPE" "BGA1"
					( Origin gFrontEnd )
				)
				( attribute "VER" "27"
					( Origin gFrontEnd )
				)
				( attribute "XY" "(-5275,2650)"
					( Origin gFrontEnd )
				)
				( attribute "CHIPS_PART_NAME" "SKX_EXT_B"
					( Origin gPackager )
				)
				( attribute "CDS_PART_NAME" "SKX_EXT_B_BGA1-IC,TBD"
					( Origin gPackager )
				)
				( objectStatus "U5D1" )
				( pin "vss(454)"
					( attribute "PN" "P49"
						( Origin gPackager )
					)
					( objectStatus "U5D1.P49" )
				)
				( pin "vss(455)"
					( attribute "PN" "CJ12"
						( Origin gPackager )
					)
					( objectStatus "U5D1.CJ12" )
				)
				( pin "vss(456)"
					( attribute "PN" "CJ10"
						( Origin gPackager )
					)
					( objectStatus "U5D1.CJ10" )
				)
				( pin "vss(457)"
					( attribute "PN" "CJ8"
						( Origin gPackager )
					)
					( objectStatus "U5D1.CJ8" )
				)
				( pin "vss(458)"
					( attribute "PN" "CJ6"
						( Origin gPackager )
					)
					( objectStatus "U5D1.CJ6" )
				)
				( pin "vss(459)"
					( attribute "PN" "CJ2"
						( Origin gPackager )
					)
					( objectStatus "U5D1.CJ2" )
				)
				( pin "vss(460)"
					( attribute "PN" "CH83"
						( Origin gPackager )
					)
					( objectStatus "U5D1.CH83" )
				)
				( pin "vss(461)"
					( attribute "PN" "CH81"
						( Origin gPackager )
					)
					( objectStatus "U5D1.CH81" )
				)
				( pin "vss(462)"
					( attribute "PN" "CH79"
						( Origin gPackager )
					)
					( objectStatus "U5D1.CH79" )
				)
				( pin "vss(463)"
					( attribute "PN" "CH73"
						( Origin gPackager )
					)
					( objectStatus "U5D1.CH73" )
				)
				( pin "vss(464)"
					( attribute "PN" "CH67"
						( Origin gPackager )
					)
					( objectStatus "U5D1.CH67" )
				)
				( pin "vss(465)"
					( attribute "PN" "CH63"
						( Origin gPackager )
					)
					( objectStatus "U5D1.CH63" )
				)
				( pin "vss(466)"
					( attribute "PN" "CH19"
						( Origin gPackager )
					)
					( objectStatus "U5D1.CH19" )
				)
				( pin "vss(467)"
					( attribute "PN" "CH15"
						( Origin gPackager )
					)
					( objectStatus "U5D1.CH15" )
				)
				( pin "vss(468)"
					( attribute "PN" "CH3"
						( Origin gPackager )
					)
					( objectStatus "U5D1.CH3" )
				)
				( pin "vss(469)"
					( attribute "PN" "CH1"
						( Origin gPackager )
					)
					( objectStatus "U5D1.CH1" )
				)
				( pin "vss(470)"
					( attribute "PN" "CG80"
						( Origin gPackager )
					)
					( objectStatus "U5D1.CG80" )
				)
				( pin "vss(471)"
					( attribute "PN" "CG72"
						( Origin gPackager )
					)
					( objectStatus "U5D1.CG72" )
				)
				( pin "vss(472)"
					( attribute "PN" "CG68"
						( Origin gPackager )
					)
					( objectStatus "U5D1.CG68" )
				)
				( pin "vss(473)"
					( attribute "PN" "CG62"
						( Origin gPackager )
					)
					( objectStatus "U5D1.CG62" )
				)
				( pin "vss(474)"
					( attribute "PN" "CG22"
						( Origin gPackager )
					)
					( objectStatus "U5D1.CG22" )
				)
				( pin "vss(475)"
					( attribute "PN" "CG18"
						( Origin gPackager )
					)
					( objectStatus "U5D1.CG18" )
				)
				( pin "vss(476)"
					( attribute "PN" "P51"
						( Origin gPackager )
					)
					( objectStatus "U5D1.P51" )
				)
				( pin "vss(477)"
					( attribute "PN" "CF83"
						( Origin gPackager )
					)
					( objectStatus "U5D1.CF83" )
				)
				( pin "vss(478)"
					( attribute "PN" "CF77"
						( Origin gPackager )
					)
					( objectStatus "U5D1.CF77" )
				)
				( pin "vss(479)"
					( attribute "PN" "CF71"
						( Origin gPackager )
					)
					( objectStatus "U5D1.CF71" )
				)
				( pin "vss(480)"
					( attribute "PN" "CF69"
						( Origin gPackager )
					)
					( objectStatus "U5D1.CF69" )
				)
				( pin "vss(481)"
					( attribute "PN" "CF63"
						( Origin gPackager )
					)
					( objectStatus "U5D1.CF63" )
				)
				( pin "vss(482)"
					( attribute "PN" "CF9"
						( Origin gPackager )
					)
					( objectStatus "U5D1.CF9" )
				)
				( pin "vss(483)"
					( attribute "PN" "P53"
						( Origin gPackager )
					)
					( objectStatus "U5D1.P53" )
				)
				( pin "vss(484)"
					( attribute "PN" "CE82"
						( Origin gPackager )
					)
					( objectStatus "U5D1.CE82" )
				)
				( pin "vss(485)"
					( attribute "PN" "CE70"
						( Origin gPackager )
					)
					( objectStatus "U5D1.CE70" )
				)
				( pin "vss(486)"
					( attribute "PN" "CE62"
						( Origin gPackager )
					)
					( objectStatus "U5D1.CE62" )
				)
				( pin "vss(487)"
					( attribute "PN" "CE26"
						( Origin gPackager )
					)
					( objectStatus "U5D1.CE26" )
				)
				( pin "vss(488)"
					( attribute "PN" "CE20"
						( Origin gPackager )
					)
					( objectStatus "U5D1.CE20" )
				)
				( pin "vss(489)"
					( attribute "PN" "CE14"
						( Origin gPackager )
					)
					( objectStatus "U5D1.CE14" )
				)
				( pin "vss(490)"
					( attribute "PN" "CE10"
						( Origin gPackager )
					)
					( objectStatus "U5D1.CE10" )
				)
				( pin "vss(491)"
					( attribute "PN" "CD81"
						( Origin gPackager )
					)
					( objectStatus "U5D1.CD81" )
				)
				( pin "vss(492)"
					( attribute "PN" "CD79"
						( Origin gPackager )
					)
					( objectStatus "U5D1.CD79" )
				)
				( pin "vss(493)"
					( attribute "PN" "CD77"
						( Origin gPackager )
					)
					( objectStatus "U5D1.CD77" )
				)
				( pin "vss(494)"
					( attribute "PN" "CD75"
						( Origin gPackager )
					)
					( objectStatus "U5D1.CD75" )
				)
				( pin "vss(495)"
					( attribute "PN" "CD73"
						( Origin gPackager )
					)
					( objectStatus "U5D1.CD73" )
				)
				( pin "vss(496)"
					( attribute "PN" "CD63"
						( Origin gPackager )
					)
					( objectStatus "U5D1.CD63" )
				)
				( pin "vss(497)"
					( attribute "PN" "CD13"
						( Origin gPackager )
					)
					( objectStatus "U5D1.CD13" )
				)
				( pin "vss(498)"
					( attribute "PN" "CD5"
						( Origin gPackager )
					)
					( objectStatus "U5D1.CD5" )
				)
				( pin "vss(499)"
					( attribute "PN" "CC82"
						( Origin gPackager )
					)
					( objectStatus "U5D1.CC82" )
				)
				( pin "vss(500)"
					( attribute "PN" "CC80"
						( Origin gPackager )
					)
					( objectStatus "U5D1.CC80" )
				)
				( pin "vss(501)"
					( attribute "PN" "CC78"
						( Origin gPackager )
					)
					( objectStatus "U5D1.CC78" )
				)
				( pin "vss(502)"
					( attribute "PN" "CC76"
						( Origin gPackager )
					)
					( objectStatus "U5D1.CC76" )
				)
				( pin "vss(503)"
					( attribute "PN" "CC74"
						( Origin gPackager )
					)
					( objectStatus "U5D1.CC74" )
				)
				( pin "vss(504)"
					( attribute "PN" "CC72"
						( Origin gPackager )
					)
					( objectStatus "U5D1.CC72" )
				)
				( pin "vss(505)"
					( attribute "PN" "CC64"
						( Origin gPackager )
					)
					( objectStatus "U5D1.CC64" )
				)
				( pin "vss(506)"
					( attribute "PN" "CC24"
						( Origin gPackager )
					)
					( objectStatus "U5D1.CC24" )
				)
				( pin "vss(507)"
					( attribute "PN" "CC18"
						( Origin gPackager )
					)
					( objectStatus "U5D1.CC18" )
				)
				( pin "vss(508)"
					( attribute "PN" "CC16"
						( Origin gPackager )
					)
					( objectStatus "U5D1.CC16" )
				)
				( pin "vss(509)"
					( attribute "PN" "CC4"
						( Origin gPackager )
					)
					( objectStatus "U5D1.CC4" )
				)
				( pin "vss(510)"
					( attribute "PN" "CB71"
						( Origin gPackager )
					)
					( objectStatus "U5D1.CB71" )
				)
				( pin "vss(511)"
					( attribute "PN" "CB63"
						( Origin gPackager )
					)
					( objectStatus "U5D1.CB63" )
				)
				( pin "vss(512)"
					( attribute "PN" "CB27"
						( Origin gPackager )
					)
					( objectStatus "U5D1.CB27" )
				)
				( pin "vss(513)"
					( attribute "PN" "CB9"
						( Origin gPackager )
					)
					( objectStatus "U5D1.CB9" )
				)
				( pin "vss(514)"
					( attribute "PN" "CB7"
						( Origin gPackager )
					)
					( objectStatus "U5D1.CB7" )
				)
				( pin "vss(515)"
					( attribute "PN" "CA70"
						( Origin gPackager )
					)
					( objectStatus "U5D1.CA70" )
				)
				( pin "vss(516)"
					( attribute "PN" "CA68"
						( Origin gPackager )
					)
					( objectStatus "U5D1.CA68" )
				)
				( pin "vss(517)"
					( attribute "PN" "CA66"
						( Origin gPackager )
					)
					( objectStatus "U5D1.CA66" )
				)
				( pin "vss(518)"
					( attribute "PN" "CA64"
						( Origin gPackager )
					)
					( objectStatus "U5D1.CA64" )
				)
				( pin "vss(519)"
					( attribute "PN" "CA26"
						( Origin gPackager )
					)
					( objectStatus "U5D1.CA26" )
				)
				( pin "vss(520)"
					( attribute "PN" "CA18"
						( Origin gPackager )
					)
					( objectStatus "U5D1.CA18" )
				)
				( pin "vss(521)"
					( attribute "PN" "CA14"
						( Origin gPackager )
					)
					( objectStatus "U5D1.CA14" )
				)
				( pin "vss(522)"
					( attribute "PN" "CA10"
						( Origin gPackager )
					)
					( objectStatus "U5D1.CA10" )
				)
				( pin "vss(523)"
					( attribute "PN" "CA8"
						( Origin gPackager )
					)
					( objectStatus "U5D1.CA8" )
				)
				( pin "vss(524)"
					( attribute "PN" "CA6"
						( Origin gPackager )
					)
					( objectStatus "U5D1.CA6" )
				)
				( pin "vss(525)"
					( attribute "PN" "CA2"
						( Origin gPackager )
					)
					( objectStatus "U5D1.CA2" )
				)
				( pin "vss(526)"
					( attribute "PN" "BY71"
						( Origin gPackager )
					)
					( objectStatus "U5D1.BY71" )
				)
				( pin "vss(527)"
					( attribute "PN" "BY69"
						( Origin gPackager )
					)
					( objectStatus "U5D1.BY69" )
				)
				( pin "vss(528)"
					( attribute "PN" "BY67"
						( Origin gPackager )
					)
					( objectStatus "U5D1.BY67" )
				)
				( pin "vss(529)"
					( attribute "PN" "BY65"
						( Origin gPackager )
					)
					( objectStatus "U5D1.BY65" )
				)
				( pin "vss(530)"
					( attribute "PN" "BY63"
						( Origin gPackager )
					)
					( objectStatus "U5D1.BY63" )
				)
				( pin "vss(531)"
					( attribute "PN" "BY23"
						( Origin gPackager )
					)
					( objectStatus "U5D1.BY23" )
				)
				( pin "vss(532)"
					( attribute "PN" "BY13"
						( Origin gPackager )
					)
					( objectStatus "U5D1.BY13" )
				)
				( pin "vss(533)"
					( attribute "PN" "BY11"
						( Origin gPackager )
					)
					( objectStatus "U5D1.BY11" )
				)
				( pin "vss(534)"
					( attribute "PN" "BW82"
						( Origin gPackager )
					)
					( objectStatus "U5D1.BW82" )
				)
				( pin "vss(535)"
					( attribute "PN" "BW80"
						( Origin gPackager )
					)
					( objectStatus "U5D1.BW80" )
				)
				( pin "vss(536)"
					( attribute "PN" "BW78"
						( Origin gPackager )
					)
					( objectStatus "U5D1.BW78" )
				)
				( pin "vss(537)"
					( attribute "PN" "BW76"
						( Origin gPackager )
					)
					( objectStatus "U5D1.BW76" )
				)
				( pin "vss(538)"
					( attribute "PN" "BW74"
						( Origin gPackager )
					)
					( objectStatus "U5D1.BW74" )
				)
				( pin "vss(539)"
					( attribute "PN" "BW72"
						( Origin gPackager )
					)
					( objectStatus "U5D1.BW72" )
				)
				( pin "vss(540)"
					( attribute "PN" "BW26"
						( Origin gPackager )
					)
					( objectStatus "U5D1.BW26" )
				)
				( pin "vss(541)"
					( attribute "PN" "BW18"
						( Origin gPackager )
					)
					( objectStatus "U5D1.BW18" )
				)
				( pin "vss(542)"
					( attribute "PN" "BW16"
						( Origin gPackager )
					)
					( objectStatus "U5D1.BW16" )
				)
				( pin "vss(543)"
					( attribute "PN" "BW14"
						( Origin gPackager )
					)
					( objectStatus "U5D1.BW14" )
				)
				( pin "vss(544)"
					( attribute "PN" "BW12"
						( Origin gPackager )
					)
					( objectStatus "U5D1.BW12" )
				)
				( pin "vss(545)"
					( attribute "PN" "P55"
						( Origin gPackager )
					)
					( objectStatus "U5D1.P55" )
				)
				( pin "vss(546)"
					( attribute "PN" "BW6"
						( Origin gPackager )
					)
					( objectStatus "U5D1.BW6" )
				)
				( pin "vss(547)"
					( attribute "PN" "BV25"
						( Origin gPackager )
					)
					( objectStatus "U5D1.BV25" )
				)
				( pin "vss(548)"
					( attribute "PN" "BV17"
						( Origin gPackager )
					)
					( objectStatus "U5D1.BV17" )
				)
				( pin "vss(549)"
					( attribute "PN" "BU10"
						( Origin gPackager )
					)
					( objectStatus "U5D1.BU10" )
				)
				( pin "vss(550)"
					( attribute "PN" "BV5"
						( Origin gPackager )
					)
					( objectStatus "U5D1.BV5" )
				)
				( pin "vss(551)"
					( attribute "PN" "BU8"
						( Origin gPackager )
					)
					( objectStatus "U5D1.BU8" )
				)
				( pin "vss(552)"
					( attribute "PN" "BT25"
						( Origin gPackager )
					)
					( objectStatus "U5D1.BT25" )
				)
				( pin "vss(553)"
					( attribute "PN" "BT23"
						( Origin gPackager )
					)
					( objectStatus "U5D1.BT23" )
				)
				( pin "vss(554)"
					( attribute "PN" "BT21"
						( Origin gPackager )
					)
					( objectStatus "U5D1.BT21" )
				)
				( pin "vss(555)"
					( attribute "PN" "BT5"
						( Origin gPackager )
					)
					( objectStatus "U5D1.BT5" )
				)
				( pin "vss(556)"
					( attribute "PN" "BT3"
						( Origin gPackager )
					)
					( objectStatus "U5D1.BT3" )
				)
				( pin "vss(557)"
					( attribute "PN" "BR82"
						( Origin gPackager )
					)
					( objectStatus "U5D1.BR82" )
				)
				( pin "vss(558)"
					( attribute "PN" "BR80"
						( Origin gPackager )
					)
					( objectStatus "U5D1.BR80" )
				)
				( pin "vss(559)"
					( attribute "PN" "BR78"
						( Origin gPackager )
					)
					( objectStatus "U5D1.BR78" )
				)
				( pin "vss(560)"
					( attribute "PN" "BR76"
						( Origin gPackager )
					)
					( objectStatus "U5D1.BR76" )
				)
				( pin "vss(561)"
					( attribute "PN" "BR74"
						( Origin gPackager )
					)
					( objectStatus "U5D1.BR74" )
				)
				( pin "vss(562)"
					( attribute "PN" "BR72"
						( Origin gPackager )
					)
					( objectStatus "U5D1.BR72" )
				)
				( pin "vss(563)"
					( attribute "PN" "BR70"
						( Origin gPackager )
					)
					( objectStatus "U5D1.BR70" )
				)
				( pin "vss(564)"
					( attribute "PN" "BR68"
						( Origin gPackager )
					)
					( objectStatus "U5D1.BR68" )
				)
				( pin "vss(565)"
					( attribute "PN" "BR66"
						( Origin gPackager )
					)
					( objectStatus "U5D1.BR66" )
				)
				( pin "vss(566)"
					( attribute "PN" "BR64"
						( Origin gPackager )
					)
					( objectStatus "U5D1.BR64" )
				)
				( pin "vss(567)"
					( attribute "PN" "P57"
						( Origin gPackager )
					)
					( objectStatus "U5D1.P57" )
				)
				( pin "vss(568)"
					( attribute "PN" "BR16"
						( Origin gPackager )
					)
					( objectStatus "U5D1.BR16" )
				)
				( pin "vss(569)"
					( attribute "PN" "BR10"
						( Origin gPackager )
					)
					( objectStatus "U5D1.BR10" )
				)
				( pin "vss(570)"
					( attribute "PN" "BR6"
						( Origin gPackager )
					)
					( objectStatus "U5D1.BR6" )
				)
				( pin "vss(571)"
					( attribute "PN" "BP27"
						( Origin gPackager )
					)
					( objectStatus "U5D1.BP27" )
				)
				( pin "vss(572)"
					( attribute "PN" "BP3"
						( Origin gPackager )
					)
					( objectStatus "U5D1.BP3" )
				)
				( pin "vss(573)"
					( attribute "PN" "BN26"
						( Origin gPackager )
					)
					( objectStatus "U5D1.BN26" )
				)
				( pin "vss(574)"
					( attribute "PN" "BN20"
						( Origin gPackager )
					)
					( objectStatus "U5D1.BN20" )
				)
				( pin "vss(575)"
					( attribute "PN" "BN10"
						( Origin gPackager )
					)
					( objectStatus "U5D1.BN10" )
				)
				( pin "vss(576)"
					( attribute "PN" "BN6"
						( Origin gPackager )
					)
					( objectStatus "U5D1.BN6" )
				)
				( pin "vss(577)"
					( attribute "PN" "BM25"
						( Origin gPackager )
					)
					( objectStatus "U5D1.BM25" )
				)
				( pin "vss(578)"
					( attribute "PN" "P59"
						( Origin gPackager )
					)
					( objectStatus "U5D1.P59" )
				)
				( pin "vss(579)"
					( attribute "PN" "BM15"
						( Origin gPackager )
					)
					( objectStatus "U5D1.BM15" )
				)
				( pin "vss(580)"
					( attribute "PN" "BM13"
						( Origin gPackager )
					)
					( objectStatus "U5D1.BM13" )
				)
				( pin "vss(581)"
					( attribute "PN" "BM9"
						( Origin gPackager )
					)
					( objectStatus "U5D1.BM9" )
				)
				( pin "vss(582)"
					( attribute "PN" "BL82"
						( Origin gPackager )
					)
					( objectStatus "U5D1.BL82" )
				)
				( pin "vss(583)"
					( attribute "PN" "BL80"
						( Origin gPackager )
					)
					( objectStatus "U5D1.BL80" )
				)
				( pin "vss(584)"
					( attribute "PN" "BL78"
						( Origin gPackager )
					)
					( objectStatus "U5D1.BL78" )
				)
				( pin "vss(585)"
					( attribute "PN" "BL76"
						( Origin gPackager )
					)
					( objectStatus "U5D1.BL76" )
				)
				( pin "vss(586)"
					( attribute "PN" "BL74"
						( Origin gPackager )
					)
					( objectStatus "U5D1.BL74" )
				)
				( pin "vss(587)"
					( attribute "PN" "BL72"
						( Origin gPackager )
					)
					( objectStatus "U5D1.BL72" )
				)
				( pin "vss(588)"
					( attribute "PN" "BL70"
						( Origin gPackager )
					)
					( objectStatus "U5D1.BL70" )
				)
				( pin "vss(589)"
					( attribute "PN" "BL68"
						( Origin gPackager )
					)
					( objectStatus "U5D1.BL68" )
				)
				( pin "vss(590)"
					( attribute "PN" "BL66"
						( Origin gPackager )
					)
					( objectStatus "U5D1.BL66" )
				)
				( pin "vss(591)"
					( attribute "PN" "BL64"
						( Origin gPackager )
					)
					( objectStatus "U5D1.BL64" )
				)
				( pin "vss(592)"
					( attribute "PN" "BL24"
						( Origin gPackager )
					)
					( objectStatus "U5D1.BL24" )
				)
				( pin "vss(593)"
					( attribute "PN" "BL22"
						( Origin gPackager )
					)
					( objectStatus "U5D1.BL22" )
				)
				( pin "vss(594)"
					( attribute "PN" "P61"
						( Origin gPackager )
					)
					( objectStatus "U5D1.P61" )
				)
				( pin "vss(595)"
					( attribute "PN" "BL12"
						( Origin gPackager )
					)
					( objectStatus "U5D1.BL12" )
				)
				( pin "vss(596)"
					( attribute "PN" "BL10"
						( Origin gPackager )
					)
					( objectStatus "U5D1.BL10" )
				)
				( pin "vss(597)"
					( attribute "PN" "BL6"
						( Origin gPackager )
					)
					( objectStatus "U5D1.BL6" )
				)
				( pin "vss(598)"
					( attribute "PN" "BK19"
						( Origin gPackager )
					)
					( objectStatus "U5D1.BK19" )
				)
				( pin "vss(599)"
					( attribute "PN" "BK11"
						( Origin gPackager )
					)
					( objectStatus "U5D1.BK11" )
				)
				( pin "vss(600)"
					( attribute "PN" "BK7"
						( Origin gPackager )
					)
					( objectStatus "U5D1.BK7" )
				)
				( pin "vss(601)"
					( attribute "PN" "BK3"
						( Origin gPackager )
					)
					( objectStatus "U5D1.BK3" )
				)
				( pin "vss(602)"
					( attribute "PN" "BJ6"
						( Origin gPackager )
					)
					( objectStatus "U5D1.BJ6" )
				)
				( pin "vss(603)"
					( attribute "PN" "BJ4"
						( Origin gPackager )
					)
					( objectStatus "U5D1.BJ4" )
				)
				( pin "vss(604)"
					( attribute "PN" "BH21"
						( Origin gPackager )
					)
					( objectStatus "U5D1.BH21" )
				)
				( pin "vss(605)"
					( attribute "PN" "BH15"
						( Origin gPackager )
					)
					( objectStatus "U5D1.BH15" )
				)
				( pin "vss(606)"
					( attribute "PN" "BH11"
						( Origin gPackager )
					)
					( objectStatus "U5D1.BH11" )
				)
				( pin "vss(607)"
					( attribute "PN" "BH9"
						( Origin gPackager )
					)
					( objectStatus "U5D1.BH9" )
				)
				( pin "vss(608)"
					( attribute "PN" "BH7"
						( Origin gPackager )
					)
					( objectStatus "U5D1.BH7" )
				)
				( pin "vss(609)"
					( attribute "PN" "BG82"
						( Origin gPackager )
					)
					( objectStatus "U5D1.BG82" )
				)
				( pin "vss(610)"
					( attribute "PN" "BG80"
						( Origin gPackager )
					)
					( objectStatus "U5D1.BG80" )
				)
				( pin "vss(611)"
					( attribute "PN" "BG78"
						( Origin gPackager )
					)
					( objectStatus "U5D1.BG78" )
				)
				( pin "vss(612)"
					( attribute "PN" "BG76"
						( Origin gPackager )
					)
					( objectStatus "U5D1.BG76" )
				)
				( pin "vss(613)"
					( attribute "PN" "BG74"
						( Origin gPackager )
					)
					( objectStatus "U5D1.BG74" )
				)
			)
			( gate "@baseboard_fab2_lib.baseboard_fab2(sch_1):page41_i284"
				( attribute "CDS_LIB" "chpset_lib"
					( Origin gPackager )
				)
				( attribute "CDS_LOCATION" "U5D1"
					( Origin gPackager )
				)
				( attribute "CDS_SEC" "28"
					( Origin gPackager )
				)
				( attribute "LOCATION" "U5D1"
					( Origin gFrontEnd )
				)
				( attribute "MATERIAL" "IC"
					( Origin gFrontEnd )
				)
				( attribute "PACK_TYPE" "BGA1"
					( Origin gFrontEnd )
				)
				( attribute "PART_NUMBER" "TBD"
					( Origin gFrontEnd )
				)
				( attribute "PHYS_PAGE" "41"
					( Origin gFrontEnd )
				)
				( attribute "ROOM" "CPU0"
					( Origin gFrontEnd )
				)
				( attribute "ROT" "0"
					( Origin gFrontEnd )
				)
				( attribute "SEC" "28"
					( Origin gFrontEnd )
				)
				( attribute "SEC_TYPE" "BGA1"
					( Origin gFrontEnd )
				)
				( attribute "VER" "28"
					( Origin gFrontEnd )
				)
				( attribute "XY" "(-3575,2650)"
					( Origin gFrontEnd )
				)
				( attribute "CHIPS_PART_NAME" "SKX_EXT_B"
					( Origin gPackager )
				)
				( attribute "CDS_PART_NAME" "SKX_EXT_B_BGA1-IC,TBD"
					( Origin gPackager )
				)
				( objectStatus "U5D1" )
				( pin "vss(294)"
					( attribute "PN" "DA46"
						( Origin gPackager )
					)
					( objectStatus "U5D1.DA46" )
				)
				( pin "vss(295)"
					( attribute "PN" "DA44"
						( Origin gPackager )
					)
					( objectStatus "U5D1.DA44" )
				)
				( pin "vss(296)"
					( attribute "PN" "DA38"
						( Origin gPackager )
					)
					( objectStatus "U5D1.DA38" )
				)
				( pin "vss(297)"
					( attribute "PN" "DA36"
						( Origin gPackager )
					)
					( objectStatus "U5D1.DA36" )
				)
				( pin "vss(298)"
					( attribute "PN" "DA34"
						( Origin gPackager )
					)
					( objectStatus "U5D1.DA34" )
				)
				( pin "vss(299)"
					( attribute "PN" "DA32"
						( Origin gPackager )
					)
					( objectStatus "U5D1.DA32" )
				)
				( pin "vss(300)"
					( attribute "PN" "DA30"
						( Origin gPackager )
					)
					( objectStatus "U5D1.DA30" )
				)
				( pin "vss(301)"
					( attribute "PN" "DA28"
						( Origin gPackager )
					)
					( objectStatus "U5D1.DA28" )
				)
				( pin "vss(302)"
					( attribute "PN" "DA26"
						( Origin gPackager )
					)
					( objectStatus "U5D1.DA26" )
				)
				( pin "vss(303)"
					( attribute "PN" "DA18"
						( Origin gPackager )
					)
					( objectStatus "U5D1.DA18" )
				)
				( pin "vss(304)"
					( attribute "PN" "H53"
						( Origin gPackager )
					)
					( objectStatus "U5D1.H53" )
				)
				( pin "vss(305)"
					( attribute "PN" "DA6"
						( Origin gPackager )
					)
					( objectStatus "U5D1.DA6" )
				)
				( pin "vss(306)"
					( attribute "PN" "CY85"
						( Origin gPackager )
					)
					( objectStatus "U5D1.CY85" )
				)
				( pin "vss(307)"
					( attribute "PN" "CY83"
						( Origin gPackager )
					)
					( objectStatus "U5D1.CY83" )
				)
				( pin "vss(308)"
					( attribute "PN" "CY77"
						( Origin gPackager )
					)
					( objectStatus "U5D1.CY77" )
				)
				( pin "vss(309)"
					( attribute "PN" "CY75"
						( Origin gPackager )
					)
					( objectStatus "U5D1.CY75" )
				)
				( pin "vss(310)"
					( attribute "PN" "CY69"
						( Origin gPackager )
					)
					( objectStatus "U5D1.CY69" )
				)
				( pin "vss(311)"
					( attribute "PN" "CY65"
						( Origin gPackager )
					)
					( objectStatus "U5D1.CY65" )
				)
				( pin "vss(312)"
					( attribute "PN" "CY61"
						( Origin gPackager )
					)
					( objectStatus "U5D1.CY61" )
				)
				( pin "vss(313)"
					( attribute "PN" "CY59"
						( Origin gPackager )
					)
					( objectStatus "U5D1.CY59" )
				)
				( pin "vss(314)"
					( attribute "PN" "CY51"
						( Origin gPackager )
					)
					( objectStatus "U5D1.CY51" )
				)
				( pin "vss(315)"
					( attribute "PN" "CY45"
						( Origin gPackager )
					)
					( objectStatus "U5D1.CY45" )
				)
				( pin "vss(316)"
					( attribute "PN" "CY41"
						( Origin gPackager )
					)
					( objectStatus "U5D1.CY41" )
				)
				( pin "vss(317)"
					( attribute "PN" "CY21"
						( Origin gPackager )
					)
					( objectStatus "U5D1.CY21" )
				)
				( pin "vss(318)"
					( attribute "PN" "CY15"
						( Origin gPackager )
					)
					( objectStatus "U5D1.CY15" )
				)
				( pin "vss(319)"
					( attribute "PN" "CY13"
						( Origin gPackager )
					)
					( objectStatus "U5D1.CY13" )
				)
				( pin "vss(320)"
					( attribute "PN" "CY9"
						( Origin gPackager )
					)
					( objectStatus "U5D1.CY9" )
				)
				( pin "vss(321)"
					( attribute "PN" "CY1"
						( Origin gPackager )
					)
					( objectStatus "U5D1.CY1" )
				)
				( pin "vss(322)"
					( attribute "PN" "CW82"
						( Origin gPackager )
					)
					( objectStatus "U5D1.CW82" )
				)
				( pin "vss(323)"
					( attribute "PN" "CW78"
						( Origin gPackager )
					)
					( objectStatus "U5D1.CW78" )
				)
				( pin "vss(324)"
					( attribute "PN" "CW74"
						( Origin gPackager )
					)
					( objectStatus "U5D1.CW74" )
				)
				( pin "vss(325)"
					( attribute "PN" "CW68"
						( Origin gPackager )
					)
					( objectStatus "U5D1.CW68" )
				)
				( pin "vss(326)"
					( attribute "PN" "CW66"
						( Origin gPackager )
					)
					( objectStatus "U5D1.CW66" )
				)
				( pin "vss(327)"
					( attribute "PN" "CW64"
						( Origin gPackager )
					)
					( objectStatus "U5D1.CW64" )
				)
				( pin "vss(328)"
					( attribute "PN" "CW54"
						( Origin gPackager )
					)
					( objectStatus "U5D1.CW54" )
				)
				( pin "vss(329)"
					( attribute "PN" "CW52"
						( Origin gPackager )
					)
					( objectStatus "U5D1.CW52" )
				)
				( pin "vss(330)"
					( attribute "PN" "CW42"
						( Origin gPackager )
					)
					( objectStatus "U5D1.CW42" )
				)
				( pin "vss(331)"
					( attribute "PN" "CW40"
						( Origin gPackager )
					)
					( objectStatus "U5D1.CW40" )
				)
				( pin "vss(332)"
					( attribute "PN" "CW38"
						( Origin gPackager )
					)
					( objectStatus "U5D1.CW38" )
				)
				( pin "vss(333)"
					( attribute "PN" "CW32"
						( Origin gPackager )
					)
					( objectStatus "U5D1.CW32" )
				)
				( pin "vss(334)"
					( attribute "PN" "CW26"
						( Origin gPackager )
					)
					( objectStatus "U5D1.CW26" )
				)
				( pin "vss(335)"
					( attribute "PN" "CW12"
						( Origin gPackager )
					)
					( objectStatus "U5D1.CW12" )
				)
				( pin "vss(336)"
					( attribute "PN" "CV83"
						( Origin gPackager )
					)
					( objectStatus "U5D1.CV83" )
				)
				( pin "vss(337)"
					( attribute "PN" "CV81"
						( Origin gPackager )
					)
					( objectStatus "U5D1.CV81" )
				)
				( pin "vss(338)"
					( attribute "PN" "CV79"
						( Origin gPackager )
					)
					( objectStatus "U5D1.CV79" )
				)
				( pin "vss(339)"
					( attribute "PN" "CV73"
						( Origin gPackager )
					)
					( objectStatus "U5D1.CV73" )
				)
				( pin "vss(340)"
					( attribute "PN" "CV67"
						( Origin gPackager )
					)
					( objectStatus "U5D1.CV67" )
				)
				( pin "vss(341)"
					( attribute "PN" "CV63"
						( Origin gPackager )
					)
					( objectStatus "U5D1.CV63" )
				)
				( pin "vss(342)"
					( attribute "PN" "CV55"
						( Origin gPackager )
					)
					( objectStatus "U5D1.CV55" )
				)
				( pin "vss(343)"
					( attribute "PN" "CV53"
						( Origin gPackager )
					)
					( objectStatus "U5D1.CV53" )
				)
				( pin "vss(344)"
					( attribute "PN" "CV41"
						( Origin gPackager )
					)
					( objectStatus "U5D1.CV41" )
				)
				( pin "vss(345)"
					( attribute "PN" "CV39"
						( Origin gPackager )
					)
					( objectStatus "U5D1.CV39" )
				)
				( pin "vss(346)"
					( attribute "PN" "CV37"
						( Origin gPackager )
					)
					( objectStatus "U5D1.CV37" )
				)
				( pin "vss(347)"
					( attribute "PN" "CV33"
						( Origin gPackager )
					)
					( objectStatus "U5D1.CV33" )
				)
				( pin "vss(348)"
					( attribute "PN" "CV31"
						( Origin gPackager )
					)
					( objectStatus "U5D1.CV31" )
				)
				( pin "vss(349)"
					( attribute "PN" "CV27"
						( Origin gPackager )
					)
					( objectStatus "U5D1.CV27" )
				)
				( pin "vss(350)"
					( attribute "PN" "CV25"
						( Origin gPackager )
					)
					( objectStatus "U5D1.CV25" )
				)
				( pin "vss(351)"
					( attribute "PN" "CV17"
						( Origin gPackager )
					)
					( objectStatus "U5D1.CV17" )
				)
				( pin "vss(352)"
					( attribute "PN" "H55"
						( Origin gPackager )
					)
					( objectStatus "U5D1.H55" )
				)
				( pin "vss(353)"
					( attribute "PN" "CV1"
						( Origin gPackager )
					)
					( objectStatus "U5D1.CV1" )
				)
				( pin "vss(354)"
					( attribute "PN" "CU86"
						( Origin gPackager )
					)
					( objectStatus "U5D1.CU86" )
				)
				( pin "vss(355)"
					( attribute "PN" "CU82"
						( Origin gPackager )
					)
					( objectStatus "U5D1.CU82" )
				)
				( pin "vss(356)"
					( attribute "PN" "CU80"
						( Origin gPackager )
					)
					( objectStatus "U5D1.CU80" )
				)
				( pin "vss(357)"
					( attribute "PN" "CU78"
						( Origin gPackager )
					)
					( objectStatus "U5D1.CU78" )
				)
				( pin "vss(358)"
					( attribute "PN" "CU76"
						( Origin gPackager )
					)
					( objectStatus "U5D1.CU76" )
				)
				( pin "vss(359)"
					( attribute "PN" "CU68"
						( Origin gPackager )
					)
					( objectStatus "U5D1.CU68" )
				)
				( pin "vss(360)"
					( attribute "PN" "CU62"
						( Origin gPackager )
					)
					( objectStatus "U5D1.CU62" )
				)
				( pin "vss(361)"
					( attribute "PN" "CU56"
						( Origin gPackager )
					)
					( objectStatus "U5D1.CU56" )
				)
				( pin "vss(362)"
					( attribute "PN" "CU36"
						( Origin gPackager )
					)
					( objectStatus "U5D1.CU36" )
				)
				( pin "vss(363)"
					( attribute "PN" "CU34"
						( Origin gPackager )
					)
					( objectStatus "U5D1.CU34" )
				)
				( pin "vss(364)"
					( attribute "PN" "CU30"
						( Origin gPackager )
					)
					( objectStatus "U5D1.CU30" )
				)
				( pin "vss(365)"
					( attribute "PN" "CU28"
						( Origin gPackager )
					)
					( objectStatus "U5D1.CU28" )
				)
				( pin "vss(366)"
					( attribute "PN" "CU22"
						( Origin gPackager )
					)
					( objectStatus "U5D1.CU22" )
				)
				( pin "vss(367)"
					( attribute "PN" "CU4"
						( Origin gPackager )
					)
					( objectStatus "U5D1.CU4" )
				)
				( pin "vss(368)"
					( attribute "PN" "CT85"
						( Origin gPackager )
					)
					( objectStatus "U5D1.CT85" )
				)
				( pin "vss(369)"
					( attribute "PN" "CT83"
						( Origin gPackager )
					)
					( objectStatus "U5D1.CT83" )
				)
				( pin "vss(370)"
					( attribute "PN" "CT79"
						( Origin gPackager )
					)
					( objectStatus "U5D1.CT79" )
				)
				( pin "vss(371)"
					( attribute "PN" "CT73"
						( Origin gPackager )
					)
					( objectStatus "U5D1.CT73" )
				)
				( pin "vss(372)"
					( attribute "PN" "CT57"
						( Origin gPackager )
					)
					( objectStatus "U5D1.CT57" )
				)
				( pin "vss(373)"
					( attribute "PN" "CT35"
						( Origin gPackager )
					)
					( objectStatus "U5D1.CT35" )
				)
				( pin "vss(374)"
					( attribute "PN" "CT33"
						( Origin gPackager )
					)
					( objectStatus "U5D1.CT33" )
				)
				( pin "vss(375)"
					( attribute "PN" "CT29"
						( Origin gPackager )
					)
					( objectStatus "U5D1.CT29" )
				)
				( pin "vss(376)"
					( attribute "PN" "CT27"
						( Origin gPackager )
					)
					( objectStatus "U5D1.CT27" )
				)
				( pin "vss(377)"
					( attribute "PN" "CT19"
						( Origin gPackager )
					)
					( objectStatus "U5D1.CT19" )
				)
				( pin "vss(378)"
					( attribute "PN" "CT13"
						( Origin gPackager )
					)
					( objectStatus "U5D1.CT13" )
				)
				( pin "vss(379)"
					( attribute "PN" "H57"
						( Origin gPackager )
					)
					( objectStatus "U5D1.H57" )
				)
				( pin "vss(380)"
					( attribute "PN" "CR86"
						( Origin gPackager )
					)
					( objectStatus "U5D1.CR86" )
				)
				( pin "vss(381)"
					( attribute "PN" "CR78"
						( Origin gPackager )
					)
					( objectStatus "U5D1.CR78" )
				)
				( pin "vss(382)"
					( attribute "PN" "CR68"
						( Origin gPackager )
					)
					( objectStatus "U5D1.CR68" )
				)
				( pin "vss(383)"
					( attribute "PN" "CR66"
						( Origin gPackager )
					)
					( objectStatus "U5D1.CR66" )
				)
				( pin "vss(384)"
					( attribute "PN" "CR64"
						( Origin gPackager )
					)
					( objectStatus "U5D1.CR64" )
				)
				( pin "vss(385)"
					( attribute "PN" "CR62"
						( Origin gPackager )
					)
					( objectStatus "U5D1.CR62" )
				)
				( pin "vss(386)"
					( attribute "PN" "CR58"
						( Origin gPackager )
					)
					( objectStatus "U5D1.CR58" )
				)
				( pin "vss(387)"
					( attribute "PN" "CR32"
						( Origin gPackager )
					)
					( objectStatus "U5D1.CR32" )
				)
				( pin "vss(388)"
					( attribute "PN" "CR24"
						( Origin gPackager )
					)
					( objectStatus "U5D1.CR24" )
				)
				( pin "vss(389)"
					( attribute "PN" "CR22"
						( Origin gPackager )
					)
					( objectStatus "U5D1.CR22" )
				)
				( pin "vss(390)"
					( attribute "PN" "CR10"
						( Origin gPackager )
					)
					( objectStatus "U5D1.CR10" )
				)
				( pin "vss(391)"
					( attribute "PN" "CR6"
						( Origin gPackager )
					)
					( objectStatus "U5D1.CR6" )
				)
				( pin "vss(392)"
					( attribute "PN" "CP83"
						( Origin gPackager )
					)
					( objectStatus "U5D1.CP83" )
				)
				( pin "vss(393)"
					( attribute "PN" "CP81"
						( Origin gPackager )
					)
					( objectStatus "U5D1.CP81" )
				)
				( pin "vss(394)"
					( attribute "PN" "CP75"
						( Origin gPackager )
					)
					( objectStatus "U5D1.CP75" )
				)
				( pin "vss(395)"
					( attribute "PN" "CP73"
						( Origin gPackager )
					)
					( objectStatus "U5D1.CP73" )
				)
				( pin "vss(396)"
					( attribute "PN" "CP69"
						( Origin gPackager )
					)
					( objectStatus "U5D1.CP69" )
				)
				( pin "vss(397)"
					( attribute "PN" "CP59"
						( Origin gPackager )
					)
					( objectStatus "U5D1.CP59" )
				)
				( pin "vss(398)"
					( attribute "PN" "CP25"
						( Origin gPackager )
					)
					( objectStatus "U5D1.CP25" )
				)
				( pin "vss(399)"
					( attribute "PN" "H59"
						( Origin gPackager )
					)
					( objectStatus "U5D1.H59" )
				)
				( pin "vss(400)"
					( attribute "PN" "CP1"
						( Origin gPackager )
					)
					( objectStatus "U5D1.CP1" )
				)
				( pin "vss(401)"
					( attribute "PN" "CN78"
						( Origin gPackager )
					)
					( objectStatus "U5D1.CN78" )
				)
				( pin "vss(402)"
					( attribute "PN" "CN68"
						( Origin gPackager )
					)
					( objectStatus "U5D1.CN68" )
				)
				( pin "vss(403)"
					( attribute "PN" "CN62"
						( Origin gPackager )
					)
					( objectStatus "U5D1.CN62" )
				)
				( pin "vss(404)"
					( attribute "PN" "CN60"
						( Origin gPackager )
					)
					( objectStatus "U5D1.CN60" )
				)
				( pin "vss(405)"
					( attribute "PN" "CN32"
						( Origin gPackager )
					)
					( objectStatus "U5D1.CN32" )
				)
				( pin "vss(406)"
					( attribute "PN" "CN26"
						( Origin gPackager )
					)
					( objectStatus "U5D1.CN26" )
				)
				( pin "vss(407)"
					( attribute "PN" "H61"
						( Origin gPackager )
					)
					( objectStatus "U5D1.H61" )
				)
				( pin "vss(408)"
					( attribute "PN" "CN12"
						( Origin gPackager )
					)
					( objectStatus "U5D1.CN12" )
				)
				( pin "vss(409)"
					( attribute "PN" "CN2"
						( Origin gPackager )
					)
					( objectStatus "U5D1.CN2" )
				)
				( pin "vss(410)"
					( attribute "PN" "CM85"
						( Origin gPackager )
					)
					( objectStatus "U5D1.CM85" )
				)
				( pin "vss(411)"
					( attribute "PN" "CM83"
						( Origin gPackager )
					)
					( objectStatus "U5D1.CM83" )
				)
				( pin "vss(412)"
					( attribute "PN" "CM77"
						( Origin gPackager )
					)
					( objectStatus "U5D1.CM77" )
				)
				( pin "vss(413)"
					( attribute "PN" "CM73"
						( Origin gPackager )
					)
					( objectStatus "U5D1.CM73" )
				)
				( pin "vss(414)"
					( attribute "PN" "CM67"
						( Origin gPackager )
					)
					( objectStatus "U5D1.CM67" )
				)
				( pin "vss(415)"
					( attribute "PN" "CM63"
						( Origin gPackager )
					)
					( objectStatus "U5D1.CM63" )
				)
				( pin "vss(416)"
					( attribute "PN" "CM61"
						( Origin gPackager )
					)
					( objectStatus "U5D1.CM61" )
				)
				( pin "vss(417)"
					( attribute "PN" "CM31"
						( Origin gPackager )
					)
					( objectStatus "U5D1.CM31" )
				)
				( pin "vss(418)"
					( attribute "PN" "CM5"
						( Origin gPackager )
					)
					( objectStatus "U5D1.CM5" )
				)
				( pin "vss(419)"
					( attribute "PN" "CM29"
						( Origin gPackager )
					)
					( objectStatus "U5D1.CM29" )
				)
				( pin "vss(420)"
					( attribute "PN" "CM19"
						( Origin gPackager )
					)
					( objectStatus "U5D1.CM19" )
				)
				( pin "vss(421)"
					( attribute "PN" "CL80"
						( Origin gPackager )
					)
					( objectStatus "U5D1.CL80" )
				)
				( pin "vss(422)"
					( attribute "PN" "CL78"
						( Origin gPackager )
					)
					( objectStatus "U5D1.CL78" )
				)
				( pin "vss(423)"
					( attribute "PN" "CL76"
						( Origin gPackager )
					)
					( objectStatus "U5D1.CL76" )
				)
				( pin "vss(424)"
					( attribute "PN" "CL74"
						( Origin gPackager )
					)
					( objectStatus "U5D1.CL74" )
				)
				( pin "vss(425)"
					( attribute "PN" "CL66"
						( Origin gPackager )
					)
					( objectStatus "U5D1.CL66" )
				)
				( pin "vss(426)"
					( attribute "PN" "CL64"
						( Origin gPackager )
					)
					( objectStatus "U5D1.CL64" )
				)
				( pin "vss(427)"
					( attribute "PN" "CL62"
						( Origin gPackager )
					)
					( objectStatus "U5D1.CL62" )
				)
				( pin "vss(428)"
					( attribute "PN" "H63"
						( Origin gPackager )
					)
					( objectStatus "U5D1.H63" )
				)
				( pin "vss(429)"
					( attribute "PN" "P45"
						( Origin gPackager )
					)
					( objectStatus "U5D1.P45" )
				)
				( pin "vss(430)"
					( attribute "PN" "CL18"
						( Origin gPackager )
					)
					( objectStatus "U5D1.CL18" )
				)
				( pin "vss(431)"
					( attribute "PN" "CL14"
						( Origin gPackager )
					)
					( objectStatus "U5D1.CL14" )
				)
				( pin "vss(432)"
					( attribute "PN" "CL8"
						( Origin gPackager )
					)
					( objectStatus "U5D1.CL8" )
				)
				( pin "vss(433)"
					( attribute "PN" "CK85"
						( Origin gPackager )
					)
					( objectStatus "U5D1.CK85" )
				)
				( pin "vss(434)"
					( attribute "PN" "CK83"
						( Origin gPackager )
					)
					( objectStatus "U5D1.CK83" )
				)
				( pin "vss(435)"
					( attribute "PN" "CK75"
						( Origin gPackager )
					)
					( objectStatus "U5D1.CK75" )
				)
				( pin "vss(436)"
					( attribute "PN" "CK73"
						( Origin gPackager )
					)
					( objectStatus "U5D1.CK73" )
				)
				( pin "vss(437)"
					( attribute "PN" "CK71"
						( Origin gPackager )
					)
					( objectStatus "U5D1.CK71" )
				)
				( pin "vss(438)"
					( attribute "PN" "CK69"
						( Origin gPackager )
					)
					( objectStatus "U5D1.CK69" )
				)
				( pin "vss(439)"
					( attribute "PN" "CK67"
						( Origin gPackager )
					)
					( objectStatus "U5D1.CK67" )
				)
				( pin "vss(440)"
					( attribute "PN" "CK65"
						( Origin gPackager )
					)
					( objectStatus "U5D1.CK65" )
				)
				( pin "vss(441)"
					( attribute "PN" "CK63"
						( Origin gPackager )
					)
					( objectStatus "U5D1.CK63" )
				)
				( pin "vss(442)"
					( attribute "PN" "CK27"
						( Origin gPackager )
					)
					( objectStatus "U5D1.CK27" )
				)
				( pin "vss(443)"
					( attribute "PN" "CK21"
						( Origin gPackager )
					)
					( objectStatus "U5D1.CK21" )
				)
				( pin "vss(444)"
					( attribute "PN" "CK15"
						( Origin gPackager )
					)
					( objectStatus "U5D1.CK15" )
				)
				( pin "vss(445)"
					( attribute "PN" "CK11"
						( Origin gPackager )
					)
					( objectStatus "U5D1.CK11" )
				)
				( pin "vss(446)"
					( attribute "PN" "CJ86"
						( Origin gPackager )
					)
					( objectStatus "U5D1.CJ86" )
				)
				( pin "vss(447)"
					( attribute "PN" "CJ84"
						( Origin gPackager )
					)
					( objectStatus "U5D1.CJ84" )
				)
				( pin "vss(448)"
					( attribute "PN" "CJ82"
						( Origin gPackager )
					)
					( objectStatus "U5D1.CJ82" )
				)
				( pin "vss(449)"
					( attribute "PN" "CJ78"
						( Origin gPackager )
					)
					( objectStatus "U5D1.CJ78" )
				)
				( pin "vss(450)"
					( attribute "PN" "CJ76"
						( Origin gPackager )
					)
					( objectStatus "U5D1.CJ76" )
				)
				( pin "vss(451)"
					( attribute "PN" "CJ74"
						( Origin gPackager )
					)
					( objectStatus "U5D1.CJ74" )
				)
				( pin "vss(452)"
					( attribute "PN" "CJ62"
						( Origin gPackager )
					)
					( objectStatus "U5D1.CJ62" )
				)
				( pin "vss(453)"
					( attribute "PN" "P47"
						( Origin gPackager )
					)
					( objectStatus "U5D1.P47" )
				)
			)
			( gate "@baseboard_fab2_lib.baseboard_fab2(sch_1):page41_i285"
				( attribute "CDS_LIB" "chpset_lib"
					( Origin gPackager )
				)
				( attribute "CDS_LOCATION" "U5D1"
					( Origin gPackager )
				)
				( attribute "CDS_SEC" "29"
					( Origin gPackager )
				)
				( attribute "LOCATION" "U5D1"
					( Origin gFrontEnd )
				)
				( attribute "MATERIAL" "IC"
					( Origin gFrontEnd )
				)
				( attribute "PACK_TYPE" "BGA1"
					( Origin gFrontEnd )
				)
				( attribute "PART_NUMBER" "TBD"
					( Origin gFrontEnd )
				)
				( attribute "PHYS_PAGE" "41"
					( Origin gFrontEnd )
				)
				( attribute "ROOM" "CPU0"
					( Origin gFrontEnd )
				)
				( attribute "ROT" "0"
					( Origin gFrontEnd )
				)
				( attribute "SEC" "29"
					( Origin gFrontEnd )
				)
				( attribute "SEC_TYPE" "BGA1"
					( Origin gFrontEnd )
				)
				( attribute "VER" "29"
					( Origin gFrontEnd )
				)
				( attribute "XY" "(-1850,2600)"
					( Origin gFrontEnd )
				)
				( attribute "CHIPS_PART_NAME" "SKX_EXT_B"
					( Origin gPackager )
				)
				( attribute "CDS_PART_NAME" "SKX_EXT_B_BGA1-IC,TBD"
					( Origin gPackager )
				)
				( objectStatus "U5D1" )
				( pin "vss(134)"
					( attribute "PN" "DN72"
						( Origin gPackager )
					)
					( objectStatus "U5D1.DN72" )
				)
				( pin "vss(135)"
					( attribute "PN" "DN68"
						( Origin gPackager )
					)
					( objectStatus "U5D1.DN68" )
				)
				( pin "vss(136)"
					( attribute "PN" "DN38"
						( Origin gPackager )
					)
					( objectStatus "U5D1.DN38" )
				)
				( pin "vss(137)"
					( attribute "PN" "DN32"
						( Origin gPackager )
					)
					( objectStatus "U5D1.DN32" )
				)
				( pin "vss(138)"
					( attribute "PN" "DN26"
						( Origin gPackager )
					)
					( objectStatus "U5D1.DN26" )
				)
				( pin "vss(139)"
					( attribute "PN" "DN22"
						( Origin gPackager )
					)
					( objectStatus "U5D1.DN22" )
				)
				( pin "vss(140)"
					( attribute "PN" "DN12"
						( Origin gPackager )
					)
					( objectStatus "U5D1.DN12" )
				)
				( pin "vss(141)"
					( attribute "PN" "BH17"
						( Origin gPackager )
					)
					( objectStatus "U5D1.BH17" )
				)
				( pin "vss(142)"
					( attribute "PN" "DN2"
						( Origin gPackager )
					)
					( objectStatus "U5D1.DN2" )
				)
				( pin "vss(143)"
					( attribute "PN" "DM83"
						( Origin gPackager )
					)
					( objectStatus "U5D1.DM83" )
				)
				( pin "vss(144)"
					( attribute "PN" "DM77"
						( Origin gPackager )
					)
					( objectStatus "U5D1.DM77" )
				)
				( pin "vss(145)"
					( attribute "PN" "DM73"
						( Origin gPackager )
					)
					( objectStatus "U5D1.DM73" )
				)
				( pin "vss(146)"
					( attribute "PN" "DM65"
						( Origin gPackager )
					)
					( objectStatus "U5D1.DM65" )
				)
				( pin "vss(147)"
					( attribute "PN" "DM39"
						( Origin gPackager )
					)
					( objectStatus "U5D1.DM39" )
				)
				( pin "vss(148)"
					( attribute "PN" "DM37"
						( Origin gPackager )
					)
					( objectStatus "U5D1.DM37" )
				)
				( pin "vss(149)"
					( attribute "PN" "DM33"
						( Origin gPackager )
					)
					( objectStatus "U5D1.DM33" )
				)
				( pin "vss(150)"
					( attribute "PN" "DM31"
						( Origin gPackager )
					)
					( objectStatus "U5D1.DM31" )
				)
				( pin "vss(151)"
					( attribute "PN" "DM27"
						( Origin gPackager )
					)
					( objectStatus "U5D1.DM27" )
				)
				( pin "vss(152)"
					( attribute "PN" "DM25"
						( Origin gPackager )
					)
					( objectStatus "U5D1.DM25" )
				)
				( pin "vss(153)"
					( attribute "PN" "H45"
						( Origin gPackager )
					)
					( objectStatus "U5D1.H45" )
				)
				( pin "vss(154)"
					( attribute "PN" "DM15"
						( Origin gPackager )
					)
					( objectStatus "U5D1.DM15" )
				)
				( pin "vss(155)"
					( attribute "PN" "DL80"
						( Origin gPackager )
					)
					( objectStatus "U5D1.DL80" )
				)
				( pin "vss(156)"
					( attribute "PN" "DL78"
						( Origin gPackager )
					)
					( objectStatus "U5D1.DL78" )
				)
				( pin "vss(157)"
					( attribute "PN" "DL76"
						( Origin gPackager )
					)
					( objectStatus "U5D1.DL76" )
				)
				( pin "vss(158)"
					( attribute "PN" "DL74"
						( Origin gPackager )
					)
					( objectStatus "U5D1.DL74" )
				)
				( pin "vss(159)"
					( attribute "PN" "DL70"
						( Origin gPackager )
					)
					( objectStatus "U5D1.DL70" )
				)
				( pin "vss(160)"
					( attribute "PN" "DL68"
						( Origin gPackager )
					)
					( objectStatus "U5D1.DL68" )
				)
				( pin "vss(161)"
					( attribute "PN" "DL40"
						( Origin gPackager )
					)
					( objectStatus "U5D1.DL40" )
				)
				( pin "vss(162)"
					( attribute "PN" "DL36"
						( Origin gPackager )
					)
					( objectStatus "U5D1.DL36" )
				)
				( pin "vss(163)"
					( attribute "PN" "DL34"
						( Origin gPackager )
					)
					( objectStatus "U5D1.DL34" )
				)
				( pin "vss(164)"
					( attribute "PN" "DL30"
						( Origin gPackager )
					)
					( objectStatus "U5D1.DL30" )
				)
				( pin "vss(165)"
					( attribute "PN" "DL28"
						( Origin gPackager )
					)
					( objectStatus "U5D1.DL28" )
				)
				( pin "vss(166)"
					( attribute "PN" "DL24"
						( Origin gPackager )
					)
					( objectStatus "U5D1.DL24" )
				)
				( pin "vss(167)"
					( attribute "PN" "DL22"
						( Origin gPackager )
					)
					( objectStatus "U5D1.DL22" )
				)
				( pin "vss(168)"
					( attribute "PN" "DL4"
						( Origin gPackager )
					)
					( objectStatus "U5D1.DL4" )
				)
				( pin "vss(169)"
					( attribute "PN" "DL18"
						( Origin gPackager )
					)
					( objectStatus "U5D1.DL18" )
				)
				( pin "vss(170)"
					( attribute "PN" "DL16"
						( Origin gPackager )
					)
					( objectStatus "U5D1.DL16" )
				)
				( pin "vss(171)"
					( attribute "PN" "DK85"
						( Origin gPackager )
					)
					( objectStatus "U5D1.DK85" )
				)
				( pin "vss(172)"
					( attribute "PN" "DK83"
						( Origin gPackager )
					)
					( objectStatus "U5D1.DK83" )
				)
				( pin "vss(173)"
					( attribute "PN" "DK77"
						( Origin gPackager )
					)
					( objectStatus "U5D1.DK77" )
				)
				( pin "vss(174)"
					( attribute "PN" "DK75"
						( Origin gPackager )
					)
					( objectStatus "U5D1.DK75" )
				)
				( pin "vss(175)"
					( attribute "PN" "DK73"
						( Origin gPackager )
					)
					( objectStatus "U5D1.DK73" )
				)
				( pin "vss(176)"
					( attribute "PN" "DK41"
						( Origin gPackager )
					)
					( objectStatus "U5D1.DK41" )
				)
				( pin "vss(177)"
					( attribute "PN" "DK39"
						( Origin gPackager )
					)
					( objectStatus "U5D1.DK39" )
				)
				( pin "vss(178)"
					( attribute "PN" "DK35"
						( Origin gPackager )
					)
					( objectStatus "U5D1.DK35" )
				)
				( pin "vss(179)"
					( attribute "PN" "DK29"
						( Origin gPackager )
					)
					( objectStatus "U5D1.DK29" )
				)
				( pin "vss(180)"
					( attribute "PN" "DK23"
						( Origin gPackager )
					)
					( objectStatus "U5D1.DK23" )
				)
				( pin "vss(181)"
					( attribute "PN" "DK7"
						( Origin gPackager )
					)
					( objectStatus "U5D1.DK7" )
				)
				( pin "vss(182)"
					( attribute "PN" "DJ84"
						( Origin gPackager )
					)
					( objectStatus "U5D1.DJ84" )
				)
				( pin "vss(183)"
					( attribute "PN" "DJ82"
						( Origin gPackager )
					)
					( objectStatus "U5D1.DJ82" )
				)
				( pin "vss(184)"
					( attribute "PN" "DJ78"
						( Origin gPackager )
					)
					( objectStatus "U5D1.DJ78" )
				)
				( pin "vss(185)"
					( attribute "PN" "DJ74"
						( Origin gPackager )
					)
					( objectStatus "U5D1.DJ74" )
				)
				( pin "vss(186)"
					( attribute "PN" "DJ68"
						( Origin gPackager )
					)
					( objectStatus "U5D1.DJ68" )
				)
				( pin "vss(187)"
					( attribute "PN" "DJ42"
						( Origin gPackager )
					)
					( objectStatus "U5D1.DJ42" )
				)
				( pin "vss(188)"
					( attribute "PN" "DJ38"
						( Origin gPackager )
					)
					( objectStatus "U5D1.DJ38" )
				)
				( pin "vss(189)"
					( attribute "PN" "DJ22"
						( Origin gPackager )
					)
					( objectStatus "U5D1.DJ22" )
				)
				( pin "vss(190)"
					( attribute "PN" "H47"
						( Origin gPackager )
					)
					( objectStatus "U5D1.H47" )
				)
				( pin "vss(191)"
					( attribute "PN" "DJ10"
						( Origin gPackager )
					)
					( objectStatus "U5D1.DJ10" )
				)
				( pin "vss(192)"
					( attribute "PN" "DJ2"
						( Origin gPackager )
					)
					( objectStatus "U5D1.DJ2" )
				)
				( pin "vss(193)"
					( attribute "PN" "DH83"
						( Origin gPackager )
					)
					( objectStatus "U5D1.DH83" )
				)
				( pin "vss(194)"
					( attribute "PN" "DH81"
						( Origin gPackager )
					)
					( objectStatus "U5D1.DH81" )
				)
				( pin "vss(195)"
					( attribute "PN" "DH79"
						( Origin gPackager )
					)
					( objectStatus "U5D1.DH79" )
				)
				( pin "vss(196)"
					( attribute "PN" "DH73"
						( Origin gPackager )
					)
					( objectStatus "U5D1.DH73" )
				)
				( pin "vss(197)"
					( attribute "PN" "DH71"
						( Origin gPackager )
					)
					( objectStatus "U5D1.DH71" )
				)
				( pin "vss(198)"
					( attribute "PN" "DH67"
						( Origin gPackager )
					)
					( objectStatus "U5D1.DH67" )
				)
				( pin "vss(199)"
					( attribute "PN" "DH41"
						( Origin gPackager )
					)
					( objectStatus "U5D1.DH41" )
				)
				( pin "vss(200)"
					( attribute "PN" "DH37"
						( Origin gPackager )
					)
					( objectStatus "U5D1.DH37" )
				)
				( pin "vss(201)"
					( attribute "PN" "DH35"
						( Origin gPackager )
					)
					( objectStatus "U5D1.DH35" )
				)
				( pin "vss(202)"
					( attribute "PN" "DH33"
						( Origin gPackager )
					)
					( objectStatus "U5D1.DH33" )
				)
				( pin "vss(203)"
					( attribute "PN" "DH31"
						( Origin gPackager )
					)
					( objectStatus "U5D1.DH31" )
				)
				( pin "vss(204)"
					( attribute "PN" "DH29"
						( Origin gPackager )
					)
					( objectStatus "U5D1.DH29" )
				)
				( pin "vss(205)"
					( attribute "PN" "DH27"
						( Origin gPackager )
					)
					( objectStatus "U5D1.DH27" )
				)
				( pin "vss(206)"
					( attribute "PN" "DH25"
						( Origin gPackager )
					)
					( objectStatus "U5D1.DH25" )
				)
				( pin "vss(207)"
					( attribute "PN" "DH23"
						( Origin gPackager )
					)
					( objectStatus "U5D1.DH23" )
				)
				( pin "vss(208)"
					( attribute "PN" "DH15"
						( Origin gPackager )
					)
					( objectStatus "U5D1.DH15" )
				)
				( pin "vss(209)"
					( attribute "PN" "DH13"
						( Origin gPackager )
					)
					( objectStatus "U5D1.DH13" )
				)
				( pin "vss(210)"
					( attribute "PN" "DG82"
						( Origin gPackager )
					)
					( objectStatus "U5D1.DG82" )
				)
				( pin "vss(211)"
					( attribute "PN" "DG80"
						( Origin gPackager )
					)
					( objectStatus "U5D1.DG80" )
				)
				( pin "vss(212)"
					( attribute "PN" "DG78"
						( Origin gPackager )
					)
					( objectStatus "U5D1.DG78" )
				)
				( pin "vss(213)"
					( attribute "PN" "DG76"
						( Origin gPackager )
					)
					( objectStatus "U5D1.DG76" )
				)
				( pin "vss(214)"
					( attribute "PN" "DG68"
						( Origin gPackager )
					)
					( objectStatus "U5D1.DG68" )
				)
				( pin "vss(215)"
					( attribute "PN" "DG66"
						( Origin gPackager )
					)
					( objectStatus "U5D1.DG66" )
				)
				( pin "vss(216)"
					( attribute "PN" "DG24"
						( Origin gPackager )
					)
					( objectStatus "U5D1.DG24" )
				)
				( pin "vss(217)"
					( attribute "PN" "DG16"
						( Origin gPackager )
					)
					( objectStatus "U5D1.DG16" )
				)
				( pin "vss(218)"
					( attribute "PN" "DG14"
						( Origin gPackager )
					)
					( objectStatus "U5D1.DG14" )
				)
				( pin "vss(219)"
					( attribute "PN" "H49"
						( Origin gPackager )
					)
					( objectStatus "U5D1.H49" )
				)
				( pin "vss(220)"
					( attribute "PN" "DG2"
						( Origin gPackager )
					)
					( objectStatus "U5D1.DG2" )
				)
				( pin "vss(221)"
					( attribute "PN" "DF85"
						( Origin gPackager )
					)
					( objectStatus "U5D1.DF85" )
				)
				( pin "vss(222)"
					( attribute "PN" "DF83"
						( Origin gPackager )
					)
					( objectStatus "U5D1.DF83" )
				)
				( pin "vss(223)"
					( attribute "PN" "DF79"
						( Origin gPackager )
					)
					( objectStatus "U5D1.DF79" )
				)
				( pin "vss(224)"
					( attribute "PN" "DF73"
						( Origin gPackager )
					)
					( objectStatus "U5D1.DF73" )
				)
				( pin "vss(225)"
					( attribute "PN" "DF69"
						( Origin gPackager )
					)
					( objectStatus "U5D1.DF69" )
				)
				( pin "vss(226)"
					( attribute "PN" "DF65"
						( Origin gPackager )
					)
					( objectStatus "U5D1.DF65" )
				)
				( pin "vss(227)"
					( attribute "PN" "DF41"
						( Origin gPackager )
					)
					( objectStatus "U5D1.DF41" )
				)
				( pin "vss(228)"
					( attribute "PN" "DF39"
						( Origin gPackager )
					)
					( objectStatus "U5D1.DF39" )
				)
				( pin "vss(229)"
					( attribute "PN" "DF37"
						( Origin gPackager )
					)
					( objectStatus "U5D1.DF37" )
				)
				( pin "vss(230)"
					( attribute "PN" "DF35"
						( Origin gPackager )
					)
					( objectStatus "U5D1.DF35" )
				)
				( pin "vss(231)"
					( attribute "PN" "DF29"
						( Origin gPackager )
					)
					( objectStatus "U5D1.DF29" )
				)
				( pin "vss(232)"
					( attribute "PN" "DF19"
						( Origin gPackager )
					)
					( objectStatus "U5D1.DF19" )
				)
				( pin "vss(233)"
					( attribute "PN" "H51"
						( Origin gPackager )
					)
					( objectStatus "U5D1.H51" )
				)
				( pin "vss(234)"
					( attribute "PN" "DF7"
						( Origin gPackager )
					)
					( objectStatus "U5D1.DF7" )
				)
				( pin "vss(235)"
					( attribute "PN" "DF5"
						( Origin gPackager )
					)
					( objectStatus "U5D1.DF5" )
				)
				( pin "vss(236)"
					( attribute "PN" "DE78"
						( Origin gPackager )
					)
					( objectStatus "U5D1.DE78" )
				)
				( pin "vss(237)"
					( attribute "PN" "DE72"
						( Origin gPackager )
					)
					( objectStatus "U5D1.DE72" )
				)
				( pin "vss(238)"
					( attribute "PN" "DE70"
						( Origin gPackager )
					)
					( objectStatus "U5D1.DE70" )
				)
				( pin "vss(239)"
					( attribute "PN" "DE64"
						( Origin gPackager )
					)
					( objectStatus "U5D1.DE64" )
				)
				( pin "vss(240)"
					( attribute "PN" "DE36"
						( Origin gPackager )
					)
					( objectStatus "U5D1.DE36" )
				)
				( pin "vss(241)"
					( attribute "PN" "DE34"
						( Origin gPackager )
					)
					( objectStatus "U5D1.DE34" )
				)
				( pin "vss(242)"
					( attribute "PN" "DE30"
						( Origin gPackager )
					)
					( objectStatus "U5D1.DE30" )
				)
				( pin "vss(243)"
					( attribute "PN" "DE28"
						( Origin gPackager )
					)
					( objectStatus "U5D1.DE28" )
				)
				( pin "vss(244)"
					( attribute "PN" "DE24"
						( Origin gPackager )
					)
					( objectStatus "U5D1.DE24" )
				)
				( pin "vss(245)"
					( attribute "PN" "DE20"
						( Origin gPackager )
					)
					( objectStatus "U5D1.DE20" )
				)
				( pin "vss(246)"
					( attribute "PN" "DE18"
						( Origin gPackager )
					)
					( objectStatus "U5D1.DE18" )
				)
				( pin "vss(247)"
					( attribute "PN" "DE8"
						( Origin gPackager )
					)
					( objectStatus "U5D1.DE8" )
				)
				( pin "vss(248)"
					( attribute "PN" "DE6"
						( Origin gPackager )
					)
					( objectStatus "U5D1.DE6" )
				)
				( pin "vss(249)"
					( attribute "PN" "DD83"
						( Origin gPackager )
					)
					( objectStatus "U5D1.DD83" )
				)
				( pin "vss(250)"
					( attribute "PN" "DD81"
						( Origin gPackager )
					)
					( objectStatus "U5D1.DD81" )
				)
				( pin "vss(251)"
					( attribute "PN" "DD75"
						( Origin gPackager )
					)
					( objectStatus "U5D1.DD75" )
				)
				( pin "vss(252)"
					( attribute "PN" "DD73"
						( Origin gPackager )
					)
					( objectStatus "U5D1.DD73" )
				)
				( pin "vss(253)"
					( attribute "PN" "DD71"
						( Origin gPackager )
					)
					( objectStatus "U5D1.DD71" )
				)
				( pin "vss(254)"
					( attribute "PN" "DD37"
						( Origin gPackager )
					)
					( objectStatus "U5D1.DD37" )
				)
				( pin "vss(255)"
					( attribute "PN" "DD33"
						( Origin gPackager )
					)
					( objectStatus "U5D1.DD33" )
				)
				( pin "vss(256)"
					( attribute "PN" "DD31"
						( Origin gPackager )
					)
					( objectStatus "U5D1.DD31" )
				)
				( pin "vss(257)"
					( attribute "PN" "DD27"
						( Origin gPackager )
					)
					( objectStatus "U5D1.DD27" )
				)
				( pin "vss(258)"
					( attribute "PN" "DD23"
						( Origin gPackager )
					)
					( objectStatus "U5D1.DD23" )
				)
				( pin "vss(259)"
					( attribute "PN" "DD11"
						( Origin gPackager )
					)
					( objectStatus "U5D1.DD11" )
				)
				( pin "vss(260)"
					( attribute "PN" "DC86"
						( Origin gPackager )
					)
					( objectStatus "U5D1.DC86" )
				)
				( pin "vss(261)"
					( attribute "PN" "DC84"
						( Origin gPackager )
					)
					( objectStatus "U5D1.DC84" )
				)
				( pin "vss(262)"
					( attribute "PN" "DC78"
						( Origin gPackager )
					)
					( objectStatus "U5D1.DC78" )
				)
				( pin "vss(263)"
					( attribute "PN" "DC70"
						( Origin gPackager )
					)
					( objectStatus "U5D1.DC70" )
				)
				( pin "vss(264)"
					( attribute "PN" "DC68"
						( Origin gPackager )
					)
					( objectStatus "U5D1.DC68" )
				)
				( pin "vss(265)"
					( attribute "PN" "DC66"
						( Origin gPackager )
					)
					( objectStatus "U5D1.DC66" )
				)
				( pin "vss(266)"
					( attribute "PN" "DC64"
						( Origin gPackager )
					)
					( objectStatus "U5D1.DC64" )
				)
				( pin "vss(267)"
					( attribute "PN" "DC42"
						( Origin gPackager )
					)
					( objectStatus "U5D1.DC42" )
				)
				( pin "vss(268)"
					( attribute "PN" "DC38"
						( Origin gPackager )
					)
					( objectStatus "U5D1.DC38" )
				)
				( pin "vss(269)"
					( attribute "PN" "DC32"
						( Origin gPackager )
					)
					( objectStatus "U5D1.DC32" )
				)
				( pin "vss(270)"
					( attribute "PN" "DC26"
						( Origin gPackager )
					)
					( objectStatus "U5D1.DC26" )
				)
				( pin "vss(271)"
					( attribute "PN" "DC24"
						( Origin gPackager )
					)
					( objectStatus "U5D1.DC24" )
				)
				( pin "vss(272)"
					( attribute "PN" "DC14"
						( Origin gPackager )
					)
					( objectStatus "U5D1.DC14" )
				)
				( pin "vss(273)"
					( attribute "PN" "DB85"
						( Origin gPackager )
					)
					( objectStatus "U5D1.DB85" )
				)
				( pin "vss(274)"
					( attribute "PN" "DB83"
						( Origin gPackager )
					)
					( objectStatus "U5D1.DB83" )
				)
				( pin "vss(275)"
					( attribute "PN" "DB77"
						( Origin gPackager )
					)
					( objectStatus "U5D1.DB77" )
				)
				( pin "vss(276)"
					( attribute "PN" "DB73"
						( Origin gPackager )
					)
					( objectStatus "U5D1.DB73" )
				)
				( pin "vss(277)"
					( attribute "PN" "DB49"
						( Origin gPackager )
					)
					( objectStatus "U5D1.DB49" )
				)
				( pin "vss(278)"
					( attribute "PN" "DB47"
						( Origin gPackager )
					)
					( objectStatus "U5D1.DB47" )
				)
				( pin "vss(279)"
					( attribute "PN" "DB41"
						( Origin gPackager )
					)
					( objectStatus "U5D1.DB41" )
				)
				( pin "vss(280)"
					( attribute "PN" "DB39"
						( Origin gPackager )
					)
					( objectStatus "U5D1.DB39" )
				)
				( pin "vss(281)"
					( attribute "PN" "DB25"
						( Origin gPackager )
					)
					( objectStatus "U5D1.DB25" )
				)
				( pin "vss(282)"
					( attribute "PN" "DB23"
						( Origin gPackager )
					)
					( objectStatus "U5D1.DB23" )
				)
				( pin "vss(283)"
					( attribute "PN" "DB17"
						( Origin gPackager )
					)
					( objectStatus "U5D1.DB17" )
				)
				( pin "vss(284)"
					( attribute "PN" "DB13"
						( Origin gPackager )
					)
					( objectStatus "U5D1.DB13" )
				)
				( pin "vss(285)"
					( attribute "PN" "DB3"
						( Origin gPackager )
					)
					( objectStatus "U5D1.DB3" )
				)
				( pin "vss(286)"
					( attribute "PN" "DA80"
						( Origin gPackager )
					)
					( objectStatus "U5D1.DA80" )
				)
				( pin "vss(287)"
					( attribute "PN" "DA78"
						( Origin gPackager )
					)
					( objectStatus "U5D1.DA78" )
				)
				( pin "vss(288)"
					( attribute "PN" "DA76"
						( Origin gPackager )
					)
					( objectStatus "U5D1.DA76" )
				)
				( pin "vss(289)"
					( attribute "PN" "DA74"
						( Origin gPackager )
					)
					( objectStatus "U5D1.DA74" )
				)
				( pin "vss(290)"
					( attribute "PN" "DA70"
						( Origin gPackager )
					)
					( objectStatus "U5D1.DA70" )
				)
				( pin "vss(291)"
					( attribute "PN" "DA64"
						( Origin gPackager )
					)
					( objectStatus "U5D1.DA64" )
				)
				( pin "vss(292)"
					( attribute "PN" "DA50"
						( Origin gPackager )
					)
					( objectStatus "U5D1.DA50" )
				)
				( pin "vss(293)"
					( attribute "PN" "DA48"
						( Origin gPackager )
					)
					( objectStatus "U5D1.DA48" )
				)
			)
			( gate "@baseboard_fab2_lib.baseboard_fab2(sch_1):page41_i286"
				( attribute "CDS_LIB" "chpset_lib"
					( Origin gPackager )
				)
				( attribute "CDS_LOCATION" "U5D1"
					( Origin gPackager )
				)
				( attribute "CDS_SEC" "30"
					( Origin gPackager )
				)
				( attribute "LOCATION" "U5D1"
					( Origin gFrontEnd )
				)
				( attribute "MATERIAL" "IC"
					( Origin gFrontEnd )
				)
				( attribute "PACK_TYPE" "BGA1"
					( Origin gFrontEnd )
				)
				( attribute "PART_NUMBER" "TBD"
					( Origin gFrontEnd )
				)
				( attribute "PHYS_PAGE" "41"
					( Origin gFrontEnd )
				)
				( attribute "ROOM" "CPU0"
					( Origin gFrontEnd )
				)
				( attribute "ROT" "0"
					( Origin gFrontEnd )
				)
				( attribute "SEC" "30"
					( Origin gFrontEnd )
				)
				( attribute "SEC_TYPE" "BGA1"
					( Origin gFrontEnd )
				)
				( attribute "VER" "30"
					( Origin gFrontEnd )
				)
				( attribute "XY" "(-175,2650)"
					( Origin gFrontEnd )
				)
				( attribute "CHIPS_PART_NAME" "SKX_EXT_B"
					( Origin gPackager )
				)
				( attribute "CDS_PART_NAME" "SKX_EXT_B_BGA1-IC,TBD"
					( Origin gPackager )
				)
				( objectStatus "U5D1" )
				( pin "vss(0)"
					( attribute "PN" "EF79"
						( Origin gPackager )
					)
					( objectStatus "U5D1.EF79" )
				)
				( pin "vss(1)"
					( attribute "PN" "EF75"
						( Origin gPackager )
					)
					( objectStatus "U5D1.EF75" )
				)
				( pin "vss(2)"
					( attribute "PN" "EF71"
						( Origin gPackager )
					)
					( objectStatus "U5D1.EF71" )
				)
				( pin "vss(3)"
					( attribute "PN" "EE78"
						( Origin gPackager )
					)
					( objectStatus "U5D1.EE78" )
				)
				( pin "vss(4)"
					( attribute "PN" "EE76"
						( Origin gPackager )
					)
					( objectStatus "U5D1.EE76" )
				)
				( pin "vss(5)"
					( attribute "PN" "EE70"
						( Origin gPackager )
					)
					( objectStatus "U5D1.EE70" )
				)
				( pin "vss(6)"
					( attribute "PN" "EE36"
						( Origin gPackager )
					)
					( objectStatus "U5D1.EE36" )
				)
				( pin "vss(7)"
					( attribute "PN" "EE34"
						( Origin gPackager )
					)
					( objectStatus "U5D1.EE34" )
				)
				( pin "vss(8)"
					( attribute "PN" "EE30"
						( Origin gPackager )
					)
					( objectStatus "U5D1.EE30" )
				)
				( pin "vss(9)"
					( attribute "PN" "EE28"
						( Origin gPackager )
					)
					( objectStatus "U5D1.EE28" )
				)
				( pin "vss(10)"
					( attribute "PN" "EE24"
						( Origin gPackager )
					)
					( objectStatus "U5D1.EE24" )
				)
				( pin "vss(11)"
					( attribute "PN" "ED77"
						( Origin gPackager )
					)
					( objectStatus "U5D1.ED77" )
				)
				( pin "vss(12)"
					( attribute "PN" "ED35"
						( Origin gPackager )
					)
					( objectStatus "U5D1.ED35" )
				)
				( pin "vss(13)"
					( attribute "PN" "ED29"
						( Origin gPackager )
					)
					( objectStatus "U5D1.ED29" )
				)
				( pin "vss(14)"
					( attribute "PN" "ED23"
						( Origin gPackager )
					)
					( objectStatus "U5D1.ED23" )
				)
				( pin "vss(15)"
					( attribute "PN" "ED15"
						( Origin gPackager )
					)
					( objectStatus "U5D1.ED15" )
				)
				( pin "vss(16)"
					( attribute "PN" "ED11"
						( Origin gPackager )
					)
					( objectStatus "U5D1.ED11" )
				)
				( pin "vss(17)"
					( attribute "PN" "EC76"
						( Origin gPackager )
					)
					( objectStatus "U5D1.EC76" )
				)
				( pin "vss(18)"
					( attribute "PN" "EC74"
						( Origin gPackager )
					)
					( objectStatus "U5D1.EC74" )
				)
				( pin "vss(19)"
					( attribute "PN" "EC72"
						( Origin gPackager )
					)
					( objectStatus "U5D1.EC72" )
				)
				( pin "vss(20)"
					( attribute "PN" "EC70"
						( Origin gPackager )
					)
					( objectStatus "U5D1.EC70" )
				)
				( pin "vss(21)"
					( attribute "PN" "EC10"
						( Origin gPackager )
					)
					( objectStatus "U5D1.EC10" )
				)
				( pin "vss(22)"
					( attribute "PN" "EB69"
						( Origin gPackager )
					)
					( objectStatus "U5D1.EB69" )
				)
				( pin "vss(23)"
					( attribute "PN" "EB65"
						( Origin gPackager )
					)
					( objectStatus "U5D1.EB65" )
				)
				( pin "vss(24)"
					( attribute "PN" "EB41"
						( Origin gPackager )
					)
					( objectStatus "U5D1.EB41" )
				)
				( pin "vss(25)"
					( attribute "PN" "EB39"
						( Origin gPackager )
					)
					( objectStatus "U5D1.EB39" )
				)
				( pin "vss(26)"
					( attribute "PN" "EB37"
						( Origin gPackager )
					)
					( objectStatus "U5D1.EB37" )
				)
				( pin "vss(27)"
					( attribute "PN" "EB35"
						( Origin gPackager )
					)
					( objectStatus "U5D1.EB35" )
				)
				( pin "vss(28)"
					( attribute "PN" "EB33"
						( Origin gPackager )
					)
					( objectStatus "U5D1.EB33" )
				)
				( pin "vss(29)"
					( attribute "PN" "EB31"
						( Origin gPackager )
					)
					( objectStatus "U5D1.EB31" )
				)
				( pin "vss(30)"
					( attribute "PN" "EB29"
						( Origin gPackager )
					)
					( objectStatus "U5D1.EB29" )
				)
				( pin "vss(31)"
					( attribute "PN" "EB27"
						( Origin gPackager )
					)
					( objectStatus "U5D1.EB27" )
				)
				( pin "vss(32)"
					( attribute "PN" "EB25"
						( Origin gPackager )
					)
					( objectStatus "U5D1.EB25" )
				)
				( pin "vss(33)"
					( attribute "PN" "EB23"
						( Origin gPackager )
					)
					( objectStatus "U5D1.EB23" )
				)
				( pin "vss(34)"
					( attribute "PN" "BR18"
						( Origin gPackager )
					)
					( objectStatus "U5D1.BR18" )
				)
				( pin "vss(35)"
					( attribute "PN" "EB13"
						( Origin gPackager )
					)
					( objectStatus "U5D1.EB13" )
				)
				( pin "vss(36)"
					( attribute "PN" "EA82"
						( Origin gPackager )
					)
					( objectStatus "U5D1.EA82" )
				)
				( pin "vss(37)"
					( attribute "PN" "EA80"
						( Origin gPackager )
					)
					( objectStatus "U5D1.EA80" )
				)
				( pin "vss(38)"
					( attribute "PN" "EA78"
						( Origin gPackager )
					)
					( objectStatus "U5D1.EA78" )
				)
				( pin "vss(39)"
					( attribute "PN" "EA76"
						( Origin gPackager )
					)
					( objectStatus "U5D1.EA76" )
				)
				( pin "vss(40)"
					( attribute "PN" "EA70"
						( Origin gPackager )
					)
					( objectStatus "U5D1.EA70" )
				)
				( pin "vss(41)"
					( attribute "PN" "EA64"
						( Origin gPackager )
					)
					( objectStatus "U5D1.EA64" )
				)
				( pin "vss(42)"
					( attribute "PN" "EA42"
						( Origin gPackager )
					)
					( objectStatus "U5D1.EA42" )
				)
				( pin "vss(43)"
					( attribute "PN" "EA22"
						( Origin gPackager )
					)
					( objectStatus "U5D1.EA22" )
				)
				( pin "vss(44)"
					( attribute "PN" "EA20"
						( Origin gPackager )
					)
					( objectStatus "U5D1.EA20" )
				)
				( pin "vss(45)"
					( attribute "PN" "EA16"
						( Origin gPackager )
					)
					( objectStatus "U5D1.EA16" )
				)
				( pin "vss(46)"
					( attribute "PN" "J16"
						( Origin gPackager )
					)
					( objectStatus "U5D1.J16" )
				)
				( pin "vss(47)"
					( attribute "PN" "EA6"
						( Origin gPackager )
					)
					( objectStatus "U5D1.EA6" )
				)
				( pin "vss(48)"
					( attribute "PN" "DY75"
						( Origin gPackager )
					)
					( objectStatus "U5D1.DY75" )
				)
				( pin "vss(49)"
					( attribute "PN" "DY71"
						( Origin gPackager )
					)
					( objectStatus "U5D1.DY71" )
				)
				( pin "vss(50)"
					( attribute "PN" "DY41"
						( Origin gPackager )
					)
					( objectStatus "U5D1.DY41" )
				)
				( pin "vss(51)"
					( attribute "PN" "DY35"
						( Origin gPackager )
					)
					( objectStatus "U5D1.DY35" )
				)
				( pin "vss(52)"
					( attribute "PN" "DY29"
						( Origin gPackager )
					)
					( objectStatus "U5D1.DY29" )
				)
				( pin "vss(53)"
					( attribute "PN" "DY23"
						( Origin gPackager )
					)
					( objectStatus "U5D1.DY23" )
				)
				( pin "vss(54)"
					( attribute "PN" "DY19"
						( Origin gPackager )
					)
					( objectStatus "U5D1.DY19" )
				)
				( pin "vss(55)"
					( attribute "PN" "DY5"
						( Origin gPackager )
					)
					( objectStatus "U5D1.DY5" )
				)
				( pin "vss(56)"
					( attribute "PN" "DW84"
						( Origin gPackager )
					)
					( objectStatus "U5D1.DW84" )
				)
				( pin "vss(57)"
					( attribute "PN" "DW82"
						( Origin gPackager )
					)
					( objectStatus "U5D1.DW82" )
				)
				( pin "vss(58)"
					( attribute "PN" "DW8"
						( Origin gPackager )
					)
					( objectStatus "U5D1.DW8" )
				)
				( pin "vss(59)"
					( attribute "PN" "DW76"
						( Origin gPackager )
					)
					( objectStatus "U5D1.DW76" )
				)
				( pin "vss(60)"
					( attribute "PN" "DW74"
						( Origin gPackager )
					)
					( objectStatus "U5D1.DW74" )
				)
				( pin "vss(61)"
					( attribute "PN" "DW72"
						( Origin gPackager )
					)
					( objectStatus "U5D1.DW72" )
				)
				( pin "vss(62)"
					( attribute "PN" "DW70"
						( Origin gPackager )
					)
					( objectStatus "U5D1.DW70" )
				)
				( pin "vss(63)"
					( attribute "PN" "DW68"
						( Origin gPackager )
					)
					( objectStatus "U5D1.DW68" )
				)
				( pin "vss(64)"
					( attribute "PN" "DW66"
						( Origin gPackager )
					)
					( objectStatus "U5D1.DW66" )
				)
				( pin "vss(65)"
					( attribute "PN" "DW64"
						( Origin gPackager )
					)
					( objectStatus "U5D1.DW64" )
				)
				( pin "vss(66)"
					( attribute "PN" "DW40"
						( Origin gPackager )
					)
					( objectStatus "U5D1.DW40" )
				)
				( pin "vss(67)"
					( attribute "PN" "DW36"
						( Origin gPackager )
					)
					( objectStatus "U5D1.DW36" )
				)
				( pin "vss(68)"
					( attribute "PN" "DW34"
						( Origin gPackager )
					)
					( objectStatus "U5D1.DW34" )
				)
				( pin "vss(69)"
					( attribute "PN" "DW30"
						( Origin gPackager )
					)
					( objectStatus "U5D1.DW30" )
				)
				( pin "vss(70)"
					( attribute "PN" "DW28"
						( Origin gPackager )
					)
					( objectStatus "U5D1.DW28" )
				)
				( pin "vss(71)"
					( attribute "PN" "DW24"
						( Origin gPackager )
					)
					( objectStatus "U5D1.DW24" )
				)
				( pin "vss(72)"
					( attribute "PN" "DW20"
						( Origin gPackager )
					)
					( objectStatus "U5D1.DW20" )
				)
				( pin "vss(73)"
					( attribute "PN" "DW12"
						( Origin gPackager )
					)
					( objectStatus "U5D1.DW12" )
				)
				( pin "vss(74)"
					( attribute "PN" "DV81"
						( Origin gPackager )
					)
					( objectStatus "U5D1.DV81" )
				)
				( pin "vss(75)"
					( attribute "PN" "DV77"
						( Origin gPackager )
					)
					( objectStatus "U5D1.DV77" )
				)
				( pin "vss(76)"
					( attribute "PN" "DV73"
						( Origin gPackager )
					)
					( objectStatus "U5D1.DV73" )
				)
				( pin "vss(77)"
					( attribute "PN" "DV39"
						( Origin gPackager )
					)
					( objectStatus "U5D1.DV39" )
				)
				( pin "vss(78)"
					( attribute "PN" "DV37"
						( Origin gPackager )
					)
					( objectStatus "U5D1.DV37" )
				)
				( pin "vss(79)"
					( attribute "PN" "DV33"
						( Origin gPackager )
					)
					( objectStatus "U5D1.DV33" )
				)
				( pin "vss(80)"
					( attribute "PN" "DV31"
						( Origin gPackager )
					)
					( objectStatus "U5D1.DV31" )
				)
				( pin "vss(81)"
					( attribute "PN" "DV27"
						( Origin gPackager )
					)
					( objectStatus "U5D1.DV27" )
				)
				( pin "vss(82)"
					( attribute "PN" "DV25"
						( Origin gPackager )
					)
					( objectStatus "U5D1.DV25" )
				)
				( pin "vss(83)"
					( attribute "PN" "DV21"
						( Origin gPackager )
					)
					( objectStatus "U5D1.DV21" )
				)
				( pin "vss(84)"
					( attribute "PN" "DU84"
						( Origin gPackager )
					)
					( objectStatus "U5D1.DU84" )
				)
				( pin "vss(85)"
					( attribute "PN" "DU82"
						( Origin gPackager )
					)
					( objectStatus "U5D1.DU82" )
				)
				( pin "vss(86)"
					( attribute "PN" "DU80"
						( Origin gPackager )
					)
					( objectStatus "U5D1.DU80" )
				)
				( pin "vss(87)"
					( attribute "PN" "DU78"
						( Origin gPackager )
					)
					( objectStatus "U5D1.DU78" )
				)
				( pin "vss(88)"
					( attribute "PN" "DU72"
						( Origin gPackager )
					)
					( objectStatus "U5D1.DU72" )
				)
				( pin "vss(89)"
					( attribute "PN" "DU70"
						( Origin gPackager )
					)
					( objectStatus "U5D1.DU70" )
				)
				( pin "vss(90)"
					( attribute "PN" "DU38"
						( Origin gPackager )
					)
					( objectStatus "U5D1.DU38" )
				)
				( pin "vss(91)"
					( attribute "PN" "DU32"
						( Origin gPackager )
					)
					( objectStatus "U5D1.DU32" )
				)
				( pin "vss(92)"
					( attribute "PN" "DU26"
						( Origin gPackager )
					)
					( objectStatus "U5D1.DU26" )
				)
				( pin "vss(93)"
					( attribute "PN" "DU22"
						( Origin gPackager )
					)
					( objectStatus "U5D1.DU22" )
				)
				( pin "vss(94)"
					( attribute "PN" "CN14"
						( Origin gPackager )
					)
					( objectStatus "U5D1.CN14" )
				)
				( pin "vss(95)"
					( attribute "PN" "DU14"
						( Origin gPackager )
					)
					( objectStatus "U5D1.DU14" )
				)
				( pin "vss(96)"
					( attribute "PN" "DU10"
						( Origin gPackager )
					)
					( objectStatus "U5D1.DU10" )
				)
				( pin "vss(97)"
					( attribute "PN" "DT85"
						( Origin gPackager )
					)
					( objectStatus "U5D1.DT85" )
				)
				( pin "vss(98)"
					( attribute "PN" "DT83"
						( Origin gPackager )
					)
					( objectStatus "U5D1.DT83" )
				)
				( pin "vss(99)"
					( attribute "PN" "DT79"
						( Origin gPackager )
					)
					( objectStatus "U5D1.DT79" )
				)
				( pin "vss(100)"
					( attribute "PN" "DT69"
						( Origin gPackager )
					)
					( objectStatus "U5D1.DT69" )
				)
				( pin "vss(101)"
					( attribute "PN" "DT65"
						( Origin gPackager )
					)
					( objectStatus "U5D1.DT65" )
				)
				( pin "vss(102)"
					( attribute "PN" "DH21"
						( Origin gPackager )
					)
					( objectStatus "U5D1.DH21" )
				)
				( pin "vss(103)"
					( attribute "PN" "DT17"
						( Origin gPackager )
					)
					( objectStatus "U5D1.DT17" )
				)
				( pin "vss(104)"
					( attribute "PN" "DT3"
						( Origin gPackager )
					)
					( objectStatus "U5D1.DT3" )
				)
				( pin "vss(105)"
					( attribute "PN" "DR78"
						( Origin gPackager )
					)
					( objectStatus "U5D1.DR78" )
				)
				( pin "vss(106)"
					( attribute "PN" "DR76"
						( Origin gPackager )
					)
					( objectStatus "U5D1.DR76" )
				)
				( pin "vss(107)"
					( attribute "PN" "DR74"
						( Origin gPackager )
					)
					( objectStatus "U5D1.DR74" )
				)
				( pin "vss(108)"
					( attribute "PN" "DR72"
						( Origin gPackager )
					)
					( objectStatus "U5D1.DR72" )
				)
				( pin "vss(109)"
					( attribute "PN" "DR70"
						( Origin gPackager )
					)
					( objectStatus "U5D1.DR70" )
				)
				( pin "vss(110)"
					( attribute "PN" "DR68"
						( Origin gPackager )
					)
					( objectStatus "U5D1.DR68" )
				)
				( pin "vss(111)"
					( attribute "PN" "DR66"
						( Origin gPackager )
					)
					( objectStatus "U5D1.DR66" )
				)
				( pin "vss(112)"
					( attribute "PN" "DR42"
						( Origin gPackager )
					)
					( objectStatus "U5D1.DR42" )
				)
				( pin "vss(113)"
					( attribute "PN" "DR40"
						( Origin gPackager )
					)
					( objectStatus "U5D1.DR40" )
				)
				( pin "vss(114)"
					( attribute "PN" "DR38"
						( Origin gPackager )
					)
					( objectStatus "U5D1.DR38" )
				)
				( pin "vss(115)"
					( attribute "PN" "DR36"
						( Origin gPackager )
					)
					( objectStatus "U5D1.DR36" )
				)
				( pin "vss(116)"
					( attribute "PN" "DR34"
						( Origin gPackager )
					)
					( objectStatus "U5D1.DR34" )
				)
				( pin "vss(117)"
					( attribute "PN" "DR32"
						( Origin gPackager )
					)
					( objectStatus "U5D1.DR32" )
				)
				( pin "vss(118)"
					( attribute "PN" "DR30"
						( Origin gPackager )
					)
					( objectStatus "U5D1.DR30" )
				)
				( pin "vss(119)"
					( attribute "PN" "DR28"
						( Origin gPackager )
					)
					( objectStatus "U5D1.DR28" )
				)
				( pin "vss(120)"
					( attribute "PN" "DR26"
						( Origin gPackager )
					)
					( objectStatus "U5D1.DR26" )
				)
				( pin "vss(121)"
					( attribute "PN" "DR24"
						( Origin gPackager )
					)
					( objectStatus "U5D1.DR24" )
				)
				( pin "vss(122)"
					( attribute "PN" "DR22"
						( Origin gPackager )
					)
					( objectStatus "U5D1.DR22" )
				)
				( pin "vss(123)"
					( attribute "PN" "DR20"
						( Origin gPackager )
					)
					( objectStatus "U5D1.DR20" )
				)
				( pin "vss(124)"
					( attribute "PN" "CL22"
						( Origin gPackager )
					)
					( objectStatus "U5D1.CL22" )
				)
				( pin "vss(125)"
					( attribute "PN" "CA20"
						( Origin gPackager )
					)
					( objectStatus "U5D1.CA20" )
				)
				( pin "vss(126)"
					( attribute "PN" "DR6"
						( Origin gPackager )
					)
					( objectStatus "U5D1.DR6" )
				)
				( pin "vss(127)"
					( attribute "PN" "BR26"
						( Origin gPackager )
					)
					( objectStatus "U5D1.BR26" )
				)
				( pin "vss(128)"
					( attribute "PN" "DP83"
						( Origin gPackager )
					)
					( objectStatus "U5D1.DP83" )
				)
				( pin "vss(129)"
					( attribute "PN" "DP81"
						( Origin gPackager )
					)
					( objectStatus "U5D1.DP81" )
				)
				( pin "vss(130)"
					( attribute "PN" "DP71"
						( Origin gPackager )
					)
					( objectStatus "U5D1.DP71" )
				)
				( pin "vss(131)"
					( attribute "PN" "DP69"
						( Origin gPackager )
					)
					( objectStatus "U5D1.DP69" )
				)
				( pin "vss(132)"
					( attribute "PN" "DP67"
						( Origin gPackager )
					)
					( objectStatus "U5D1.DP67" )
				)
				( pin "vss(133)"
					( attribute "PN" "DN78"
						( Origin gPackager )
					)
					( objectStatus "U5D1.DN78" )
				)
			)
			( gate "@baseboard_fab2_lib.baseboard_fab2(sch_1):page42_i2"
				( attribute "BOM_COST" "PROC_SOCKET"
					( Origin gFrontEnd )
				)
				( attribute "CDS_LIB" "mstr_discrete"
					( Origin gPackager )
				)
				( attribute "CDS_LOCATION" "C5P18"
					( Origin gPackager )
				)
				( attribute "CDS_SEC" "1"
					( Origin gPackager )
				)
				( attribute "LOCATION" "C5P18"
					( Origin gFrontEnd )
				)
				( attribute "MATERIAL" "X6S"
					( Origin gFrontEnd )
				)
				( attribute "PACK_TYPE" "0805"
					( Origin gFrontEnd )
				)
				( attribute "PART_NUMBER" "C95333-006"
					( Origin gFrontEnd )
				)
				( attribute "PHYS_PAGE" "42"
					( Origin gFrontEnd )
				)
				( attribute "ROOM" "PVCCIN_CPU0_DECAP_VR"
					( Origin gFrontEnd )
				)
				( attribute "ROT" "0"
					( Origin gFrontEnd )
				)
				( attribute "SEC" "1"
					( Origin gPackager )
				)
				( attribute "TOLERANCE" "20%"
					( Origin gFrontEnd )
				)
				( attribute "VALUE" "47UF"
					( Origin gFrontEnd )
				)
				( attribute "VER" "1"
					( Origin gFrontEnd )
				)
				( attribute "VOLTAGE" "4V"
					( Units "uVoltage" "V" 1.000000)
					( Origin gFrontEnd )
				)
				( attribute "XY" "(-2150,2150)"
					( Origin gFrontEnd )
				)
				( attribute "CHIPS_PART_NAME" "CAP"
					( Origin gPackager )
				)
				( attribute "CDS_PART_NAME" "CAP_0805-47UF,4V,20%,X6S,C9533A"
					( Origin gPackager )
				)
				( objectStatus "C5P18" )
				( pin "a"
					( attribute "PN" "1"
						( Origin gPackager )
					)
					( objectStatus "C5P18.1" )
				)
				( pin "b"
					( attribute "PN" "2"
						( Origin gPackager )
					)
					( objectStatus "C5P18.2" )
				)
			)
			( gate "@baseboard_fab2_lib.baseboard_fab2(sch_1):page42_i3"
				( attribute "BOM_COST" "PROC_SOCKET"
					( Origin gFrontEnd )
				)
				( attribute "CDS_LIB" "mstr_discrete"
					( Origin gPackager )
				)
				( attribute "CDS_LOCATION" "C5P28"
					( Origin gPackager )
				)
				( attribute "CDS_SEC" "1"
					( Origin gPackager )
				)
				( attribute "LOCATION" "C5P28"
					( Origin gFrontEnd )
				)
				( attribute "MATERIAL" "X6S"
					( Origin gFrontEnd )
				)
				( attribute "PACK_TYPE" "0805"
					( Origin gFrontEnd )
				)
				( attribute "PART_NUMBER" "C95333-006"
					( Origin gFrontEnd )
				)
				( attribute "PHYS_PAGE" "42"
					( Origin gFrontEnd )
				)
				( attribute "ROOM" "PVCCIN_CPU0_DECAP_VR"
					( Origin gFrontEnd )
				)
				( attribute "ROT" "0"
					( Origin gFrontEnd )
				)
				( attribute "SEC" "1"
					( Origin gPackager )
				)
				( attribute "TOLERANCE" "20%"
					( Origin gFrontEnd )
				)
				( attribute "VALUE" "47UF"
					( Origin gFrontEnd )
				)
				( attribute "VER" "1"
					( Origin gFrontEnd )
				)
				( attribute "VOLTAGE" "4V"
					( Units "uVoltage" "V" 1.000000)
					( Origin gFrontEnd )
				)
				( attribute "XY" "(-2425,2175)"
					( Origin gFrontEnd )
				)
				( attribute "CHIPS_PART_NAME" "CAP"
					( Origin gPackager )
				)
				( attribute "CDS_PART_NAME" "CAP_0805-47UF,4V,20%,X6S,C9533A"
					( Origin gPackager )
				)
				( objectStatus "C5P28" )
				( pin "a"
					( attribute "PN" "1"
						( Origin gPackager )
					)
					( objectStatus "C5P28.1" )
				)
				( pin "b"
					( attribute "PN" "2"
						( Origin gPackager )
					)
					( objectStatus "C5P28.2" )
				)
			)
			( gate "@baseboard_fab2_lib.baseboard_fab2(sch_1):page42_i4"
				( attribute "BOM_COST" "PROC_SOCKET"
					( Origin gFrontEnd )
				)
				( attribute "CDS_LIB" "mstr_discrete"
					( Origin gPackager )
				)
				( attribute "CDS_LOCATION" "C5P11"
					( Origin gPackager )
				)
				( attribute "CDS_SEC" "1"
					( Origin gPackager )
				)
				( attribute "LOCATION" "C5P11"
					( Origin gFrontEnd )
				)
				( attribute "MATERIAL" "X6S"
					( Origin gFrontEnd )
				)
				( attribute "PACK_TYPE" "0805"
					( Origin gFrontEnd )
				)
				( attribute "PART_NUMBER" "C95333-006"
					( Origin gFrontEnd )
				)
				( attribute "PHYS_PAGE" "42"
					( Origin gFrontEnd )
				)
				( attribute "ROOM" "PVCCIN_CPU0_DECAP_VR"
					( Origin gFrontEnd )
				)
				( attribute "ROT" "0"
					( Origin gFrontEnd )
				)
				( attribute "SEC" "1"
					( Origin gPackager )
				)
				( attribute "TOLERANCE" "20%"
					( Origin gFrontEnd )
				)
				( attribute "VALUE" "47UF"
					( Origin gFrontEnd )
				)
				( attribute "VER" "1"
					( Origin gFrontEnd )
				)
				( attribute "VOLTAGE" "4V"
					( Units "uVoltage" "V" 1.000000)
					( Origin gFrontEnd )
				)
				( attribute "XY" "(-2700,2175)"
					( Origin gFrontEnd )
				)
				( attribute "CHIPS_PART_NAME" "CAP"
					( Origin gPackager )
				)
				( attribute "CDS_PART_NAME" "CAP_0805-47UF,4V,20%,X6S,C9533A"
					( Origin gPackager )
				)
				( objectStatus "C5P11" )
				( pin "a"
					( attribute "PN" "1"
						( Origin gPackager )
					)
					( objectStatus "C5P11.1" )
				)
				( pin "b"
					( attribute "PN" "2"
						( Origin gPackager )
					)
					( objectStatus "C5P11.2" )
				)
			)
			( gate "@baseboard_fab2_lib.baseboard_fab2(sch_1):page42_i6"
				( attribute "BOM_COST" "PROC_SOCKET"
					( Origin gFrontEnd )
				)
				( attribute "CDS_LIB" "mstr_discrete"
					( Origin gPackager )
				)
				( attribute "CDS_LOCATION" "C5P10"
					( Origin gPackager )
				)
				( attribute "CDS_SEC" "1"
					( Origin gPackager )
				)
				( attribute "LOCATION" "C5P10"
					( Origin gFrontEnd )
				)
				( attribute "MATERIAL" "X6S"
					( Origin gFrontEnd )
				)
				( attribute "PACK_TYPE" "0805"
					( Origin gFrontEnd )
				)
				( attribute "PART_NUMBER" "C95333-006"
					( Origin gFrontEnd )
				)
				( attribute "PHYS_PAGE" "42"
					( Origin gFrontEnd )
				)
				( attribute "ROOM" "PVCCIN_CPU0_DECAP_VR"
					( Origin gFrontEnd )
				)
				( attribute "ROT" "0"
					( Origin gFrontEnd )
				)
				( attribute "SEC" "1"
					( Origin gPackager )
				)
				( attribute "TOLERANCE" "20%"
					( Origin gFrontEnd )
				)
				( attribute "VALUE" "47UF"
					( Origin gFrontEnd )
				)
				( attribute "VER" "1"
					( Origin gFrontEnd )
				)
				( attribute "VOLTAGE" "4V"
					( Units "uVoltage" "V" 1.000000)
					( Origin gFrontEnd )
				)
				( attribute "XY" "(-3000,2175)"
					( Origin gFrontEnd )
				)
				( attribute "CHIPS_PART_NAME" "CAP"
					( Origin gPackager )
				)
				( attribute "CDS_PART_NAME" "CAP_0805-47UF,4V,20%,X6S,C9533A"
					( Origin gPackager )
				)
				( objectStatus "C5P10" )
				( pin "a"
					( attribute "PN" "1"
						( Origin gPackager )
					)
					( objectStatus "C5P10.1" )
				)
				( pin "b"
					( attribute "PN" "2"
						( Origin gPackager )
					)
					( objectStatus "C5P10.2" )
				)
			)
			( gate "@baseboard_fab2_lib.baseboard_fab2(sch_1):page42_i8"
				( attribute "BOM_COST" "PROC_SOCKET"
					( Origin gFrontEnd )
				)
				( attribute "CDS_LIB" "mstr_discrete"
					( Origin gPackager )
				)
				( attribute "CDS_LOCATION" "C4P3"
					( Origin gPackager )
				)
				( attribute "CDS_SEC" "1"
					( Origin gPackager )
				)
				( attribute "LOCATION" "C4P3"
					( Origin gFrontEnd )
				)
				( attribute "MATERIAL" "X6S"
					( Origin gFrontEnd )
				)
				( attribute "PACK_TYPE" "0805"
					( Origin gFrontEnd )
				)
				( attribute "PART_NUMBER" "C95333-006"
					( Origin gFrontEnd )
				)
				( attribute "PHYS_PAGE" "42"
					( Origin gFrontEnd )
				)
				( attribute "ROOM" "PVCCIN_CPU0_DECAP_VR"
					( Origin gFrontEnd )
				)
				( attribute "ROT" "0"
					( Origin gFrontEnd )
				)
				( attribute "SEC" "1"
					( Origin gPackager )
				)
				( attribute "TOLERANCE" "20%"
					( Origin gFrontEnd )
				)
				( attribute "VALUE" "47UF"
					( Origin gFrontEnd )
				)
				( attribute "VER" "1"
					( Origin gFrontEnd )
				)
				( attribute "VOLTAGE" "4V"
					( Units "uVoltage" "V" 1.000000)
					( Origin gFrontEnd )
				)
				( attribute "XY" "(-3275,2175)"
					( Origin gFrontEnd )
				)
				( attribute "CHIPS_PART_NAME" "CAP"
					( Origin gPackager )
				)
				( attribute "CDS_PART_NAME" "CAP_0805-47UF,4V,20%,X6S,C9533A"
					( Origin gPackager )
				)
				( objectStatus "C4P3" )
				( pin "a"
					( attribute "PN" "1"
						( Origin gPackager )
					)
					( objectStatus "C4P3.1" )
				)
				( pin "b"
					( attribute "PN" "2"
						( Origin gPackager )
					)
					( objectStatus "C4P3.2" )
				)
			)
			( gate "@baseboard_fab2_lib.baseboard_fab2(sch_1):page42_i9"
				( attribute "BOM_COST" "PROC_SOCKET"
					( Origin gFrontEnd )
				)
				( attribute "CDS_LIB" "mstr_discrete"
					( Origin gPackager )
				)
				( attribute "CDS_LOCATION" "C4P7"
					( Origin gPackager )
				)
				( attribute "CDS_SEC" "1"
					( Origin gPackager )
				)
				( attribute "LOCATION" "C4P7"
					( Origin gFrontEnd )
				)
				( attribute "MATERIAL" "X6S"
					( Origin gFrontEnd )
				)
				( attribute "PACK_TYPE" "0805"
					( Origin gFrontEnd )
				)
				( attribute "PART_NUMBER" "C95333-006"
					( Origin gFrontEnd )
				)
				( attribute "PHYS_PAGE" "42"
					( Origin gFrontEnd )
				)
				( attribute "ROOM" "PVCCIN_CPU0_DECAP_VR"
					( Origin gFrontEnd )
				)
				( attribute "ROT" "0"
					( Origin gFrontEnd )
				)
				( attribute "SEC" "1"
					( Origin gPackager )
				)
				( attribute "TOLERANCE" "20%"
					( Origin gFrontEnd )
				)
				( attribute "VALUE" "47UF"
					( Origin gFrontEnd )
				)
				( attribute "VER" "1"
					( Origin gFrontEnd )
				)
				( attribute "VOLTAGE" "4V"
					( Units "uVoltage" "V" 1.000000)
					( Origin gFrontEnd )
				)
				( attribute "XY" "(-3550,2175)"
					( Origin gFrontEnd )
				)
				( attribute "CHIPS_PART_NAME" "CAP"
					( Origin gPackager )
				)
				( attribute "CDS_PART_NAME" "CAP_0805-47UF,4V,20%,X6S,C9533A"
					( Origin gPackager )
				)
				( objectStatus "C4P7" )
				( pin "a"
					( attribute "PN" "1"
						( Origin gPackager )
					)
					( objectStatus "C4P7.1" )
				)
				( pin "b"
					( attribute "PN" "2"
						( Origin gPackager )
					)
					( objectStatus "C4P7.2" )
				)
			)
			( gate "@baseboard_fab2_lib.baseboard_fab2(sch_1):page42_i10"
				( attribute "BOM_COST" "PROC_SOCKET"
					( Origin gFrontEnd )
				)
				( attribute "CDS_LIB" "mstr_discrete"
					( Origin gPackager )
				)
				( attribute "CDS_LOCATION" "C4P1"
					( Origin gPackager )
				)
				( attribute "CDS_SEC" "1"
					( Origin gPackager )
				)
				( attribute "LOCATION" "C4P1"
					( Origin gFrontEnd )
				)
				( attribute "MATERIAL" "X6S"
					( Origin gFrontEnd )
				)
				( attribute "PACK_TYPE" "0805"
					( Origin gFrontEnd )
				)
				( attribute "PART_NUMBER" "C95333-006"
					( Origin gFrontEnd )
				)
				( attribute "PHYS_PAGE" "42"
					( Origin gFrontEnd )
				)
				( attribute "ROOM" "PVCCIN_CPU0_DECAP_VR"
					( Origin gFrontEnd )
				)
				( attribute "ROT" "0"
					( Origin gFrontEnd )
				)
				( attribute "SEC" "1"
					( Origin gPackager )
				)
				( attribute "TOLERANCE" "20%"
					( Origin gFrontEnd )
				)
				( attribute "VALUE" "47UF"
					( Origin gFrontEnd )
				)
				( attribute "VER" "1"
					( Origin gFrontEnd )
				)
				( attribute "VOLTAGE" "4V"
					( Units "uVoltage" "V" 1.000000)
					( Origin gFrontEnd )
				)
				( attribute "XY" "(-2550,950)"
					( Origin gFrontEnd )
				)
				( attribute "CHIPS_PART_NAME" "CAP"
					( Origin gPackager )
				)
				( attribute "CDS_PART_NAME" "CAP_0805-47UF,4V,20%,X6S,C9533A"
					( Origin gPackager )
				)
				( objectStatus "C4P1" )
				( pin "a"
					( attribute "PN" "1"
						( Origin gPackager )
					)
					( objectStatus "C4P1.1" )
				)
				( pin "b"
					( attribute "PN" "2"
						( Origin gPackager )
					)
					( objectStatus "C4P1.2" )
				)
			)
			( gate "@baseboard_fab2_lib.baseboard_fab2(sch_1):page42_i12"
				( attribute "BOM_COST" "PROC_SOCKET"
					( Origin gFrontEnd )
				)
				( attribute "CDS_LIB" "mstr_discrete"
					( Origin gPackager )
				)
				( attribute "CDS_LOCATION" "C4P9"
					( Origin gPackager )
				)
				( attribute "CDS_SEC" "1"
					( Origin gPackager )
				)
				( attribute "LOCATION" "C4P9"
					( Origin gFrontEnd )
				)
				( attribute "MATERIAL" "X6S"
					( Origin gFrontEnd )
				)
				( attribute "PACK_TYPE" "0805"
					( Origin gFrontEnd )
				)
				( attribute "PART_NUMBER" "C95333-006"
					( Origin gFrontEnd )
				)
				( attribute "PHYS_PAGE" "42"
					( Origin gFrontEnd )
				)
				( attribute "ROOM" "PVCCIN_CPU0_DECAP_VR"
					( Origin gFrontEnd )
				)
				( attribute "ROT" "0"
					( Origin gFrontEnd )
				)
				( attribute "SEC" "1"
					( Origin gPackager )
				)
				( attribute "TOLERANCE" "20%"
					( Origin gFrontEnd )
				)
				( attribute "VALUE" "47UF"
					( Origin gFrontEnd )
				)
				( attribute "VER" "1"
					( Origin gFrontEnd )
				)
				( attribute "VOLTAGE" "4V"
					( Units "uVoltage" "V" 1.000000)
					( Origin gFrontEnd )
				)
				( attribute "XY" "(-2850,950)"
					( Origin gFrontEnd )
				)
				( attribute "CHIPS_PART_NAME" "CAP"
					( Origin gPackager )
				)
				( attribute "CDS_PART_NAME" "CAP_0805-47UF,4V,20%,X6S,C9533A"
					( Origin gPackager )
				)
				( objectStatus "C4P9" )
				( pin "a"
					( attribute "PN" "1"
						( Origin gPackager )
					)
					( objectStatus "C4P9.1" )
				)
				( pin "b"
					( attribute "PN" "2"
						( Origin gPackager )
					)
					( objectStatus "C4P9.2" )
				)
			)
			( gate "@baseboard_fab2_lib.baseboard_fab2(sch_1):page42_i13"
				( attribute "BOM_COST" "PROC_SOCKET"
					( Origin gFrontEnd )
				)
				( attribute "CDS_LIB" "mstr_discrete"
					( Origin gPackager )
				)
				( attribute "CDS_LOCATION" "C5P19"
					( Origin gPackager )
				)
				( attribute "CDS_SEC" "1"
					( Origin gPackager )
				)
				( attribute "LOCATION" "C5P19"
					( Origin gFrontEnd )
				)
				( attribute "MATERIAL" "X6S"
					( Origin gFrontEnd )
				)
				( attribute "PACK_TYPE" "0805"
					( Origin gFrontEnd )
				)
				( attribute "PART_NUMBER" "C95333-006"
					( Origin gFrontEnd )
				)
				( attribute "PHYS_PAGE" "42"
					( Origin gFrontEnd )
				)
				( attribute "ROOM" "PVCCIN_CPU0_DECAP_VR"
					( Origin gFrontEnd )
				)
				( attribute "ROT" "0"
					( Origin gFrontEnd )
				)
				( attribute "SEC" "1"
					( Origin gPackager )
				)
				( attribute "TOLERANCE" "20%"
					( Origin gFrontEnd )
				)
				( attribute "VALUE" "47UF"
					( Origin gFrontEnd )
				)
				( attribute "VER" "1"
					( Origin gFrontEnd )
				)
				( attribute "VOLTAGE" "4V"
					( Units "uVoltage" "V" 1.000000)
					( Origin gFrontEnd )
				)
				( attribute "XY" "(-3825,2175)"
					( Origin gFrontEnd )
				)
				( attribute "CHIPS_PART_NAME" "CAP"
					( Origin gPackager )
				)
				( attribute "CDS_PART_NAME" "CAP_0805-47UF,4V,20%,X6S,C9533A"
					( Origin gPackager )
				)
				( objectStatus "C5P19" )
				( pin "a"
					( attribute "PN" "1"
						( Origin gPackager )
					)
					( objectStatus "C5P19.1" )
				)
				( pin "b"
					( attribute "PN" "2"
						( Origin gPackager )
					)
					( objectStatus "C5P19.2" )
				)
			)
			( gate "@baseboard_fab2_lib.baseboard_fab2(sch_1):page42_i14"
				( attribute "BOM_COST" "PROC_SOCKET"
					( Origin gFrontEnd )
				)
				( attribute "CDS_LIB" "mstr_discrete"
					( Origin gPackager )
				)
				( attribute "CDS_LOCATION" "C4P4"
					( Origin gPackager )
				)
				( attribute "CDS_SEC" "1"
					( Origin gPackager )
				)
				( attribute "LOCATION" "C4P4"
					( Origin gFrontEnd )
				)
				( attribute "MATERIAL" "X6S"
					( Origin gFrontEnd )
				)
				( attribute "PACK_TYPE" "0805"
					( Origin gFrontEnd )
				)
				( attribute "PART_NUMBER" "C95333-006"
					( Origin gFrontEnd )
				)
				( attribute "PHYS_PAGE" "42"
					( Origin gFrontEnd )
				)
				( attribute "ROOM" "PVCCIN_CPU0_DECAP_VR"
					( Origin gFrontEnd )
				)
				( attribute "ROT" "0"
					( Origin gFrontEnd )
				)
				( attribute "SEC" "1"
					( Origin gPackager )
				)
				( attribute "TOLERANCE" "20%"
					( Origin gFrontEnd )
				)
				( attribute "VALUE" "47UF"
					( Origin gFrontEnd )
				)
				( attribute "VER" "1"
					( Origin gFrontEnd )
				)
				( attribute "VOLTAGE" "4V"
					( Units "uVoltage" "V" 1.000000)
					( Origin gFrontEnd )
				)
				( attribute "XY" "(-4100,2175)"
					( Origin gFrontEnd )
				)
				( attribute "CHIPS_PART_NAME" "CAP"
					( Origin gPackager )
				)
				( attribute "CDS_PART_NAME" "CAP_0805-47UF,4V,20%,X6S,C9533A"
					( Origin gPackager )
				)
				( objectStatus "C4P4" )
				( pin "a"
					( attribute "PN" "1"
						( Origin gPackager )
					)
					( objectStatus "C4P4.1" )
				)
				( pin "b"
					( attribute "PN" "2"
						( Origin gPackager )
					)
					( objectStatus "C4P4.2" )
				)
			)
			( gate "@baseboard_fab2_lib.baseboard_fab2(sch_1):page42_i17"
				( attribute "BOM_COST" "PROC_SOCKET"
					( Origin gFrontEnd )
				)
				( attribute "CDS_LIB" "mstr_discrete"
					( Origin gPackager )
				)
				( attribute "CDS_LOCATION" "C4P10"
					( Origin gPackager )
				)
				( attribute "CDS_SEC" "1"
					( Origin gPackager )
				)
				( attribute "LOCATION" "C4P10"
					( Origin gFrontEnd )
				)
				( attribute "MATERIAL" "X6S"
					( Origin gFrontEnd )
				)
				( attribute "PACK_TYPE" "0805"
					( Origin gFrontEnd )
				)
				( attribute "PART_NUMBER" "C95333-006"
					( Origin gFrontEnd )
				)
				( attribute "PHYS_PAGE" "42"
					( Origin gFrontEnd )
				)
				( attribute "ROOM" "PVCCIN_CPU0_DECAP_VR"
					( Origin gFrontEnd )
				)
				( attribute "ROT" "0"
					( Origin gFrontEnd )
				)
				( attribute "SEC" "1"
					( Origin gPackager )
				)
				( attribute "TOLERANCE" "20%"
					( Origin gFrontEnd )
				)
				( attribute "VALUE" "47UF"
					( Origin gFrontEnd )
				)
				( attribute "VER" "1"
					( Origin gFrontEnd )
				)
				( attribute "VOLTAGE" "4V"
					( Units "uVoltage" "V" 1.000000)
					( Origin gFrontEnd )
				)
				( attribute "XY" "(-3175,950)"
					( Origin gFrontEnd )
				)
				( attribute "CHIPS_PART_NAME" "CAP"
					( Origin gPackager )
				)
				( attribute "CDS_PART_NAME" "CAP_0805-47UF,4V,20%,X6S,C9533A"
					( Origin gPackager )
				)
				( objectStatus "C4P10" )
				( pin "a"
					( attribute "PN" "1"
						( Origin gPackager )
					)
					( objectStatus "C4P10.1" )
				)
				( pin "b"
					( attribute "PN" "2"
						( Origin gPackager )
					)
					( objectStatus "C4P10.2" )
				)
			)
			( gate "@baseboard_fab2_lib.baseboard_fab2(sch_1):page42_i18"
				( attribute "BOM_COST" "PROC_SOCKET"
					( Origin gFrontEnd )
				)
				( attribute "CDS_LIB" "mstr_discrete"
					( Origin gPackager )
				)
				( attribute "CDS_LOCATION" "C5P9"
					( Origin gPackager )
				)
				( attribute "CDS_SEC" "1"
					( Origin gPackager )
				)
				( attribute "LOCATION" "C5P9"
					( Origin gFrontEnd )
				)
				( attribute "MATERIAL" "X6S"
					( Origin gFrontEnd )
				)
				( attribute "PACK_TYPE" "0805LF"
					( Origin gFrontEnd )
				)
				( attribute "PART_NUMBER" "C95333-002"
					( Origin gFrontEnd )
				)
				( attribute "PHYS_PAGE" "42"
					( Origin gFrontEnd )
				)
				( attribute "ROOM" "PVCCIN_CPU0_DECAP_VR"
					( Origin gFrontEnd )
				)
				( attribute "ROT" "0"
					( Origin gFrontEnd )
				)
				( attribute "SEC" "1"
					( Origin gPackager )
				)
				( attribute "TOLERANCE" "20%"
					( Origin gFrontEnd )
				)
				( attribute "VALUE" "22UF"
					( Origin gFrontEnd )
				)
				( attribute "VER" "1"
					( Origin gFrontEnd )
				)
				( attribute "VOLTAGE" "4V"
					( Units "uVoltage" "V" 1.000000)
					( Origin gFrontEnd )
				)
				( attribute "XY" "(-3600,975)"
					( Origin gFrontEnd )
				)
				( attribute "CHIPS_PART_NAME" "CAP"
					( Origin gPackager )
				)
				( attribute "CDS_PART_NAME" "CAP_0805LF-22UF,4V,20%,X6S,C95A"
					( Origin gPackager )
				)
				( objectStatus "C5P9" )
				( pin "a"
					( attribute "PN" "1"
						( Origin gPackager )
					)
					( objectStatus "C5P9.1" )
				)
				( pin "b"
					( attribute "PN" "2"
						( Origin gPackager )
					)
					( objectStatus "C5P9.2" )
				)
			)
			( gate "@baseboard_fab2_lib.baseboard_fab2(sch_1):page42_i19"
				( attribute "BOM_COST" "PROC_SOCKET"
					( Origin gFrontEnd )
				)
				( attribute "CDS_LIB" "mstr_discrete"
					( Origin gPackager )
				)
				( attribute "CDS_LOCATION" "C5P8"
					( Origin gPackager )
				)
				( attribute "CDS_SEC" "1"
					( Origin gPackager )
				)
				( attribute "LOCATION" "C5P8"
					( Origin gFrontEnd )
				)
				( attribute "MATERIAL" "X6S"
					( Origin gFrontEnd )
				)
				( attribute "PACK_TYPE" "0805LF"
					( Origin gFrontEnd )
				)
				( attribute "PART_NUMBER" "C95333-002"
					( Origin gFrontEnd )
				)
				( attribute "PHYS_PAGE" "42"
					( Origin gFrontEnd )
				)
				( attribute "ROOM" "PVCCIN_CPU0_DECAP_VR"
					( Origin gFrontEnd )
				)
				( attribute "ROT" "0"
					( Origin gFrontEnd )
				)
				( attribute "SEC" "1"
					( Origin gPackager )
				)
				( attribute "TOLERANCE" "20%"
					( Origin gFrontEnd )
				)
				( attribute "VALUE" "22UF"
					( Origin gFrontEnd )
				)
				( attribute "VER" "1"
					( Origin gFrontEnd )
				)
				( attribute "VOLTAGE" "4V"
					( Units "uVoltage" "V" 1.000000)
					( Origin gFrontEnd )
				)
				( attribute "XY" "(-3925,975)"
					( Origin gFrontEnd )
				)
				( attribute "CHIPS_PART_NAME" "CAP"
					( Origin gPackager )
				)
				( attribute "CDS_PART_NAME" "CAP_0805LF-22UF,4V,20%,X6S,C95A"
					( Origin gPackager )
				)
				( objectStatus "C5P8" )
				( pin "a"
					( attribute "PN" "1"
						( Origin gPackager )
					)
					( objectStatus "C5P8.1" )
				)
				( pin "b"
					( attribute "PN" "2"
						( Origin gPackager )
					)
					( objectStatus "C5P8.2" )
				)
			)
			( gate "@baseboard_fab2_lib.baseboard_fab2(sch_1):page42_i25"
				( attribute "BOM_COST" "PROC_SOCKET"
					( Origin gFrontEnd )
				)
				( attribute "CDS_LIB" "mstr_discrete"
					( Origin gPackager )
				)
				( attribute "CDS_LOCATION" "C5P7"
					( Origin gPackager )
				)
				( attribute "CDS_SEC" "1"
					( Origin gPackager )
				)
				( attribute "LOCATION" "C5P7"
					( Origin gFrontEnd )
				)
				( attribute "MATERIAL" "X6S"
					( Origin gFrontEnd )
				)
				( attribute "PACK_TYPE" "0805LF"
					( Origin gFrontEnd )
				)
				( attribute "PART_NUMBER" "C95333-002"
					( Origin gFrontEnd )
				)
				( attribute "PHYS_PAGE" "42"
					( Origin gFrontEnd )
				)
				( attribute "ROOM" "PVCCIN_CPU0_DECAP_VR"
					( Origin gFrontEnd )
				)
				( attribute "ROT" "0"
					( Origin gFrontEnd )
				)
				( attribute "SEC" "1"
					( Origin gPackager )
				)
				( attribute "TOLERANCE" "20%"
					( Origin gFrontEnd )
				)
				( attribute "VALUE" "22UF"
					( Origin gFrontEnd )
				)
				( attribute "VER" "1"
					( Origin gFrontEnd )
				)
				( attribute "VOLTAGE" "4V"
					( Units "uVoltage" "V" 1.000000)
					( Origin gFrontEnd )
				)
				( attribute "XY" "(-4275,975)"
					( Origin gFrontEnd )
				)
				( attribute "CHIPS_PART_NAME" "CAP"
					( Origin gPackager )
				)
				( attribute "CDS_PART_NAME" "CAP_0805LF-22UF,4V,20%,X6S,C95A"
					( Origin gPackager )
				)
				( objectStatus "C5P7" )
				( pin "a"
					( attribute "PN" "1"
						( Origin gPackager )
					)
					( objectStatus "C5P7.1" )
				)
				( pin "b"
					( attribute "PN" "2"
						( Origin gPackager )
					)
					( objectStatus "C5P7.2" )
				)
			)
			( gate "@baseboard_fab2_lib.baseboard_fab2(sch_1):page42_i27"
				( attribute "BOM_COST" "PROC_SOCKET"
					( Origin gFrontEnd )
				)
				( attribute "CDS_LIB" "mstr_discrete"
					( Origin gPackager )
				)
				( attribute "CDS_LOCATION" "C5P4"
					( Origin gPackager )
				)
				( attribute "CDS_SEC" "1"
					( Origin gPackager )
				)
				( attribute "LOCATION" "C5P4"
					( Origin gFrontEnd )
				)
				( attribute "MATERIAL" "X6S"
					( Origin gFrontEnd )
				)
				( attribute "PACK_TYPE" "0805"
					( Origin gFrontEnd )
				)
				( attribute "PART_NUMBER" "C95333-006"
					( Origin gFrontEnd )
				)
				( attribute "PHYS_PAGE" "42"
					( Origin gFrontEnd )
				)
				( attribute "ROOM" "PVCCIN_CPU0_DECAP_VR"
					( Origin gFrontEnd )
				)
				( attribute "ROT" "0"
					( Origin gFrontEnd )
				)
				( attribute "SEC" "1"
					( Origin gPackager )
				)
				( attribute "TOLERANCE" "20%"
					( Origin gFrontEnd )
				)
				( attribute "VALUE" "47UF"
					( Origin gFrontEnd )
				)
				( attribute "VER" "1"
					( Origin gFrontEnd )
				)
				( attribute "VOLTAGE" "4V"
					( Units "uVoltage" "V" 1.000000)
					( Origin gFrontEnd )
				)
				( attribute "XY" "(-5100,2200)"
					( Origin gFrontEnd )
				)
				( attribute "CHIPS_PART_NAME" "CAP"
					( Origin gPackager )
				)
				( attribute "CDS_PART_NAME" "CAP_0805-47UF,4V,20%,X6S,C9533A"
					( Origin gPackager )
				)
				( objectStatus "C5P4" )
				( pin "a"
					( attribute "PN" "1"
						( Origin gPackager )
					)
					( objectStatus "C5P4.1" )
				)
				( pin "b"
					( attribute "PN" "2"
						( Origin gPackager )
					)
					( objectStatus "C5P4.2" )
				)
			)
			( gate "@baseboard_fab2_lib.baseboard_fab2(sch_1):page42_i28"
				( attribute "BOM_COST" "PROC_SOCKET"
					( Origin gFrontEnd )
				)
				( attribute "CDS_LIB" "mstr_discrete"
					( Origin gPackager )
				)
				( attribute "CDS_LOCATION" "C5P23"
					( Origin gPackager )
				)
				( attribute "CDS_SEC" "1"
					( Origin gPackager )
				)
				( attribute "LOCATION" "C5P23"
					( Origin gFrontEnd )
				)
				( attribute "MATERIAL" "X6S"
					( Origin gFrontEnd )
				)
				( attribute "PACK_TYPE" "0805"
					( Origin gFrontEnd )
				)
				( attribute "PART_NUMBER" "C95333-006"
					( Origin gFrontEnd )
				)
				( attribute "PHYS_PAGE" "42"
					( Origin gFrontEnd )
				)
				( attribute "ROOM" "PVCCIN_CPU0_DECAP_VR"
					( Origin gFrontEnd )
				)
				( attribute "ROT" "0"
					( Origin gFrontEnd )
				)
				( attribute "SEC" "1"
					( Origin gPackager )
				)
				( attribute "TOLERANCE" "20%"
					( Origin gFrontEnd )
				)
				( attribute "VALUE" "47UF"
					( Origin gFrontEnd )
				)
				( attribute "VER" "1"
					( Origin gFrontEnd )
				)
				( attribute "VOLTAGE" "4V"
					( Units "uVoltage" "V" 1.000000)
					( Origin gFrontEnd )
				)
				( attribute "XY" "(-5350,2225)"
					( Origin gFrontEnd )
				)
				( attribute "CHIPS_PART_NAME" "CAP"
					( Origin gPackager )
				)
				( attribute "CDS_PART_NAME" "CAP_0805-47UF,4V,20%,X6S,C9533A"
					( Origin gPackager )
				)
				( objectStatus "C5P23" )
				( pin "a"
					( attribute "PN" "1"
						( Origin gPackager )
					)
					( objectStatus "C5P23.1" )
				)
				( pin "b"
					( attribute "PN" "2"
						( Origin gPackager )
					)
					( objectStatus "C5P23.2" )
				)
			)
			( gate "@baseboard_fab2_lib.baseboard_fab2(sch_1):page42_i33"
				( attribute "BOM_COST" "PROC_SOCKET"
					( Origin gFrontEnd )
				)
				( attribute "CDS_LIB" "mstr_discrete"
					( Origin gPackager )
				)
				( attribute "CDS_LOCATION" "C5P24"
					( Origin gPackager )
				)
				( attribute "CDS_SEC" "1"
					( Origin gPackager )
				)
				( attribute "LOCATION" "C5P24"
					( Origin gFrontEnd )
				)
				( attribute "MATERIAL" "X6S"
					( Origin gFrontEnd )
				)
				( attribute "PACK_TYPE" "0805"
					( Origin gFrontEnd )
				)
				( attribute "PART_NUMBER" "C95333-006"
					( Origin gFrontEnd )
				)
				( attribute "PHYS_PAGE" "42"
					( Origin gFrontEnd )
				)
				( attribute "ROOM" "PVCCIN_CPU0_DECAP_VR"
					( Origin gFrontEnd )
				)
				( attribute "ROT" "0"
					( Origin gFrontEnd )
				)
				( attribute "SEC" "1"
					( Origin gPackager )
				)
				( attribute "TOLERANCE" "20%"
					( Origin gFrontEnd )
				)
				( attribute "VALUE" "47UF"
					( Origin gFrontEnd )
				)
				( attribute "VER" "1"
					( Origin gFrontEnd )
				)
				( attribute "VOLTAGE" "4V"
					( Units "uVoltage" "V" 1.000000)
					( Origin gFrontEnd )
				)
				( attribute "XY" "(-5300,1575)"
					( Origin gFrontEnd )
				)
				( attribute "CHIPS_PART_NAME" "CAP"
					( Origin gPackager )
				)
				( attribute "CDS_PART_NAME" "CAP_0805-47UF,4V,20%,X6S,C9533A"
					( Origin gPackager )
				)
				( objectStatus "C5P24" )
				( pin "a"
					( attribute "PN" "1"
						( Origin gPackager )
					)
					( objectStatus "C5P24.1" )
				)
				( pin "b"
					( attribute "PN" "2"
						( Origin gPackager )
					)
					( objectStatus "C5P24.2" )
				)
			)
			( gate "@baseboard_fab2_lib.baseboard_fab2(sch_1):page42_i37"
				( attribute "BOM_COST" "PROC_SOCKET"
					( Origin gFrontEnd )
				)
				( attribute "CDS_LIB" "mstr_discrete"
					( Origin gPackager )
				)
				( attribute "CDS_LOCATION" "C5P25"
					( Origin gPackager )
				)
				( attribute "CDS_SEC" "1"
					( Origin gPackager )
				)
				( attribute "LOCATION" "C5P25"
					( Origin gFrontEnd )
				)
				( attribute "MATERIAL" "X6S"
					( Origin gFrontEnd )
				)
				( attribute "PACK_TYPE" "0805"
					( Origin gFrontEnd )
				)
				( attribute "PART_NUMBER" "C95333-006"
					( Origin gFrontEnd )
				)
				( attribute "PHYS_PAGE" "42"
					( Origin gFrontEnd )
				)
				( attribute "ROOM" "PVCCIN_CPU0_DECAP_VR"
					( Origin gFrontEnd )
				)
				( attribute "ROT" "0"
					( Origin gFrontEnd )
				)
				( attribute "SEC" "1"
					( Origin gPackager )
				)
				( attribute "TOLERANCE" "20%"
					( Origin gFrontEnd )
				)
				( attribute "VALUE" "47UF"
					( Origin gFrontEnd )
				)
				( attribute "VER" "1"
					( Origin gFrontEnd )
				)
				( attribute "VOLTAGE" "4V"
					( Units "uVoltage" "V" 1.000000)
					( Origin gFrontEnd )
				)
				( attribute "XY" "(-5275,900)"
					( Origin gFrontEnd )
				)
				( attribute "CHIPS_PART_NAME" "CAP"
					( Origin gPackager )
				)
				( attribute "CDS_PART_NAME" "CAP_0805-47UF,4V,20%,X6S,C9533A"
					( Origin gPackager )
				)
				( objectStatus "C5P25" )
				( pin "a"
					( attribute "PN" "1"
						( Origin gPackager )
					)
					( objectStatus "C5P25.1" )
				)
				( pin "b"
					( attribute "PN" "2"
						( Origin gPackager )
					)
					( objectStatus "C5P25.2" )
				)
			)
			( gate "@baseboard_fab2_lib.baseboard_fab2(sch_1):page42_i38"
				( attribute "BOM_COST" "PROC_SOCKET"
					( Origin gFrontEnd )
				)
				( attribute "CDS_LIB" "mstr_discrete"
					( Origin gPackager )
				)
				( attribute "CDS_LOCATION" "C5P6"
					( Origin gPackager )
				)
				( attribute "CDS_SEC" "1"
					( Origin gPackager )
				)
				( attribute "LOCATION" "C5P6"
					( Origin gFrontEnd )
				)
				( attribute "MATERIAL" "X6S"
					( Origin gFrontEnd )
				)
				( attribute "PACK_TYPE" "0805"
					( Origin gFrontEnd )
				)
				( attribute "PART_NUMBER" "C95333-006"
					( Origin gFrontEnd )
				)
				( attribute "PHYS_PAGE" "42"
					( Origin gFrontEnd )
				)
				( attribute "ROOM" "PVCCIN_CPU0_DECAP_VR"
					( Origin gFrontEnd )
				)
				( attribute "ROT" "0"
					( Origin gFrontEnd )
				)
				( attribute "SEC" "1"
					( Origin gPackager )
				)
				( attribute "TOLERANCE" "20%"
					( Origin gFrontEnd )
				)
				( attribute "VALUE" "47UF"
					( Origin gFrontEnd )
				)
				( attribute "VER" "1"
					( Origin gFrontEnd )
				)
				( attribute "VOLTAGE" "4V"
					( Units "uVoltage" "V" 1.000000)
					( Origin gFrontEnd )
				)
				( attribute "XY" "(-5675,2225)"
					( Origin gFrontEnd )
				)
				( attribute "CHIPS_PART_NAME" "CAP"
					( Origin gPackager )
				)
				( attribute "CDS_PART_NAME" "CAP_0805-47UF,4V,20%,X6S,C9533A"
					( Origin gPackager )
				)
				( objectStatus "C5P6" )
				( pin "a"
					( attribute "PN" "1"
						( Origin gPackager )
					)
					( objectStatus "C5P6.1" )
				)
				( pin "b"
					( attribute "PN" "2"
						( Origin gPackager )
					)
					( objectStatus "C5P6.2" )
				)
			)
			( gate "@baseboard_fab2_lib.baseboard_fab2(sch_1):page42_i40"
				( attribute "BOM_COST" "PROC_SOCKET"
					( Origin gFrontEnd )
				)
				( attribute "CDS_LIB" "mstr_discrete"
					( Origin gPackager )
				)
				( attribute "CDS_LOCATION" "C5P41"
					( Origin gPackager )
				)
				( attribute "CDS_SEC" "1"
					( Origin gPackager )
				)
				( attribute "LOCATION" "C5P41"
					( Origin gFrontEnd )
				)
				( attribute "MATERIAL" "X6S"
					( Origin gFrontEnd )
				)
				( attribute "PACK_TYPE" "0805"
					( Origin gFrontEnd )
				)
				( attribute "PART_NUMBER" "C95333-006"
					( Origin gFrontEnd )
				)
				( attribute "PHYS_PAGE" "42"
					( Origin gFrontEnd )
				)
				( attribute "ROOM" "PVCCIN_CPU0_DECAP_VR"
					( Origin gFrontEnd )
				)
				( attribute "ROT" "0"
					( Origin gFrontEnd )
				)
				( attribute "SEC" "1"
					( Origin gPackager )
				)
				( attribute "TOLERANCE" "20%"
					( Origin gFrontEnd )
				)
				( attribute "VALUE" "47UF"
					( Origin gFrontEnd )
				)
				( attribute "VER" "1"
					( Origin gFrontEnd )
				)
				( attribute "VOLTAGE" "4V"
					( Units "uVoltage" "V" 1.000000)
					( Origin gFrontEnd )
				)
				( attribute "XY" "(-5975,2225)"
					( Origin gFrontEnd )
				)
				( attribute "CHIPS_PART_NAME" "CAP"
					( Origin gPackager )
				)
				( attribute "CDS_PART_NAME" "CAP_0805-47UF,4V,20%,X6S,C9533A"
					( Origin gPackager )
				)
				( objectStatus "C5P41" )
				( pin "a"
					( attribute "PN" "1"
						( Origin gPackager )
					)
					( objectStatus "C5P41.1" )
				)
				( pin "b"
					( attribute "PN" "2"
						( Origin gPackager )
					)
					( objectStatus "C5P41.2" )
				)
			)
			( gate "@baseboard_fab2_lib.baseboard_fab2(sch_1):page42_i41"
				( attribute "BOM_COST" "PROC_SOCKET"
					( Origin gFrontEnd )
				)
				( attribute "CDS_LIB" "mstr_discrete"
					( Origin gPackager )
				)
				( attribute "CDS_LOCATION" "C5P14"
					( Origin gPackager )
				)
				( attribute "CDS_SEC" "1"
					( Origin gPackager )
				)
				( attribute "LOCATION" "C5P14"
					( Origin gFrontEnd )
				)
				( attribute "MATERIAL" "X6S"
					( Origin gFrontEnd )
				)
				( attribute "PACK_TYPE" "0805"
					( Origin gFrontEnd )
				)
				( attribute "PART_NUMBER" "C95333-006"
					( Origin gFrontEnd )
				)
				( attribute "PHYS_PAGE" "42"
					( Origin gFrontEnd )
				)
				( attribute "ROOM" "PVCCIN_CPU0_DECAP_VR"
					( Origin gFrontEnd )
				)
				( attribute "ROT" "0"
					( Origin gFrontEnd )
				)
				( attribute "SEC" "1"
					( Origin gPackager )
				)
				( attribute "TOLERANCE" "20%"
					( Origin gFrontEnd )
				)
				( attribute "VALUE" "47UF"
					( Origin gFrontEnd )
				)
				( attribute "VER" "1"
					( Origin gFrontEnd )
				)
				( attribute "VOLTAGE" "4V"
					( Units "uVoltage" "V" 1.000000)
					( Origin gFrontEnd )
				)
				( attribute "XY" "(-6350,2225)"
					( Origin gFrontEnd )
				)
				( attribute "CHIPS_PART_NAME" "CAP"
					( Origin gPackager )
				)
				( attribute "CDS_PART_NAME" "CAP_0805-47UF,4V,20%,X6S,C9533A"
					( Origin gPackager )
				)
				( objectStatus "C5P14" )
				( pin "a"
					( attribute "PN" "1"
						( Origin gPackager )
					)
					( objectStatus "C5P14.1" )
				)
				( pin "b"
					( attribute "PN" "2"
						( Origin gPackager )
					)
					( objectStatus "C5P14.2" )
				)
			)
			( gate "@baseboard_fab2_lib.baseboard_fab2(sch_1):page42_i42"
				( attribute "BOM_COST" "PROC_SOCKET"
					( Origin gFrontEnd )
				)
				( attribute "CDS_LIB" "mstr_discrete"
					( Origin gPackager )
				)
				( attribute "CDS_LOCATION" "C5P5"
					( Origin gPackager )
				)
				( attribute "CDS_SEC" "1"
					( Origin gPackager )
				)
				( attribute "LOCATION" "C5P5"
					( Origin gFrontEnd )
				)
				( attribute "MATERIAL" "X6S"
					( Origin gFrontEnd )
				)
				( attribute "PACK_TYPE" "0805"
					( Origin gFrontEnd )
				)
				( attribute "PART_NUMBER" "C95333-006"
					( Origin gFrontEnd )
				)
				( attribute "PHYS_PAGE" "42"
					( Origin gFrontEnd )
				)
				( attribute "ROOM" "PVCCIN_CPU0_DECAP_VR"
					( Origin gFrontEnd )
				)
				( attribute "ROT" "0"
					( Origin gFrontEnd )
				)
				( attribute "SEC" "1"
					( Origin gPackager )
				)
				( attribute "TOLERANCE" "20%"
					( Origin gFrontEnd )
				)
				( attribute "VALUE" "47UF"
					( Origin gFrontEnd )
				)
				( attribute "VER" "1"
					( Origin gFrontEnd )
				)
				( attribute "VOLTAGE" "4V"
					( Units "uVoltage" "V" 1.000000)
					( Origin gFrontEnd )
				)
				( attribute "XY" "(-5625,1575)"
					( Origin gFrontEnd )
				)
				( attribute "CHIPS_PART_NAME" "CAP"
					( Origin gPackager )
				)
				( attribute "CDS_PART_NAME" "CAP_0805-47UF,4V,20%,X6S,C9533A"
					( Origin gPackager )
				)
				( objectStatus "C5P5" )
				( pin "a"
					( attribute "PN" "1"
						( Origin gPackager )
					)
					( objectStatus "C5P5.1" )
				)
				( pin "b"
					( attribute "PN" "2"
						( Origin gPackager )
					)
					( objectStatus "C5P5.2" )
				)
			)
			( gate "@baseboard_fab2_lib.baseboard_fab2(sch_1):page42_i44"
				( attribute "BOM_COST" "PROC_SOCKET"
					( Origin gFrontEnd )
				)
				( attribute "CDS_LIB" "mstr_discrete"
					( Origin gPackager )
				)
				( attribute "CDS_LOCATION" "C5P27"
					( Origin gPackager )
				)
				( attribute "CDS_SEC" "1"
					( Origin gPackager )
				)
				( attribute "LOCATION" "C5P27"
					( Origin gFrontEnd )
				)
				( attribute "MATERIAL" "X6S"
					( Origin gFrontEnd )
				)
				( attribute "PACK_TYPE" "0805"
					( Origin gFrontEnd )
				)
				( attribute "PART_NUMBER" "C95333-006"
					( Origin gFrontEnd )
				)
				( attribute "PHYS_PAGE" "42"
					( Origin gFrontEnd )
				)
				( attribute "ROOM" "PVCCIN_CPU0_DECAP_VR"
					( Origin gFrontEnd )
				)
				( attribute "ROT" "0"
					( Origin gFrontEnd )
				)
				( attribute "SEC" "1"
					( Origin gPackager )
				)
				( attribute "TOLERANCE" "20%"
					( Origin gFrontEnd )
				)
				( attribute "VALUE" "47UF"
					( Origin gFrontEnd )
				)
				( attribute "VER" "1"
					( Origin gFrontEnd )
				)
				( attribute "VOLTAGE" "4V"
					( Units "uVoltage" "V" 1.000000)
					( Origin gFrontEnd )
				)
				( attribute "XY" "(-5975,1575)"
					( Origin gFrontEnd )
				)
				( attribute "CHIPS_PART_NAME" "CAP"
					( Origin gPackager )
				)
				( attribute "CDS_PART_NAME" "CAP_0805-47UF,4V,20%,X6S,C9533A"
					( Origin gPackager )
				)
				( objectStatus "C5P27" )
				( pin "a"
					( attribute "PN" "1"
						( Origin gPackager )
					)
					( objectStatus "C5P27.1" )
				)
				( pin "b"
					( attribute "PN" "2"
						( Origin gPackager )
					)
					( objectStatus "C5P27.2" )
				)
			)
			( gate "@baseboard_fab2_lib.baseboard_fab2(sch_1):page42_i50"
				( attribute "BOM_COST" "PROC_SOCKET"
					( Origin gFrontEnd )
				)
				( attribute "CDS_LIB" "mstr_discrete"
					( Origin gPackager )
				)
				( attribute "CDS_LOCATION" "C5P33"
					( Origin gPackager )
				)
				( attribute "CDS_SEC" "1"
					( Origin gPackager )
				)
				( attribute "LOCATION" "C5P33"
					( Origin gFrontEnd )
				)
				( attribute "MATERIAL" "X6S"
					( Origin gFrontEnd )
				)
				( attribute "PACK_TYPE" "0805"
					( Origin gFrontEnd )
				)
				( attribute "PART_NUMBER" "C95333-006"
					( Origin gFrontEnd )
				)
				( attribute "PHYS_PAGE" "42"
					( Origin gFrontEnd )
				)
				( attribute "ROOM" "PVCCIN_CPU0_DECAP_VR"
					( Origin gFrontEnd )
				)
				( attribute "ROT" "0"
					( Origin gFrontEnd )
				)
				( attribute "SEC" "1"
					( Origin gPackager )
				)
				( attribute "TOLERANCE" "20%"
					( Origin gFrontEnd )
				)
				( attribute "VALUE" "47UF"
					( Origin gFrontEnd )
				)
				( attribute "VER" "1"
					( Origin gFrontEnd )
				)
				( attribute "VOLTAGE" "4V"
					( Units "uVoltage" "V" 1.000000)
					( Origin gFrontEnd )
				)
				( attribute "XY" "(-7050,2225)"
					( Origin gFrontEnd )
				)
				( attribute "CHIPS_PART_NAME" "CAP"
					( Origin gPackager )
				)
				( attribute "CDS_PART_NAME" "CAP_0805-47UF,4V,20%,X6S,C9533A"
					( Origin gPackager )
				)
				( objectStatus "C5P33" )
				( pin "a"
					( attribute "PN" "1"
						( Origin gPackager )
					)
					( objectStatus "C5P33.1" )
				)
				( pin "b"
					( attribute "PN" "2"
						( Origin gPackager )
					)
					( objectStatus "C5P33.2" )
				)
			)
			( gate "@baseboard_fab2_lib.baseboard_fab2(sch_1):page42_i51"
				( attribute "BOM_COST" "PROC_SOCKET"
					( Origin gFrontEnd )
				)
				( attribute "CDS_LIB" "mstr_discrete"
					( Origin gPackager )
				)
				( attribute "CDS_LOCATION" "C5P35"
					( Origin gPackager )
				)
				( attribute "CDS_SEC" "1"
					( Origin gPackager )
				)
				( attribute "LOCATION" "C5P35"
					( Origin gFrontEnd )
				)
				( attribute "MATERIAL" "X6S"
					( Origin gFrontEnd )
				)
				( attribute "PACK_TYPE" "0805"
					( Origin gFrontEnd )
				)
				( attribute "PART_NUMBER" "C95333-006"
					( Origin gFrontEnd )
				)
				( attribute "PHYS_PAGE" "42"
					( Origin gFrontEnd )
				)
				( attribute "ROOM" "PVCCIN_CPU0_DECAP_VR"
					( Origin gFrontEnd )
				)
				( attribute "ROT" "0"
					( Origin gFrontEnd )
				)
				( attribute "SEC" "1"
					( Origin gPackager )
				)
				( attribute "TOLERANCE" "20%"
					( Origin gFrontEnd )
				)
				( attribute "VALUE" "47UF"
					( Origin gFrontEnd )
				)
				( attribute "VER" "1"
					( Origin gFrontEnd )
				)
				( attribute "VOLTAGE" "4V"
					( Units "uVoltage" "V" 1.000000)
					( Origin gFrontEnd )
				)
				( attribute "XY" "(-7375,2225)"
					( Origin gFrontEnd )
				)
				( attribute "CHIPS_PART_NAME" "CAP"
					( Origin gPackager )
				)
				( attribute "CDS_PART_NAME" "CAP_0805-47UF,4V,20%,X6S,C9533A"
					( Origin gPackager )
				)
				( objectStatus "C5P35" )
				( pin "a"
					( attribute "PN" "1"
						( Origin gPackager )
					)
					( objectStatus "C5P35.1" )
				)
				( pin "b"
					( attribute "PN" "2"
						( Origin gPackager )
					)
					( objectStatus "C5P35.2" )
				)
			)
			( gate "@baseboard_fab2_lib.baseboard_fab2(sch_1):page42_i53"
				( attribute "BOM_COST" "PROC_SOCKET"
					( Origin gFrontEnd )
				)
				( attribute "CDS_LIB" "mstr_discrete"
					( Origin gPackager )
				)
				( attribute "CDS_LOCATION" "C5P32"
					( Origin gPackager )
				)
				( attribute "CDS_SEC" "1"
					( Origin gPackager )
				)
				( attribute "LOCATION" "C5P32"
					( Origin gFrontEnd )
				)
				( attribute "MATERIAL" "X6S"
					( Origin gFrontEnd )
				)
				( attribute "PACK_TYPE" "0805"
					( Origin gFrontEnd )
				)
				( attribute "PART_NUMBER" "C95333-006"
					( Origin gFrontEnd )
				)
				( attribute "PHYS_PAGE" "42"
					( Origin gFrontEnd )
				)
				( attribute "ROOM" "PVCCIN_CPU0_DECAP_VR"
					( Origin gFrontEnd )
				)
				( attribute "ROT" "0"
					( Origin gFrontEnd )
				)
				( attribute "SEC" "1"
					( Origin gPackager )
				)
				( attribute "TOLERANCE" "20%"
					( Origin gFrontEnd )
				)
				( attribute "VALUE" "47UF"
					( Origin gFrontEnd )
				)
				( attribute "VER" "1"
					( Origin gFrontEnd )
				)
				( attribute "VOLTAGE" "4V"
					( Units "uVoltage" "V" 1.000000)
					( Origin gFrontEnd )
				)
				( attribute "XY" "(-7050,1575)"
					( Origin gFrontEnd )
				)
				( attribute "CHIPS_PART_NAME" "CAP"
					( Origin gPackager )
				)
				( attribute "CDS_PART_NAME" "CAP_0805-47UF,4V,20%,X6S,C9533A"
					( Origin gPackager )
				)
				( objectStatus "C5P32" )
				( pin "a"
					( attribute "PN" "1"
						( Origin gPackager )
					)
					( objectStatus "C5P32.1" )
				)
				( pin "b"
					( attribute "PN" "2"
						( Origin gPackager )
					)
					( objectStatus "C5P32.2" )
				)
			)
			( gate "@baseboard_fab2_lib.baseboard_fab2(sch_1):page42_i54"
				( attribute "BOM_COST" "PROC_SOCKET"
					( Origin gFrontEnd )
				)
				( attribute "CDS_LIB" "mstr_discrete"
					( Origin gPackager )
				)
				( attribute "CDS_LOCATION" "C5P34"
					( Origin gPackager )
				)
				( attribute "CDS_SEC" "1"
					( Origin gPackager )
				)
				( attribute "LOCATION" "C5P34"
					( Origin gFrontEnd )
				)
				( attribute "MATERIAL" "X6S"
					( Origin gFrontEnd )
				)
				( attribute "PACK_TYPE" "0805"
					( Origin gFrontEnd )
				)
				( attribute "PART_NUMBER" "C95333-006"
					( Origin gFrontEnd )
				)
				( attribute "PHYS_PAGE" "42"
					( Origin gFrontEnd )
				)
				( attribute "ROOM" "PVCCIN_CPU0_DECAP_VR"
					( Origin gFrontEnd )
				)
				( attribute "ROT" "0"
					( Origin gFrontEnd )
				)
				( attribute "SEC" "1"
					( Origin gPackager )
				)
				( attribute "TOLERANCE" "20%"
					( Origin gFrontEnd )
				)
				( attribute "VALUE" "47UF"
					( Origin gFrontEnd )
				)
				( attribute "VER" "1"
					( Origin gFrontEnd )
				)
				( attribute "VOLTAGE" "4V"
					( Units "uVoltage" "V" 1.000000)
					( Origin gFrontEnd )
				)
				( attribute "XY" "(-7375,1575)"
					( Origin gFrontEnd )
				)
				( attribute "CHIPS_PART_NAME" "CAP"
					( Origin gPackager )
				)
				( attribute "CDS_PART_NAME" "CAP_0805-47UF,4V,20%,X6S,C9533A"
					( Origin gPackager )
				)
				( objectStatus "C5P34" )
				( pin "a"
					( attribute "PN" "1"
						( Origin gPackager )
					)
					( objectStatus "C5P34.1" )
				)
				( pin "b"
					( attribute "PN" "2"
						( Origin gPackager )
					)
					( objectStatus "C5P34.2" )
				)
			)
			( gate "@baseboard_fab2_lib.baseboard_fab2(sch_1):page42_i55"
				( attribute "BOM_COST" "PROC_SOCKET"
					( Origin gFrontEnd )
				)
				( attribute "CDS_LIB" "mstr_discrete"
					( Origin gPackager )
				)
				( attribute "CDS_LOCATION" "C5P22"
					( Origin gPackager )
				)
				( attribute "CDS_SEC" "1"
					( Origin gPackager )
				)
				( attribute "LOCATION" "C5P22"
					( Origin gFrontEnd )
				)
				( attribute "MATERIAL" "X6S"
					( Origin gFrontEnd )
				)
				( attribute "PACK_TYPE" "0805"
					( Origin gFrontEnd )
				)
				( attribute "PART_NUMBER" "C95333-006"
					( Origin gFrontEnd )
				)
				( attribute "PHYS_PAGE" "42"
					( Origin gFrontEnd )
				)
				( attribute "ROOM" "PVCCIN_CPU0_DECAP_VR"
					( Origin gFrontEnd )
				)
				( attribute "ROT" "0"
					( Origin gFrontEnd )
				)
				( attribute "SEC" "1"
					( Origin gPackager )
				)
				( attribute "TOLERANCE" "20%"
					( Origin gFrontEnd )
				)
				( attribute "VALUE" "47UF"
					( Origin gFrontEnd )
				)
				( attribute "VER" "1"
					( Origin gFrontEnd )
				)
				( attribute "VOLTAGE" "4V"
					( Units "uVoltage" "V" 1.000000)
					( Origin gFrontEnd )
				)
				( attribute "XY" "(-5600,900)"
					( Origin gFrontEnd )
				)
				( attribute "CHIPS_PART_NAME" "CAP"
					( Origin gPackager )
				)
				( attribute "CDS_PART_NAME" "CAP_0805-47UF,4V,20%,X6S,C9533A"
					( Origin gPackager )
				)
				( objectStatus "C5P22" )
				( pin "a"
					( attribute "PN" "1"
						( Origin gPackager )
					)
					( objectStatus "C5P22.1" )
				)
				( pin "b"
					( attribute "PN" "2"
						( Origin gPackager )
					)
					( objectStatus "C5P22.2" )
				)
			)
			( gate "@baseboard_fab2_lib.baseboard_fab2(sch_1):page42_i56"
				( attribute "BOM_COST" "PROC_SOCKET"
					( Origin gFrontEnd )
				)
				( attribute "CDS_LIB" "mstr_discrete"
					( Origin gPackager )
				)
				( attribute "CDS_LOCATION" "C5P26"
					( Origin gPackager )
				)
				( attribute "CDS_SEC" "1"
					( Origin gPackager )
				)
				( attribute "LOCATION" "C5P26"
					( Origin gFrontEnd )
				)
				( attribute "MATERIAL" "X6S"
					( Origin gFrontEnd )
				)
				( attribute "PACK_TYPE" "0805"
					( Origin gFrontEnd )
				)
				( attribute "PART_NUMBER" "C95333-006"
					( Origin gFrontEnd )
				)
				( attribute "PHYS_PAGE" "42"
					( Origin gFrontEnd )
				)
				( attribute "ROOM" "PVCCIN_CPU0_DECAP_VR"
					( Origin gFrontEnd )
				)
				( attribute "ROT" "0"
					( Origin gFrontEnd )
				)
				( attribute "SEC" "1"
					( Origin gPackager )
				)
				( attribute "TOLERANCE" "20%"
					( Origin gFrontEnd )
				)
				( attribute "VALUE" "47UF"
					( Origin gFrontEnd )
				)
				( attribute "VER" "1"
					( Origin gFrontEnd )
				)
				( attribute "VOLTAGE" "4V"
					( Units "uVoltage" "V" 1.000000)
					( Origin gFrontEnd )
				)
				( attribute "XY" "(-5950,900)"
					( Origin gFrontEnd )
				)
				( attribute "CHIPS_PART_NAME" "CAP"
					( Origin gPackager )
				)
				( attribute "CDS_PART_NAME" "CAP_0805-47UF,4V,20%,X6S,C9533A"
					( Origin gPackager )
				)
				( objectStatus "C5P26" )
				( pin "a"
					( attribute "PN" "1"
						( Origin gPackager )
					)
					( objectStatus "C5P26.1" )
				)
				( pin "b"
					( attribute "PN" "2"
						( Origin gPackager )
					)
					( objectStatus "C5P26.2" )
				)
			)
			( gate "@baseboard_fab2_lib.baseboard_fab2(sch_1):page42_i57"
				( attribute "BOM_COST" "PROC_SOCKET"
					( Origin gFrontEnd )
				)
				( attribute "CDS_LIB" "mstr_discrete"
					( Origin gPackager )
				)
				( attribute "CDS_LOCATION" "C5P40"
					( Origin gPackager )
				)
				( attribute "CDS_SEC" "1"
					( Origin gPackager )
				)
				( attribute "LOCATION" "C5P40"
					( Origin gFrontEnd )
				)
				( attribute "MATERIAL" "X6S"
					( Origin gFrontEnd )
				)
				( attribute "PACK_TYPE" "0805"
					( Origin gFrontEnd )
				)
				( attribute "PART_NUMBER" "C95333-006"
					( Origin gFrontEnd )
				)
				( attribute "PHYS_PAGE" "42"
					( Origin gFrontEnd )
				)
				( attribute "ROOM" "PVCCIN_CPU0_DECAP_VR"
					( Origin gFrontEnd )
				)
				( attribute "ROT" "0"
					( Origin gFrontEnd )
				)
				( attribute "SEC" "1"
					( Origin gPackager )
				)
				( attribute "TOLERANCE" "20%"
					( Origin gFrontEnd )
				)
				( attribute "VALUE" "47UF"
					( Origin gFrontEnd )
				)
				( attribute "VER" "1"
					( Origin gFrontEnd )
				)
				( attribute "VOLTAGE" "4V"
					( Units "uVoltage" "V" 1.000000)
					( Origin gFrontEnd )
				)
				( attribute "XY" "(-6350,925)"
					( Origin gFrontEnd )
				)
				( attribute "CHIPS_PART_NAME" "CAP"
					( Origin gPackager )
				)
				( attribute "CDS_PART_NAME" "CAP_0805-47UF,4V,20%,X6S,C9533A"
					( Origin gPackager )
				)
				( objectStatus "C5P40" )
				( pin "a"
					( attribute "PN" "1"
						( Origin gPackager )
					)
					( objectStatus "C5P40.1" )
				)
				( pin "b"
					( attribute "PN" "2"
						( Origin gPackager )
					)
					( objectStatus "C5P40.2" )
				)
			)
			( gate "@baseboard_fab2_lib.baseboard_fab2(sch_1):page42_i59"
				( attribute "BOM_COST" "PROC_SOCKET"
					( Origin gFrontEnd )
				)
				( attribute "CDS_LIB" "mstr_discrete"
					( Origin gPackager )
				)
				( attribute "CDS_LOCATION" "C5P42"
					( Origin gPackager )
				)
				( attribute "CDS_SEC" "1"
					( Origin gPackager )
				)
				( attribute "LOCATION" "C5P42"
					( Origin gFrontEnd )
				)
				( attribute "MATERIAL" "X6S"
					( Origin gFrontEnd )
				)
				( attribute "PACK_TYPE" "0805"
					( Origin gFrontEnd )
				)
				( attribute "PART_NUMBER" "C95333-006"
					( Origin gFrontEnd )
				)
				( attribute "PHYS_PAGE" "42"
					( Origin gFrontEnd )
				)
				( attribute "ROOM" "PVCCIN_CPU0_DECAP_VR"
					( Origin gFrontEnd )
				)
				( attribute "ROT" "0"
					( Origin gFrontEnd )
				)
				( attribute "SEC" "1"
					( Origin gPackager )
				)
				( attribute "TOLERANCE" "20%"
					( Origin gFrontEnd )
				)
				( attribute "VALUE" "47UF"
					( Origin gFrontEnd )
				)
				( attribute "VER" "1"
					( Origin gFrontEnd )
				)
				( attribute "VOLTAGE" "4V"
					( Units "uVoltage" "V" 1.000000)
					( Origin gFrontEnd )
				)
				( attribute "XY" "(-6700,925)"
					( Origin gFrontEnd )
				)
				( attribute "CHIPS_PART_NAME" "CAP"
					( Origin gPackager )
				)
				( attribute "CDS_PART_NAME" "CAP_0805-47UF,4V,20%,X6S,C9533A"
					( Origin gPackager )
				)
				( objectStatus "C5P42" )
				( pin "a"
					( attribute "PN" "1"
						( Origin gPackager )
					)
					( objectStatus "C5P42.1" )
				)
				( pin "b"
					( attribute "PN" "2"
						( Origin gPackager )
					)
					( objectStatus "C5P42.2" )
				)
			)
			( gate "@baseboard_fab2_lib.baseboard_fab2(sch_1):page42_i60"
				( attribute "BOM_COST" "PROC_SOCKET"
					( Origin gFrontEnd )
				)
				( attribute "CDS_LIB" "mstr_discrete"
					( Origin gPackager )
				)
				( attribute "CDS_LOCATION" "C5P43"
					( Origin gPackager )
				)
				( attribute "CDS_SEC" "1"
					( Origin gPackager )
				)
				( attribute "LOCATION" "C5P43"
					( Origin gFrontEnd )
				)
				( attribute "MATERIAL" "X6S"
					( Origin gFrontEnd )
				)
				( attribute "PACK_TYPE" "0805"
					( Origin gFrontEnd )
				)
				( attribute "PART_NUMBER" "C95333-006"
					( Origin gFrontEnd )
				)
				( attribute "PHYS_PAGE" "42"
					( Origin gFrontEnd )
				)
				( attribute "ROOM" "PVCCIN_CPU0_DECAP_VR"
					( Origin gFrontEnd )
				)
				( attribute "ROT" "0"
					( Origin gFrontEnd )
				)
				( attribute "SEC" "1"
					( Origin gPackager )
				)
				( attribute "TOLERANCE" "20%"
					( Origin gFrontEnd )
				)
				( attribute "VALUE" "47UF"
					( Origin gFrontEnd )
				)
				( attribute "VER" "1"
					( Origin gFrontEnd )
				)
				( attribute "VOLTAGE" "4V"
					( Units "uVoltage" "V" 1.000000)
					( Origin gFrontEnd )
				)
				( attribute "XY" "(-7050,925)"
					( Origin gFrontEnd )
				)
				( attribute "CHIPS_PART_NAME" "CAP"
					( Origin gPackager )
				)
				( attribute "CDS_PART_NAME" "CAP_0805-47UF,4V,20%,X6S,C9533A"
					( Origin gPackager )
				)
				( objectStatus "C5P43" )
				( pin "a"
					( attribute "PN" "1"
						( Origin gPackager )
					)
					( objectStatus "C5P43.1" )
				)
				( pin "b"
					( attribute "PN" "2"
						( Origin gPackager )
					)
					( objectStatus "C5P43.2" )
				)
			)
			( gate "@baseboard_fab2_lib.baseboard_fab2(sch_1):page42_i61"
				( attribute "BOM_COST" "PROC_SOCKET"
					( Origin gFrontEnd )
				)
				( attribute "CDS_LIB" "mstr_discrete"
					( Origin gPackager )
				)
				( attribute "CDS_LOCATION" "C5P44"
					( Origin gPackager )
				)
				( attribute "CDS_SEC" "1"
					( Origin gPackager )
				)
				( attribute "LOCATION" "C5P44"
					( Origin gFrontEnd )
				)
				( attribute "MATERIAL" "X6S"
					( Origin gFrontEnd )
				)
				( attribute "PACK_TYPE" "0805"
					( Origin gFrontEnd )
				)
				( attribute "PART_NUMBER" "C95333-006"
					( Origin gFrontEnd )
				)
				( attribute "PHYS_PAGE" "42"
					( Origin gFrontEnd )
				)
				( attribute "ROOM" "PVCCIN_CPU0_DECAP_VR"
					( Origin gFrontEnd )
				)
				( attribute "ROT" "0"
					( Origin gFrontEnd )
				)
				( attribute "SEC" "1"
					( Origin gPackager )
				)
				( attribute "TOLERANCE" "20%"
					( Origin gFrontEnd )
				)
				( attribute "VALUE" "47UF"
					( Origin gFrontEnd )
				)
				( attribute "VER" "1"
					( Origin gFrontEnd )
				)
				( attribute "VOLTAGE" "4V"
					( Units "uVoltage" "V" 1.000000)
					( Origin gFrontEnd )
				)
				( attribute "XY" "(-7375,925)"
					( Origin gFrontEnd )
				)
				( attribute "CHIPS_PART_NAME" "CAP"
					( Origin gPackager )
				)
				( attribute "CDS_PART_NAME" "CAP_0805-47UF,4V,20%,X6S,C9533A"
					( Origin gPackager )
				)
				( objectStatus "C5P44" )
				( pin "a"
					( attribute "PN" "1"
						( Origin gPackager )
					)
					( objectStatus "C5P44.1" )
				)
				( pin "b"
					( attribute "PN" "2"
						( Origin gPackager )
					)
					( objectStatus "C5P44.2" )
				)
			)
			( gate "@baseboard_fab2_lib.baseboard_fab2(sch_1):page42_i63"
				( attribute "BOM_COST" "PROC_SOCKET"
					( Origin gFrontEnd )
				)
				( attribute "CDS_LIB" "mstr_discrete"
					( Origin gPackager )
				)
				( attribute "CDS_LOCATION" "C5P37"
					( Origin gPackager )
				)
				( attribute "CDS_SEC" "1"
					( Origin gPackager )
				)
				( attribute "LOCATION" "C5P37"
					( Origin gFrontEnd )
				)
				( attribute "MATERIAL" "X6S"
					( Origin gFrontEnd )
				)
				( attribute "PACK_TYPE" "0805"
					( Origin gFrontEnd )
				)
				( attribute "PART_NUMBER" "C95333-006"
					( Origin gFrontEnd )
				)
				( attribute "PHYS_PAGE" "42"
					( Origin gFrontEnd )
				)
				( attribute "ROOM" "PVCCIN_CPU0_DECAP_VR"
					( Origin gFrontEnd )
				)
				( attribute "ROT" "0"
					( Origin gFrontEnd )
				)
				( attribute "SEC" "1"
					( Origin gPackager )
				)
				( attribute "TOLERANCE" "20%"
					( Origin gFrontEnd )
				)
				( attribute "VALUE" "47UF"
					( Origin gFrontEnd )
				)
				( attribute "VER" "1"
					( Origin gFrontEnd )
				)
				( attribute "VOLTAGE" "4V"
					( Units "uVoltage" "V" 1.000000)
					( Origin gFrontEnd )
				)
				( attribute "XY" "(-7725,2225)"
					( Origin gFrontEnd )
				)
				( attribute "CHIPS_PART_NAME" "CAP"
					( Origin gPackager )
				)
				( attribute "CDS_PART_NAME" "CAP_0805-47UF,4V,20%,X6S,C9533A"
					( Origin gPackager )
				)
				( objectStatus "C5P37" )
				( pin "a"
					( attribute "PN" "1"
						( Origin gPackager )
					)
					( objectStatus "C5P37.1" )
				)
				( pin "b"
					( attribute "PN" "2"
						( Origin gPackager )
					)
					( objectStatus "C5P37.2" )
				)
			)
			( gate "@baseboard_fab2_lib.baseboard_fab2(sch_1):page42_i65"
				( attribute "BOM_COST" "PROC_SOCKET"
					( Origin gFrontEnd )
				)
				( attribute "CDS_LIB" "mstr_discrete"
					( Origin gPackager )
				)
				( attribute "CDS_LOCATION" "C5P36"
					( Origin gPackager )
				)
				( attribute "CDS_SEC" "1"
					( Origin gPackager )
				)
				( attribute "LOCATION" "C5P36"
					( Origin gFrontEnd )
				)
				( attribute "MATERIAL" "X6S"
					( Origin gFrontEnd )
				)
				( attribute "PACK_TYPE" "0805"
					( Origin gFrontEnd )
				)
				( attribute "PART_NUMBER" "C95333-006"
					( Origin gFrontEnd )
				)
				( attribute "PHYS_PAGE" "42"
					( Origin gFrontEnd )
				)
				( attribute "ROOM" "PVCCIN_CPU0_DECAP_VR"
					( Origin gFrontEnd )
				)
				( attribute "ROT" "0"
					( Origin gFrontEnd )
				)
				( attribute "SEC" "1"
					( Origin gPackager )
				)
				( attribute "TOLERANCE" "20%"
					( Origin gFrontEnd )
				)
				( attribute "VALUE" "47UF"
					( Origin gFrontEnd )
				)
				( attribute "VER" "1"
					( Origin gFrontEnd )
				)
				( attribute "VOLTAGE" "4V"
					( Units "uVoltage" "V" 1.000000)
					( Origin gFrontEnd )
				)
				( attribute "XY" "(-7725,1575)"
					( Origin gFrontEnd )
				)
				( attribute "CHIPS_PART_NAME" "CAP"
					( Origin gPackager )
				)
				( attribute "CDS_PART_NAME" "CAP_0805-47UF,4V,20%,X6S,C9533A"
					( Origin gPackager )
				)
				( objectStatus "C5P36" )
				( pin "a"
					( attribute "PN" "1"
						( Origin gPackager )
					)
					( objectStatus "C5P36.1" )
				)
				( pin "b"
					( attribute "PN" "2"
						( Origin gPackager )
					)
					( objectStatus "C5P36.2" )
				)
			)
			( gate "@baseboard_fab2_lib.baseboard_fab2(sch_1):page42_i68"
				( attribute "BOM_COST" "PROC_SOCKET"
					( Origin gFrontEnd )
				)
				( attribute "CDS_LIB" "dev_discrete"
					( Origin gPackager )
				)
				( attribute "CDS_LOCATION" "C6D8"
					( Origin gPackager )
				)
				( attribute "CDS_SEC" "1"
					( Origin gPackager )
				)
				( attribute "LOCATION" "C6D8"
					( Origin gFrontEnd )
				)
				( attribute "MATERIAL" "X6S"
					( Origin gFrontEnd )
				)
				( attribute "PACK_TYPE" "0603V"
					( Origin gFrontEnd )
				)
				( attribute "PART_NUMBER" "E15431-004"
					( Origin gFrontEnd )
				)
				( attribute "PHYS_PAGE" "42"
					( Origin gFrontEnd )
				)
				( attribute "ROOM" "PVCCIN_CPU0_DECAP_VR"
					( Origin gFrontEnd )
				)
				( attribute "ROT" "0"
					( Origin gFrontEnd )
				)
				( attribute "SEC" "1"
					( Origin gPackager )
				)
				( attribute "TOLERANCE" "20%"
					( Origin gFrontEnd )
				)
				( attribute "VALUE" "22.0UF"
					( Origin gFrontEnd )
				)
				( attribute "VER" "1"
					( Origin gFrontEnd )
				)
				( attribute "VOLTAGE" "4V"
					( Units "uVoltage" "V" 1.000000)
					( Origin gFrontEnd )
				)
				( attribute "XY" "(-800,4450)"
					( Origin gFrontEnd )
				)
				( attribute "CHIPS_PART_NAME" "CAP_A"
					( Origin gPackager )
				)
				( attribute "CDS_PART_NAME" "CAP_A_0603V-22.0UF,4V,20%,X6S,A"
					( Origin gPackager )
				)
				( objectStatus "C6D8" )
				( pin "a"
					( attribute "PN" "1"
						( Origin gPackager )
					)
					( objectStatus "C6D8.1" )
				)
				( pin "b"
					( attribute "PN" "2"
						( Origin gPackager )
					)
					( objectStatus "C6D8.2" )
				)
			)
			( gate "@baseboard_fab2_lib.baseboard_fab2(sch_1):page42_i69"
				( attribute "BOM_COST" "PROC_SOCKET"
					( Origin gFrontEnd )
				)
				( attribute "CDS_LIB" "dev_discrete"
					( Origin gPackager )
				)
				( attribute "CDS_LOCATION" "C5D38"
					( Origin gPackager )
				)
				( attribute "CDS_SEC" "1"
					( Origin gPackager )
				)
				( attribute "LOCATION" "C5D38"
					( Origin gFrontEnd )
				)
				( attribute "MATERIAL" "X6S"
					( Origin gFrontEnd )
				)
				( attribute "PACK_TYPE" "0603V"
					( Origin gFrontEnd )
				)
				( attribute "PART_NUMBER" "E15431-004"
					( Origin gFrontEnd )
				)
				( attribute "PHYS_PAGE" "42"
					( Origin gFrontEnd )
				)
				( attribute "ROOM" "PVCCIN_CPU0_DECAP_VR"
					( Origin gFrontEnd )
				)
				( attribute "ROT" "0"
					( Origin gFrontEnd )
				)
				( attribute "SEC" "1"
					( Origin gPackager )
				)
				( attribute "TOLERANCE" "20%"
					( Origin gFrontEnd )
				)
				( attribute "VALUE" "22.0UF"
					( Origin gFrontEnd )
				)
				( attribute "VER" "1"
					( Origin gFrontEnd )
				)
				( attribute "VOLTAGE" "4V"
					( Units "uVoltage" "V" 1.000000)
					( Origin gFrontEnd )
				)
				( attribute "XY" "(-1100,4450)"
					( Origin gFrontEnd )
				)
				( attribute "CHIPS_PART_NAME" "CAP_A"
					( Origin gPackager )
				)
				( attribute "CDS_PART_NAME" "CAP_A_0603V-22.0UF,4V,20%,X6S,A"
					( Origin gPackager )
				)
				( objectStatus "C5D38" )
				( pin "a"
					( attribute "PN" "1"
						( Origin gPackager )
					)
					( objectStatus "C5D38.1" )
				)
				( pin "b"
					( attribute "PN" "2"
						( Origin gPackager )
					)
					( objectStatus "C5D38.2" )
				)
			)
			( gate "@baseboard_fab2_lib.baseboard_fab2(sch_1):page42_i70"
				( attribute "BOM_COST" "PROC_SOCKET"
					( Origin gFrontEnd )
				)
				( attribute "CDS_LIB" "dev_discrete"
					( Origin gPackager )
				)
				( attribute "CDS_LOCATION" "C5D37"
					( Origin gPackager )
				)
				( attribute "CDS_SEC" "1"
					( Origin gPackager )
				)
				( attribute "LOCATION" "C5D37"
					( Origin gFrontEnd )
				)
				( attribute "MATERIAL" "X6S"
					( Origin gFrontEnd )
				)
				( attribute "PACK_TYPE" "0603V"
					( Origin gFrontEnd )
				)
				( attribute "PART_NUMBER" "E15431-004"
					( Origin gFrontEnd )
				)
				( attribute "PHYS_PAGE" "42"
					( Origin gFrontEnd )
				)
				( attribute "ROOM" "PVCCIN_CPU0_DECAP_VR"
					( Origin gFrontEnd )
				)
				( attribute "ROT" "0"
					( Origin gFrontEnd )
				)
				( attribute "SEC" "1"
					( Origin gPackager )
				)
				( attribute "TOLERANCE" "20%"
					( Origin gFrontEnd )
				)
				( attribute "VALUE" "22.0UF"
					( Origin gFrontEnd )
				)
				( attribute "VER" "1"
					( Origin gFrontEnd )
				)
				( attribute "VOLTAGE" "4V"
					( Units "uVoltage" "V" 1.000000)
					( Origin gFrontEnd )
				)
				( attribute "XY" "(-1400,4475)"
					( Origin gFrontEnd )
				)
				( attribute "CHIPS_PART_NAME" "CAP_A"
					( Origin gPackager )
				)
				( attribute "CDS_PART_NAME" "CAP_A_0603V-22.0UF,4V,20%,X6S,A"
					( Origin gPackager )
				)
				( objectStatus "C5D37" )
				( pin "a"
					( attribute "PN" "1"
						( Origin gPackager )
					)
					( objectStatus "C5D37.1" )
				)
				( pin "b"
					( attribute "PN" "2"
						( Origin gPackager )
					)
					( objectStatus "C5D37.2" )
				)
			)
			( gate "@baseboard_fab2_lib.baseboard_fab2(sch_1):page42_i72"
				( attribute "BOM_COST" "PROC_SOCKET"
					( Origin gFrontEnd )
				)
				( attribute "CDS_LIB" "dev_discrete"
					( Origin gPackager )
				)
				( attribute "CDS_LOCATION" "C6D7"
					( Origin gPackager )
				)
				( attribute "CDS_SEC" "1"
					( Origin gPackager )
				)
				( attribute "LOCATION" "C6D7"
					( Origin gFrontEnd )
				)
				( attribute "MATERIAL" "X6S"
					( Origin gFrontEnd )
				)
				( attribute "PACK_TYPE" "0603V"
					( Origin gFrontEnd )
				)
				( attribute "PART_NUMBER" "E15431-004"
					( Origin gFrontEnd )
				)
				( attribute "PHYS_PAGE" "42"
					( Origin gFrontEnd )
				)
				( attribute "ROOM" "PVCCIN_CPU0_DECAP_VR"
					( Origin gFrontEnd )
				)
				( attribute "ROT" "0"
					( Origin gFrontEnd )
				)
				( attribute "SEC" "1"
					( Origin gPackager )
				)
				( attribute "TOLERANCE" "20%"
					( Origin gFrontEnd )
				)
				( attribute "VALUE" "22.0UF"
					( Origin gFrontEnd )
				)
				( attribute "VER" "1"
					( Origin gFrontEnd )
				)
				( attribute "VOLTAGE" "4V"
					( Units "uVoltage" "V" 1.000000)
					( Origin gFrontEnd )
				)
				( attribute "XY" "(-3375,3800)"
					( Origin gFrontEnd )
				)
				( attribute "CHIPS_PART_NAME" "CAP_A"
					( Origin gPackager )
				)
				( attribute "CDS_PART_NAME" "CAP_A_0603V-22.0UF,4V,20%,X6S,A"
					( Origin gPackager )
				)
				( objectStatus "C6D7" )
				( pin "a"
					( attribute "PN" "1"
						( Origin gPackager )
					)
					( objectStatus "C6D7.1" )
				)
				( pin "b"
					( attribute "PN" "2"
						( Origin gPackager )
					)
					( objectStatus "C6D7.2" )
				)
			)
			( gate "@baseboard_fab2_lib.baseboard_fab2(sch_1):page42_i74"
				( attribute "BOM_COST" "PROC_SOCKET"
					( Origin gFrontEnd )
				)
				( attribute "CDS_LIB" "dev_discrete"
					( Origin gPackager )
				)
				( attribute "CDS_LOCATION" "C6D4"
					( Origin gPackager )
				)
				( attribute "CDS_SEC" "1"
					( Origin gPackager )
				)
				( attribute "LOCATION" "C6D4"
					( Origin gFrontEnd )
				)
				( attribute "MATERIAL" "X6S"
					( Origin gFrontEnd )
				)
				( attribute "PACK_TYPE" "0603V"
					( Origin gFrontEnd )
				)
				( attribute "PART_NUMBER" "E15431-004"
					( Origin gFrontEnd )
				)
				( attribute "PHYS_PAGE" "42"
					( Origin gFrontEnd )
				)
				( attribute "ROOM" "PVCCIN_CPU0_DECAP_VR"
					( Origin gFrontEnd )
				)
				( attribute "ROT" "0"
					( Origin gFrontEnd )
				)
				( attribute "SEC" "1"
					( Origin gPackager )
				)
				( attribute "TOLERANCE" "20%"
					( Origin gFrontEnd )
				)
				( attribute "VALUE" "22.0UF"
					( Origin gFrontEnd )
				)
				( attribute "VER" "1"
					( Origin gFrontEnd )
				)
				( attribute "VOLTAGE" "4V"
					( Units "uVoltage" "V" 1.000000)
					( Origin gFrontEnd )
				)
				( attribute "XY" "(-3600,3800)"
					( Origin gFrontEnd )
				)
				( attribute "CHIPS_PART_NAME" "CAP_A"
					( Origin gPackager )
				)
				( attribute "CDS_PART_NAME" "CAP_A_0603V-22.0UF,4V,20%,X6S,A"
					( Origin gPackager )
				)
				( objectStatus "C6D4" )
				( pin "a"
					( attribute "PN" "1"
						( Origin gPackager )
					)
					( objectStatus "C6D4.1" )
				)
				( pin "b"
					( attribute "PN" "2"
						( Origin gPackager )
					)
					( objectStatus "C6D4.2" )
				)
			)
			( gate "@baseboard_fab2_lib.baseboard_fab2(sch_1):page42_i75"
				( attribute "BOM_COST" "PROC_SOCKET"
					( Origin gFrontEnd )
				)
				( attribute "CDS_LIB" "dev_discrete"
					( Origin gPackager )
				)
				( attribute "CDS_LOCATION" "C6D5"
					( Origin gPackager )
				)
				( attribute "CDS_SEC" "1"
					( Origin gPackager )
				)
				( attribute "LOCATION" "C6D5"
					( Origin gFrontEnd )
				)
				( attribute "MATERIAL" "X6S"
					( Origin gFrontEnd )
				)
				( attribute "PACK_TYPE" "0603V"
					( Origin gFrontEnd )
				)
				( attribute "PART_NUMBER" "E15431-004"
					( Origin gFrontEnd )
				)
				( attribute "PHYS_PAGE" "42"
					( Origin gFrontEnd )
				)
				( attribute "ROOM" "PVCCIN_CPU0_DECAP_VR"
					( Origin gFrontEnd )
				)
				( attribute "ROT" "0"
					( Origin gFrontEnd )
				)
				( attribute "SEC" "1"
					( Origin gPackager )
				)
				( attribute "TOLERANCE" "20%"
					( Origin gFrontEnd )
				)
				( attribute "VALUE" "22.0UF"
					( Origin gFrontEnd )
				)
				( attribute "VER" "1"
					( Origin gFrontEnd )
				)
				( attribute "VOLTAGE" "4V"
					( Units "uVoltage" "V" 1.000000)
					( Origin gFrontEnd )
				)
				( attribute "XY" "(-1700,4450)"
					( Origin gFrontEnd )
				)
				( attribute "CHIPS_PART_NAME" "CAP_A"
					( Origin gPackager )
				)
				( attribute "CDS_PART_NAME" "CAP_A_0603V-22.0UF,4V,20%,X6S,A"
					( Origin gPackager )
				)
				( objectStatus "C6D5" )
				( pin "a"
					( attribute "PN" "1"
						( Origin gPackager )
					)
					( objectStatus "C6D5.1" )
				)
				( pin "b"
					( attribute "PN" "2"
						( Origin gPackager )
					)
					( objectStatus "C6D5.2" )
				)
			)
			( gate "@baseboard_fab2_lib.baseboard_fab2(sch_1):page42_i77"
				( attribute "BOM_COST" "PROC_SOCKET"
					( Origin gFrontEnd )
				)
				( attribute "CDS_LIB" "dev_discrete"
					( Origin gPackager )
				)
				( attribute "CDS_LOCATION" "C6D2"
					( Origin gPackager )
				)
				( attribute "CDS_SEC" "1"
					( Origin gPackager )
				)
				( attribute "LOCATION" "C6D2"
					( Origin gFrontEnd )
				)
				( attribute "MATERIAL" "X6S"
					( Origin gFrontEnd )
				)
				( attribute "PACK_TYPE" "0603V"
					( Origin gFrontEnd )
				)
				( attribute "PART_NUMBER" "E15431-004"
					( Origin gFrontEnd )
				)
				( attribute "PHYS_PAGE" "42"
					( Origin gFrontEnd )
				)
				( attribute "ROOM" "PVCCIN_CPU0_DECAP_VR"
					( Origin gFrontEnd )
				)
				( attribute "ROT" "0"
					( Origin gFrontEnd )
				)
				( attribute "SEC" "1"
					( Origin gPackager )
				)
				( attribute "TOLERANCE" "20%"
					( Origin gFrontEnd )
				)
				( attribute "VALUE" "22.0UF"
					( Origin gFrontEnd )
				)
				( attribute "VER" "1"
					( Origin gFrontEnd )
				)
				( attribute "VOLTAGE" "4V"
					( Units "uVoltage" "V" 1.000000)
					( Origin gFrontEnd )
				)
				( attribute "XY" "(-2000,4475)"
					( Origin gFrontEnd )
				)
				( attribute "CHIPS_PART_NAME" "CAP_A"
					( Origin gPackager )
				)
				( attribute "CDS_PART_NAME" "CAP_A_0603V-22.0UF,4V,20%,X6S,A"
					( Origin gPackager )
				)
				( objectStatus "C6D2" )
				( pin "a"
					( attribute "PN" "1"
						( Origin gPackager )
					)
					( objectStatus "C6D2.1" )
				)
				( pin "b"
					( attribute "PN" "2"
						( Origin gPackager )
					)
					( objectStatus "C6D2.2" )
				)
			)
			( gate "@baseboard_fab2_lib.baseboard_fab2(sch_1):page42_i80"
				( attribute "BOM_COST" "PROC_SOCKET"
					( Origin gFrontEnd )
				)
				( attribute "CDS_LIB" "dev_discrete"
					( Origin gPackager )
				)
				( attribute "CDS_LOCATION" "C6D3"
					( Origin gPackager )
				)
				( attribute "CDS_SEC" "1"
					( Origin gPackager )
				)
				( attribute "LOCATION" "C6D3"
					( Origin gFrontEnd )
				)
				( attribute "MATERIAL" "X6S"
					( Origin gFrontEnd )
				)
				( attribute "PACK_TYPE" "0603V"
					( Origin gFrontEnd )
				)
				( attribute "PART_NUMBER" "E15431-004"
					( Origin gFrontEnd )
				)
				( attribute "PHYS_PAGE" "42"
					( Origin gFrontEnd )
				)
				( attribute "ROOM" "PVCCIN_CPU0_DECAP_VR"
					( Origin gFrontEnd )
				)
				( attribute "ROT" "0"
					( Origin gFrontEnd )
				)
				( attribute "SEC" "1"
					( Origin gPackager )
				)
				( attribute "TOLERANCE" "20%"
					( Origin gFrontEnd )
				)
				( attribute "VALUE" "22.0UF"
					( Origin gFrontEnd )
				)
				( attribute "VER" "1"
					( Origin gFrontEnd )
				)
				( attribute "VOLTAGE" "4V"
					( Units "uVoltage" "V" 1.000000)
					( Origin gFrontEnd )
				)
				( attribute "XY" "(-3825,3800)"
					( Origin gFrontEnd )
				)
				( attribute "CHIPS_PART_NAME" "CAP_A"
					( Origin gPackager )
				)
				( attribute "CDS_PART_NAME" "CAP_A_0603V-22.0UF,4V,20%,X6S,A"
					( Origin gPackager )
				)
				( objectStatus "C6D3" )
				( pin "a"
					( attribute "PN" "1"
						( Origin gPackager )
					)
					( objectStatus "C6D3.1" )
				)
				( pin "b"
					( attribute "PN" "2"
						( Origin gPackager )
					)
					( objectStatus "C6D3.2" )
				)
			)
			( gate "@baseboard_fab2_lib.baseboard_fab2(sch_1):page42_i81"
				( attribute "BOM_COST" "PROC_SOCKET"
					( Origin gFrontEnd )
				)
				( attribute "CDS_LIB" "dev_discrete"
					( Origin gPackager )
				)
				( attribute "CDS_LOCATION" "C6D6"
					( Origin gPackager )
				)
				( attribute "CDS_SEC" "1"
					( Origin gPackager )
				)
				( attribute "LOCATION" "C6D6"
					( Origin gFrontEnd )
				)
				( attribute "MATERIAL" "X6S"
					( Origin gFrontEnd )
				)
				( attribute "PACK_TYPE" "0603V"
					( Origin gFrontEnd )
				)
				( attribute "PART_NUMBER" "E15431-004"
					( Origin gFrontEnd )
				)
				( attribute "PHYS_PAGE" "42"
					( Origin gFrontEnd )
				)
				( attribute "ROOM" "PVCCIN_CPU0_DECAP_VR"
					( Origin gFrontEnd )
				)
				( attribute "ROT" "0"
					( Origin gFrontEnd )
				)
				( attribute "SEC" "1"
					( Origin gPackager )
				)
				( attribute "TOLERANCE" "20%"
					( Origin gFrontEnd )
				)
				( attribute "VALUE" "22.0UF"
					( Origin gFrontEnd )
				)
				( attribute "VER" "1"
					( Origin gFrontEnd )
				)
				( attribute "VOLTAGE" "4V"
					( Units "uVoltage" "V" 1.000000)
					( Origin gFrontEnd )
				)
				( attribute "XY" "(-4075,3775)"
					( Origin gFrontEnd )
				)
				( attribute "CHIPS_PART_NAME" "CAP_A"
					( Origin gPackager )
				)
				( attribute "CDS_PART_NAME" "CAP_A_0603V-22.0UF,4V,20%,X6S,A"
					( Origin gPackager )
				)
				( objectStatus "C6D6" )
				( pin "a"
					( attribute "PN" "1"
						( Origin gPackager )
					)
					( objectStatus "C6D6.1" )
				)
				( pin "b"
					( attribute "PN" "2"
						( Origin gPackager )
					)
					( objectStatus "C6D6.2" )
				)
			)
			( gate "@baseboard_fab2_lib.baseboard_fab2(sch_1):page42_i83"
				( attribute "BOM_COST" "PROC_SOCKET"
					( Origin gFrontEnd )
				)
				( attribute "CDS_LIB" "dev_discrete"
					( Origin gPackager )
				)
				( attribute "CDS_LOCATION" "C5D51"
					( Origin gPackager )
				)
				( attribute "CDS_SEC" "1"
					( Origin gPackager )
				)
				( attribute "LOCATION" "C5D51"
					( Origin gFrontEnd )
				)
				( attribute "MATERIAL" "X6S"
					( Origin gFrontEnd )
				)
				( attribute "PACK_TYPE" "0603V"
					( Origin gFrontEnd )
				)
				( attribute "PART_NUMBER" "E15431-004"
					( Origin gFrontEnd )
				)
				( attribute "PHYS_PAGE" "42"
					( Origin gFrontEnd )
				)
				( attribute "ROOM" "PVCCIN_CPU0_DECAP_VR"
					( Origin gFrontEnd )
				)
				( attribute "ROT" "0"
					( Origin gFrontEnd )
				)
				( attribute "SEC" "1"
					( Origin gPackager )
				)
				( attribute "TOLERANCE" "20%"
					( Origin gFrontEnd )
				)
				( attribute "VALUE" "22.0UF"
					( Origin gFrontEnd )
				)
				( attribute "VER" "1"
					( Origin gFrontEnd )
				)
				( attribute "VOLTAGE" "4V"
					( Units "uVoltage" "V" 1.000000)
					( Origin gFrontEnd )
				)
				( attribute "XY" "(-2825,4475)"
					( Origin gFrontEnd )
				)
				( attribute "CHIPS_PART_NAME" "CAP_A"
					( Origin gPackager )
				)
				( attribute "CDS_PART_NAME" "CAP_A_0603V-22.0UF,4V,20%,X6S,A"
					( Origin gPackager )
				)
				( objectStatus "C5D51" )
				( pin "a"
					( attribute "PN" "1"
						( Origin gPackager )
					)
					( objectStatus "C5D51.1" )
				)
				( pin "b"
					( attribute "PN" "2"
						( Origin gPackager )
					)
					( objectStatus "C5D51.2" )
				)
			)
			( gate "@baseboard_fab2_lib.baseboard_fab2(sch_1):page42_i88"
				( attribute "BOM_COST" "PROC_SOCKET"
					( Origin gFrontEnd )
				)
				( attribute "CDS_LIB" "dev_discrete"
					( Origin gPackager )
				)
				( attribute "CDS_LOCATION" "C5D21"
					( Origin gPackager )
				)
				( attribute "CDS_SEC" "1"
					( Origin gPackager )
				)
				( attribute "LOCATION" "C5D21"
					( Origin gFrontEnd )
				)
				( attribute "MATERIAL" "X6S"
					( Origin gFrontEnd )
				)
				( attribute "PACK_TYPE" "0603V"
					( Origin gFrontEnd )
				)
				( attribute "PART_NUMBER" "E15431-004"
					( Origin gFrontEnd )
				)
				( attribute "PHYS_PAGE" "42"
					( Origin gFrontEnd )
				)
				( attribute "ROOM" "PVCCIN_CPU0_DECAP_VR"
					( Origin gFrontEnd )
				)
				( attribute "ROT" "0"
					( Origin gFrontEnd )
				)
				( attribute "SEC" "1"
					( Origin gPackager )
				)
				( attribute "TOLERANCE" "20%"
					( Origin gFrontEnd )
				)
				( attribute "VALUE" "22.0UF"
					( Origin gFrontEnd )
				)
				( attribute "VER" "1"
					( Origin gFrontEnd )
				)
				( attribute "VOLTAGE" "4V"
					( Units "uVoltage" "V" 1.000000)
					( Origin gFrontEnd )
				)
				( attribute "XY" "(-3075,4450)"
					( Origin gFrontEnd )
				)
				( attribute "CHIPS_PART_NAME" "CAP_A"
					( Origin gPackager )
				)
				( attribute "CDS_PART_NAME" "CAP_A_0603V-22.0UF,4V,20%,X6S,A"
					( Origin gPackager )
				)
				( objectStatus "C5D21" )
				( pin "a"
					( attribute "PN" "1"
						( Origin gPackager )
					)
					( objectStatus "C5D21.1" )
				)
				( pin "b"
					( attribute "PN" "2"
						( Origin gPackager )
					)
					( objectStatus "C5D21.2" )
				)
			)
			( gate "@baseboard_fab2_lib.baseboard_fab2(sch_1):page42_i89"
				( attribute "BOM_COST" "PROC_SOCKET"
					( Origin gFrontEnd )
				)
				( attribute "CDS_LIB" "dev_discrete"
					( Origin gPackager )
				)
				( attribute "CDS_LOCATION" "C5D50"
					( Origin gPackager )
				)
				( attribute "CDS_SEC" "1"
					( Origin gPackager )
				)
				( attribute "LOCATION" "C5D50"
					( Origin gFrontEnd )
				)
				( attribute "MATERIAL" "X6S"
					( Origin gFrontEnd )
				)
				( attribute "PACK_TYPE" "0603V"
					( Origin gFrontEnd )
				)
				( attribute "PART_NUMBER" "E15431-004"
					( Origin gFrontEnd )
				)
				( attribute "PHYS_PAGE" "42"
					( Origin gFrontEnd )
				)
				( attribute "ROOM" "PVCCIN_CPU0_DECAP_VR"
					( Origin gFrontEnd )
				)
				( attribute "ROT" "0"
					( Origin gFrontEnd )
				)
				( attribute "SEC" "1"
					( Origin gPackager )
				)
				( attribute "TOLERANCE" "20%"
					( Origin gFrontEnd )
				)
				( attribute "VALUE" "22.0UF"
					( Origin gFrontEnd )
				)
				( attribute "VER" "1"
					( Origin gFrontEnd )
				)
				( attribute "VOLTAGE" "4V"
					( Units "uVoltage" "V" 1.000000)
					( Origin gFrontEnd )
				)
				( attribute "XY" "(-3350,4475)"
					( Origin gFrontEnd )
				)
				( attribute "CHIPS_PART_NAME" "CAP_A"
					( Origin gPackager )
				)
				( attribute "CDS_PART_NAME" "CAP_A_0603V-22.0UF,4V,20%,X6S,A"
					( Origin gPackager )
				)
				( objectStatus "C5D50" )
				( pin "a"
					( attribute "PN" "1"
						( Origin gPackager )
					)
					( objectStatus "C5D50.1" )
				)
				( pin "b"
					( attribute "PN" "2"
						( Origin gPackager )
					)
					( objectStatus "C5D50.2" )
				)
			)
			( gate "@baseboard_fab2_lib.baseboard_fab2(sch_1):page42_i90"
				( attribute "BOM_COST" "PROC_SOCKET"
					( Origin gFrontEnd )
				)
				( attribute "CDS_LIB" "dev_discrete"
					( Origin gPackager )
				)
				( attribute "CDS_LOCATION" "C5D48"
					( Origin gPackager )
				)
				( attribute "CDS_SEC" "1"
					( Origin gPackager )
				)
				( attribute "LOCATION" "C5D48"
					( Origin gFrontEnd )
				)
				( attribute "MATERIAL" "X6S"
					( Origin gFrontEnd )
				)
				( attribute "PACK_TYPE" "0603V"
					( Origin gFrontEnd )
				)
				( attribute "PART_NUMBER" "E15431-004"
					( Origin gFrontEnd )
				)
				( attribute "PHYS_PAGE" "42"
					( Origin gFrontEnd )
				)
				( attribute "ROOM" "PVCCIN_CPU0_DECAP_VR"
					( Origin gFrontEnd )
				)
				( attribute "ROT" "0"
					( Origin gFrontEnd )
				)
				( attribute "SEC" "1"
					( Origin gPackager )
				)
				( attribute "TOLERANCE" "20%"
					( Origin gFrontEnd )
				)
				( attribute "VALUE" "22.0UF"
					( Origin gFrontEnd )
				)
				( attribute "VER" "1"
					( Origin gFrontEnd )
				)
				( attribute "VOLTAGE" "4V"
					( Units "uVoltage" "V" 1.000000)
					( Origin gFrontEnd )
				)
				( attribute "XY" "(-3625,4475)"
					( Origin gFrontEnd )
				)
				( attribute "CHIPS_PART_NAME" "CAP_A"
					( Origin gPackager )
				)
				( attribute "CDS_PART_NAME" "CAP_A_0603V-22.0UF,4V,20%,X6S,A"
					( Origin gPackager )
				)
				( objectStatus "C5D48" )
				( pin "a"
					( attribute "PN" "1"
						( Origin gPackager )
					)
					( objectStatus "C5D48.1" )
				)
				( pin "b"
					( attribute "PN" "2"
						( Origin gPackager )
					)
					( objectStatus "C5D48.2" )
				)
			)
			( gate "@baseboard_fab2_lib.baseboard_fab2(sch_1):page42_i91"
				( attribute "BOM_COST" "PROC_SOCKET"
					( Origin gFrontEnd )
				)
				( attribute "CDS_LIB" "mstr_discrete"
					( Origin gPackager )
				)
				( attribute "CDS_LOCATION" "C5D13"
					( Origin gPackager )
				)
				( attribute "CDS_SEC" "1"
					( Origin gPackager )
				)
				( attribute "LOCATION" "C5D13"
					( Origin gFrontEnd )
				)
				( attribute "MATERIAL" "X6S"
					( Origin gFrontEnd )
				)
				( attribute "PACK_TYPE" "0603LF"
					( Origin gFrontEnd )
				)
				( attribute "PART_NUMBER" "E15431-001"
					( Origin gFrontEnd )
				)
				( attribute "PHYS_PAGE" "42"
					( Origin gFrontEnd )
				)
				( attribute "ROOM" "PVCCIN_CPU0_DECAP_VR"
					( Origin gFrontEnd )
				)
				( attribute "ROT" "0"
					( Origin gFrontEnd )
				)
				( attribute "SEC" "1"
					( Origin gPackager )
				)
				( attribute "TOLERANCE" "20%"
					( Origin gFrontEnd )
				)
				( attribute "VALUE" "10UF"
					( Origin gFrontEnd )
				)
				( attribute "VER" "1"
					( Origin gFrontEnd )
				)
				( attribute "VOLTAGE" "4V"
					( Units "uVoltage" "V" 1.000000)
					( Origin gFrontEnd )
				)
				( attribute "XY" "(-2875,3125)"
					( Origin gFrontEnd )
				)
				( attribute "CHIPS_PART_NAME" "CAP"
					( Origin gPackager )
				)
				( attribute "CDS_PART_NAME" "CAP_0603LF-10UF,4V,20%,X6S,E15A"
					( Origin gPackager )
				)
				( objectStatus "C5D13" )
				( pin "a"
					( attribute "PN" "1"
						( Origin gPackager )
					)
					( objectStatus "C5D13.1" )
				)
				( pin "b"
					( attribute "PN" "2"
						( Origin gPackager )
					)
					( objectStatus "C5D13.2" )
				)
			)
			( gate "@baseboard_fab2_lib.baseboard_fab2(sch_1):page42_i93"
				( attribute "BOM_COST" "PROC_SOCKET"
					( Origin gFrontEnd )
				)
				( attribute "CDS_LIB" "mstr_discrete"
					( Origin gPackager )
				)
				( attribute "CDS_LOCATION" "C5D11"
					( Origin gPackager )
				)
				( attribute "CDS_SEC" "1"
					( Origin gPackager )
				)
				( attribute "LOCATION" "C5D11"
					( Origin gFrontEnd )
				)
				( attribute "MATERIAL" "X6S"
					( Origin gFrontEnd )
				)
				( attribute "PACK_TYPE" "0603LF"
					( Origin gFrontEnd )
				)
				( attribute "PART_NUMBER" "E15431-001"
					( Origin gFrontEnd )
				)
				( attribute "PHYS_PAGE" "42"
					( Origin gFrontEnd )
				)
				( attribute "ROOM" "PVCCIN_CPU0_DECAP_VR"
					( Origin gFrontEnd )
				)
				( attribute "ROT" "0"
					( Origin gFrontEnd )
				)
				( attribute "SEC" "1"
					( Origin gPackager )
				)
				( attribute "TOLERANCE" "20%"
					( Origin gFrontEnd )
				)
				( attribute "VALUE" "10UF"
					( Origin gFrontEnd )
				)
				( attribute "VER" "1"
					( Origin gFrontEnd )
				)
				( attribute "VOLTAGE" "4V"
					( Units "uVoltage" "V" 1.000000)
					( Origin gFrontEnd )
				)
				( attribute "XY" "(-3275,3125)"
					( Origin gFrontEnd )
				)
				( attribute "CHIPS_PART_NAME" "CAP"
					( Origin gPackager )
				)
				( attribute "CDS_PART_NAME" "CAP_0603LF-10UF,4V,20%,X6S,E15A"
					( Origin gPackager )
				)
				( objectStatus "C5D11" )
				( pin "a"
					( attribute "PN" "1"
						( Origin gPackager )
					)
					( objectStatus "C5D11.1" )
				)
				( pin "b"
					( attribute "PN" "2"
						( Origin gPackager )
					)
					( objectStatus "C5D11.2" )
				)
			)
			( gate "@baseboard_fab2_lib.baseboard_fab2(sch_1):page42_i94"
				( attribute "BOM_COST" "PROC_SOCKET"
					( Origin gFrontEnd )
				)
				( attribute "CDS_LIB" "mstr_discrete"
					( Origin gPackager )
				)
				( attribute "CDS_LOCATION" "C5D12"
					( Origin gPackager )
				)
				( attribute "CDS_SEC" "1"
					( Origin gPackager )
				)
				( attribute "LOCATION" "C5D12"
					( Origin gFrontEnd )
				)
				( attribute "MATERIAL" "X6S"
					( Origin gFrontEnd )
				)
				( attribute "PACK_TYPE" "0603LF"
					( Origin gFrontEnd )
				)
				( attribute "PART_NUMBER" "E15431-001"
					( Origin gFrontEnd )
				)
				( attribute "PHYS_PAGE" "42"
					( Origin gFrontEnd )
				)
				( attribute "ROOM" "PVCCIN_CPU0_DECAP_VR"
					( Origin gFrontEnd )
				)
				( attribute "ROT" "0"
					( Origin gFrontEnd )
				)
				( attribute "SEC" "1"
					( Origin gPackager )
				)
				( attribute "TOLERANCE" "20%"
					( Origin gFrontEnd )
				)
				( attribute "VALUE" "10UF"
					( Origin gFrontEnd )
				)
				( attribute "VER" "1"
					( Origin gFrontEnd )
				)
				( attribute "VOLTAGE" "4V"
					( Units "uVoltage" "V" 1.000000)
					( Origin gFrontEnd )
				)
				( attribute "XY" "(-3675,3150)"
					( Origin gFrontEnd )
				)
				( attribute "CHIPS_PART_NAME" "CAP"
					( Origin gPackager )
				)
				( attribute "CDS_PART_NAME" "CAP_0603LF-10UF,4V,20%,X6S,E15A"
					( Origin gPackager )
				)
				( objectStatus "C5D12" )
				( pin "a"
					( attribute "PN" "1"
						( Origin gPackager )
					)
					( objectStatus "C5D12.1" )
				)
				( pin "b"
					( attribute "PN" "2"
						( Origin gPackager )
					)
					( objectStatus "C5D12.2" )
				)
			)
			( gate "@baseboard_fab2_lib.baseboard_fab2(sch_1):page42_i98"
				( attribute "BOM_COST" "PROC_SOCKET"
					( Origin gFrontEnd )
				)
				( attribute "CDS_LIB" "dev_discrete"
					( Origin gPackager )
				)
				( attribute "CDS_LOCATION" "C5D23"
					( Origin gPackager )
				)
				( attribute "CDS_SEC" "1"
					( Origin gPackager )
				)
				( attribute "LOCATION" "C5D23"
					( Origin gFrontEnd )
				)
				( attribute "MATERIAL" "X6S"
					( Origin gFrontEnd )
				)
				( attribute "PACK_TYPE" "0603V"
					( Origin gFrontEnd )
				)
				( attribute "PART_NUMBER" "E15431-004"
					( Origin gFrontEnd )
				)
				( attribute "PHYS_PAGE" "42"
					( Origin gFrontEnd )
				)
				( attribute "ROOM" "PVCCIN_CPU0_DECAP_VR"
					( Origin gFrontEnd )
				)
				( attribute "ROT" "0"
					( Origin gFrontEnd )
				)
				( attribute "SEC" "1"
					( Origin gPackager )
				)
				( attribute "TOLERANCE" "20%"
					( Origin gFrontEnd )
				)
				( attribute "VALUE" "22.0UF"
					( Origin gFrontEnd )
				)
				( attribute "VER" "1"
					( Origin gFrontEnd )
				)
				( attribute "VOLTAGE" "4V"
					( Units "uVoltage" "V" 1.000000)
					( Origin gFrontEnd )
				)
				( attribute "XY" "(-3875,4475)"
					( Origin gFrontEnd )
				)
				( attribute "CHIPS_PART_NAME" "CAP_A"
					( Origin gPackager )
				)
				( attribute "CDS_PART_NAME" "CAP_A_0603V-22.0UF,4V,20%,X6S,A"
					( Origin gPackager )
				)
				( objectStatus "C5D23" )
				( pin "a"
					( attribute "PN" "1"
						( Origin gPackager )
					)
					( objectStatus "C5D23.1" )
				)
				( pin "b"
					( attribute "PN" "2"
						( Origin gPackager )
					)
					( objectStatus "C5D23.2" )
				)
			)
			( gate "@baseboard_fab2_lib.baseboard_fab2(sch_1):page42_i100"
				( attribute "BOM_COST" "PROC_SOCKET"
					( Origin gFrontEnd )
				)
				( attribute "CDS_LIB" "dev_discrete"
					( Origin gPackager )
				)
				( attribute "CDS_LOCATION" "C5D28"
					( Origin gPackager )
				)
				( attribute "CDS_SEC" "1"
					( Origin gPackager )
				)
				( attribute "LOCATION" "C5D28"
					( Origin gFrontEnd )
				)
				( attribute "MATERIAL" "X6S"
					( Origin gFrontEnd )
				)
				( attribute "PACK_TYPE" "0603V"
					( Origin gFrontEnd )
				)
				( attribute "PART_NUMBER" "E15431-004"
					( Origin gFrontEnd )
				)
				( attribute "PHYS_PAGE" "42"
					( Origin gFrontEnd )
				)
				( attribute "ROOM" "PVCCIN_CPU0_DECAP_VR"
					( Origin gFrontEnd )
				)
				( attribute "ROT" "0"
					( Origin gFrontEnd )
				)
				( attribute "SEC" "1"
					( Origin gPackager )
				)
				( attribute "TOLERANCE" "20%"
					( Origin gFrontEnd )
				)
				( attribute "VALUE" "22.0UF"
					( Origin gFrontEnd )
				)
				( attribute "VER" "1"
					( Origin gFrontEnd )
				)
				( attribute "VOLTAGE" "4V"
					( Units "uVoltage" "V" 1.000000)
					( Origin gFrontEnd )
				)
				( attribute "XY" "(-4700,3775)"
					( Origin gFrontEnd )
				)
				( attribute "CHIPS_PART_NAME" "CAP_A"
					( Origin gPackager )
				)
				( attribute "CDS_PART_NAME" "CAP_A_0603V-22.0UF,4V,20%,X6S,A"
					( Origin gPackager )
				)
				( objectStatus "C5D28" )
				( pin "a"
					( attribute "PN" "1"
						( Origin gPackager )
					)
					( objectStatus "C5D28.1" )
				)
				( pin "b"
					( attribute "PN" "2"
						( Origin gPackager )
					)
					( objectStatus "C5D28.2" )
				)
			)
			( gate "@baseboard_fab2_lib.baseboard_fab2(sch_1):page42_i102"
				( attribute "BOM_COST" "PROC_SOCKET"
					( Origin gFrontEnd )
				)
				( attribute "CDS_LIB" "dev_discrete"
					( Origin gPackager )
				)
				( attribute "CDS_LOCATION" "C5D29"
					( Origin gPackager )
				)
				( attribute "CDS_SEC" "1"
					( Origin gPackager )
				)
				( attribute "LOCATION" "C5D29"
					( Origin gFrontEnd )
				)
				( attribute "MATERIAL" "X6S"
					( Origin gFrontEnd )
				)
				( attribute "PACK_TYPE" "0603V"
					( Origin gFrontEnd )
				)
				( attribute "PART_NUMBER" "E15431-004"
					( Origin gFrontEnd )
				)
				( attribute "PHYS_PAGE" "42"
					( Origin gFrontEnd )
				)
				( attribute "ROOM" "PVCCIN_CPU0_DECAP_VR"
					( Origin gFrontEnd )
				)
				( attribute "ROT" "0"
					( Origin gFrontEnd )
				)
				( attribute "SEC" "1"
					( Origin gPackager )
				)
				( attribute "TOLERANCE" "20%"
					( Origin gFrontEnd )
				)
				( attribute "VALUE" "22.0UF"
					( Origin gFrontEnd )
				)
				( attribute "VER" "1"
					( Origin gFrontEnd )
				)
				( attribute "VOLTAGE" "4V"
					( Units "uVoltage" "V" 1.000000)
					( Origin gFrontEnd )
				)
				( attribute "XY" "(-4700,4450)"
					( Origin gFrontEnd )
				)
				( attribute "CHIPS_PART_NAME" "CAP_A"
					( Origin gPackager )
				)
				( attribute "CDS_PART_NAME" "CAP_A_0603V-22.0UF,4V,20%,X6S,A"
					( Origin gPackager )
				)
				( objectStatus "C5D29" )
				( pin "a"
					( attribute "PN" "1"
						( Origin gPackager )
					)
					( objectStatus "C5D29.1" )
				)
				( pin "b"
					( attribute "PN" "2"
						( Origin gPackager )
					)
					( objectStatus "C5D29.2" )
				)
			)
			( gate "@baseboard_fab2_lib.baseboard_fab2(sch_1):page42_i103"
				( attribute "BOM_COST" "PROC_SOCKET"
					( Origin gFrontEnd )
				)
				( attribute "CDS_LIB" "dev_discrete"
					( Origin gPackager )
				)
				( attribute "CDS_LOCATION" "C5D32"
					( Origin gPackager )
				)
				( attribute "CDS_SEC" "1"
					( Origin gPackager )
				)
				( attribute "LOCATION" "C5D32"
					( Origin gFrontEnd )
				)
				( attribute "MATERIAL" "X6S"
					( Origin gFrontEnd )
				)
				( attribute "PACK_TYPE" "0603V"
					( Origin gFrontEnd )
				)
				( attribute "PART_NUMBER" "E15431-004"
					( Origin gFrontEnd )
				)
				( attribute "PHYS_PAGE" "42"
					( Origin gFrontEnd )
				)
				( attribute "ROOM" "PVCCIN_CPU0_DECAP_VR"
					( Origin gFrontEnd )
				)
				( attribute "ROT" "0"
					( Origin gFrontEnd )
				)
				( attribute "SEC" "1"
					( Origin gPackager )
				)
				( attribute "TOLERANCE" "20%"
					( Origin gFrontEnd )
				)
				( attribute "VALUE" "22.0UF"
					( Origin gFrontEnd )
				)
				( attribute "VER" "1"
					( Origin gFrontEnd )
				)
				( attribute "VOLTAGE" "4V"
					( Units "uVoltage" "V" 1.000000)
					( Origin gFrontEnd )
				)
				( attribute "XY" "(-5000,4475)"
					( Origin gFrontEnd )
				)
				( attribute "CHIPS_PART_NAME" "CAP_A"
					( Origin gPackager )
				)
				( attribute "CDS_PART_NAME" "CAP_A_0603V-22.0UF,4V,20%,X6S,A"
					( Origin gPackager )
				)
				( objectStatus "C5D32" )
				( pin "a"
					( attribute "PN" "1"
						( Origin gPackager )
					)
					( objectStatus "C5D32.1" )
				)
				( pin "b"
					( attribute "PN" "2"
						( Origin gPackager )
					)
					( objectStatus "C5D32.2" )
				)
			)
			( gate "@baseboard_fab2_lib.baseboard_fab2(sch_1):page42_i104"
				( attribute "BOM_COST" "PROC_SOCKET"
					( Origin gFrontEnd )
				)
				( attribute "CDS_LIB" "dev_discrete"
					( Origin gPackager )
				)
				( attribute "CDS_LOCATION" "C5D47"
					( Origin gPackager )
				)
				( attribute "CDS_SEC" "1"
					( Origin gPackager )
				)
				( attribute "LOCATION" "C5D47"
					( Origin gFrontEnd )
				)
				( attribute "MATERIAL" "X6S"
					( Origin gFrontEnd )
				)
				( attribute "PACK_TYPE" "0603V"
					( Origin gFrontEnd )
				)
				( attribute "PART_NUMBER" "E15431-004"
					( Origin gFrontEnd )
				)
				( attribute "PHYS_PAGE" "42"
					( Origin gFrontEnd )
				)
				( attribute "ROOM" "PVCCIN_CPU0_DECAP_VR"
					( Origin gFrontEnd )
				)
				( attribute "ROT" "0"
					( Origin gFrontEnd )
				)
				( attribute "SEC" "1"
					( Origin gPackager )
				)
				( attribute "TOLERANCE" "20%"
					( Origin gFrontEnd )
				)
				( attribute "VALUE" "22.0UF"
					( Origin gFrontEnd )
				)
				( attribute "VER" "1"
					( Origin gFrontEnd )
				)
				( attribute "VOLTAGE" "4V"
					( Units "uVoltage" "V" 1.000000)
					( Origin gFrontEnd )
				)
				( attribute "XY" "(-5325,4475)"
					( Origin gFrontEnd )
				)
				( attribute "CHIPS_PART_NAME" "CAP_A"
					( Origin gPackager )
				)
				( attribute "CDS_PART_NAME" "CAP_A_0603V-22.0UF,4V,20%,X6S,A"
					( Origin gPackager )
				)
				( objectStatus "C5D47" )
				( pin "a"
					( attribute "PN" "1"
						( Origin gPackager )
					)
					( objectStatus "C5D47.1" )
				)
				( pin "b"
					( attribute "PN" "2"
						( Origin gPackager )
					)
					( objectStatus "C5D47.2" )
				)
			)
			( gate "@baseboard_fab2_lib.baseboard_fab2(sch_1):page42_i106"
				( attribute "BOM_COST" "PROC_SOCKET"
					( Origin gFrontEnd )
				)
				( attribute "CDS_LIB" "dev_discrete"
					( Origin gPackager )
				)
				( attribute "CDS_LOCATION" "C5D31"
					( Origin gPackager )
				)
				( attribute "CDS_SEC" "1"
					( Origin gPackager )
				)
				( attribute "LOCATION" "C5D31"
					( Origin gFrontEnd )
				)
				( attribute "MATERIAL" "X6S"
					( Origin gFrontEnd )
				)
				( attribute "PACK_TYPE" "0603V"
					( Origin gFrontEnd )
				)
				( attribute "PART_NUMBER" "E15431-004"
					( Origin gFrontEnd )
				)
				( attribute "PHYS_PAGE" "42"
					( Origin gFrontEnd )
				)
				( attribute "ROOM" "PVCCIN_CPU0_DECAP_VR"
					( Origin gFrontEnd )
				)
				( attribute "ROT" "0"
					( Origin gFrontEnd )
				)
				( attribute "SEC" "1"
					( Origin gPackager )
				)
				( attribute "TOLERANCE" "20%"
					( Origin gFrontEnd )
				)
				( attribute "VALUE" "22.0UF"
					( Origin gFrontEnd )
				)
				( attribute "VER" "1"
					( Origin gFrontEnd )
				)
				( attribute "VOLTAGE" "4V"
					( Units "uVoltage" "V" 1.000000)
					( Origin gFrontEnd )
				)
				( attribute "XY" "(-5000,3775)"
					( Origin gFrontEnd )
				)
				( attribute "CHIPS_PART_NAME" "CAP_A"
					( Origin gPackager )
				)
				( attribute "CDS_PART_NAME" "CAP_A_0603V-22.0UF,4V,20%,X6S,A"
					( Origin gPackager )
				)
				( objectStatus "C5D31" )
				( pin "a"
					( attribute "PN" "1"
						( Origin gPackager )
					)
					( objectStatus "C5D31.1" )
				)
				( pin "b"
					( attribute "PN" "2"
						( Origin gPackager )
					)
					( objectStatus "C5D31.2" )
				)
			)
			( gate "@baseboard_fab2_lib.baseboard_fab2(sch_1):page42_i107"
				( attribute "BOM_COST" "PROC_SOCKET"
					( Origin gFrontEnd )
				)
				( attribute "CDS_LIB" "dev_discrete"
					( Origin gPackager )
				)
				( attribute "CDS_LOCATION" "C5D46"
					( Origin gPackager )
				)
				( attribute "CDS_SEC" "1"
					( Origin gPackager )
				)
				( attribute "LOCATION" "C5D46"
					( Origin gFrontEnd )
				)
				( attribute "MATERIAL" "X6S"
					( Origin gFrontEnd )
				)
				( attribute "PACK_TYPE" "0603V"
					( Origin gFrontEnd )
				)
				( attribute "PART_NUMBER" "E15431-004"
					( Origin gFrontEnd )
				)
				( attribute "PHYS_PAGE" "42"
					( Origin gFrontEnd )
				)
				( attribute "ROOM" "PVCCIN_CPU0_DECAP_VR"
					( Origin gFrontEnd )
				)
				( attribute "ROT" "0"
					( Origin gFrontEnd )
				)
				( attribute "SEC" "1"
					( Origin gPackager )
				)
				( attribute "TOLERANCE" "20%"
					( Origin gFrontEnd )
				)
				( attribute "VALUE" "22.0UF"
					( Origin gFrontEnd )
				)
				( attribute "VER" "1"
					( Origin gFrontEnd )
				)
				( attribute "VOLTAGE" "4V"
					( Units "uVoltage" "V" 1.000000)
					( Origin gFrontEnd )
				)
				( attribute "XY" "(-5325,3800)"
					( Origin gFrontEnd )
				)
				( attribute "CHIPS_PART_NAME" "CAP_A"
					( Origin gPackager )
				)
				( attribute "CDS_PART_NAME" "CAP_A_0603V-22.0UF,4V,20%,X6S,A"
					( Origin gPackager )
				)
				( objectStatus "C5D46" )
				( pin "a"
					( attribute "PN" "1"
						( Origin gPackager )
					)
					( objectStatus "C5D46.1" )
				)
				( pin "b"
					( attribute "PN" "2"
						( Origin gPackager )
					)
					( objectStatus "C5D46.2" )
				)
			)
			( gate "@baseboard_fab2_lib.baseboard_fab2(sch_1):page42_i108"
				( attribute "BOM_COST" "PROC_SOCKET"
					( Origin gFrontEnd )
				)
				( attribute "CDS_LIB" "mstr_discrete"
					( Origin gPackager )
				)
				( attribute "CDS_LOCATION" "C5D10"
					( Origin gPackager )
				)
				( attribute "CDS_SEC" "1"
					( Origin gPackager )
				)
				( attribute "LOCATION" "C5D10"
					( Origin gFrontEnd )
				)
				( attribute "MATERIAL" "X6S"
					( Origin gFrontEnd )
				)
				( attribute "PACK_TYPE" "0603LF"
					( Origin gFrontEnd )
				)
				( attribute "PART_NUMBER" "E15431-001"
					( Origin gFrontEnd )
				)
				( attribute "PHYS_PAGE" "42"
					( Origin gFrontEnd )
				)
				( attribute "ROOM" "PVCCIN_CPU0_DECAP_VR"
					( Origin gFrontEnd )
				)
				( attribute "ROT" "0"
					( Origin gFrontEnd )
				)
				( attribute "SEC" "1"
					( Origin gPackager )
				)
				( attribute "TOLERANCE" "20%"
					( Origin gFrontEnd )
				)
				( attribute "VALUE" "10UF"
					( Origin gFrontEnd )
				)
				( attribute "VER" "1"
					( Origin gFrontEnd )
				)
				( attribute "VOLTAGE" "4V"
					( Units "uVoltage" "V" 1.000000)
					( Origin gFrontEnd )
				)
				( attribute "XY" "(-4075,3125)"
					( Origin gFrontEnd )
				)
				( attribute "CHIPS_PART_NAME" "CAP"
					( Origin gPackager )
				)
				( attribute "CDS_PART_NAME" "CAP_0603LF-10UF,4V,20%,X6S,E15A"
					( Origin gPackager )
				)
				( objectStatus "C5D10" )
				( pin "a"
					( attribute "PN" "1"
						( Origin gPackager )
					)
					( objectStatus "C5D10.1" )
				)
				( pin "b"
					( attribute "PN" "2"
						( Origin gPackager )
					)
					( objectStatus "C5D10.2" )
				)
			)
			( gate "@baseboard_fab2_lib.baseboard_fab2(sch_1):page42_i109"
				( attribute "BOM_COST" "PROC_SOCKET"
					( Origin gFrontEnd )
				)
				( attribute "CDS_LIB" "dev_discrete"
					( Origin gPackager )
				)
				( attribute "CDS_LOCATION" "C5D27"
					( Origin gPackager )
				)
				( attribute "CDS_SEC" "1"
					( Origin gPackager )
				)
				( attribute "LOCATION" "C5D27"
					( Origin gFrontEnd )
				)
				( attribute "MATERIAL" "X6S"
					( Origin gFrontEnd )
				)
				( attribute "PACK_TYPE" "0603V"
					( Origin gFrontEnd )
				)
				( attribute "PART_NUMBER" "E15431-004"
					( Origin gFrontEnd )
				)
				( attribute "PHYS_PAGE" "42"
					( Origin gFrontEnd )
				)
				( attribute "ROOM" "PVCCIN_CPU0_DECAP_VR"
					( Origin gFrontEnd )
				)
				( attribute "ROT" "0"
					( Origin gFrontEnd )
				)
				( attribute "SEC" "1"
					( Origin gPackager )
				)
				( attribute "TOLERANCE" "20%"
					( Origin gFrontEnd )
				)
				( attribute "VALUE" "22.0UF"
					( Origin gFrontEnd )
				)
				( attribute "VER" "1"
					( Origin gFrontEnd )
				)
				( attribute "VOLTAGE" "4V"
					( Units "uVoltage" "V" 1.000000)
					( Origin gFrontEnd )
				)
				( attribute "XY" "(-4750,3175)"
					( Origin gFrontEnd )
				)
				( attribute "CHIPS_PART_NAME" "CAP_A"
					( Origin gPackager )
				)
				( attribute "CDS_PART_NAME" "CAP_A_0603V-22.0UF,4V,20%,X6S,A"
					( Origin gPackager )
				)
				( objectStatus "C5D27" )
				( pin "a"
					( attribute "PN" "1"
						( Origin gPackager )
					)
					( objectStatus "C5D27.1" )
				)
				( pin "b"
					( attribute "PN" "2"
						( Origin gPackager )
					)
					( objectStatus "C5D27.2" )
				)
			)
			( gate "@baseboard_fab2_lib.baseboard_fab2(sch_1):page42_i111"
				( attribute "BOM_COST" "PROC_SOCKET"
					( Origin gFrontEnd )
				)
				( attribute "CDS_LIB" "dev_discrete"
					( Origin gPackager )
				)
				( attribute "CDS_LOCATION" "C5D30"
					( Origin gPackager )
				)
				( attribute "CDS_SEC" "1"
					( Origin gPackager )
				)
				( attribute "LOCATION" "C5D30"
					( Origin gFrontEnd )
				)
				( attribute "MATERIAL" "X6S"
					( Origin gFrontEnd )
				)
				( attribute "PACK_TYPE" "0603V"
					( Origin gFrontEnd )
				)
				( attribute "PART_NUMBER" "E15431-004"
					( Origin gFrontEnd )
				)
				( attribute "PHYS_PAGE" "42"
					( Origin gFrontEnd )
				)
				( attribute "ROOM" "PVCCIN_CPU0_DECAP_VR"
					( Origin gFrontEnd )
				)
				( attribute "ROT" "0"
					( Origin gFrontEnd )
				)
				( attribute "SEC" "1"
					( Origin gPackager )
				)
				( attribute "TOLERANCE" "20%"
					( Origin gFrontEnd )
				)
				( attribute "VALUE" "22.0UF"
					( Origin gFrontEnd )
				)
				( attribute "VER" "1"
					( Origin gFrontEnd )
				)
				( attribute "VOLTAGE" "4V"
					( Units "uVoltage" "V" 1.000000)
					( Origin gFrontEnd )
				)
				( attribute "XY" "(-5075,3150)"
					( Origin gFrontEnd )
				)
				( attribute "CHIPS_PART_NAME" "CAP_A"
					( Origin gPackager )
				)
				( attribute "CDS_PART_NAME" "CAP_A_0603V-22.0UF,4V,20%,X6S,A"
					( Origin gPackager )
				)
				( objectStatus "C5D30" )
				( pin "a"
					( attribute "PN" "1"
						( Origin gPackager )
					)
					( objectStatus "C5D30.1" )
				)
				( pin "b"
					( attribute "PN" "2"
						( Origin gPackager )
					)
					( objectStatus "C5D30.2" )
				)
			)
			( gate "@baseboard_fab2_lib.baseboard_fab2(sch_1):page42_i112"
				( attribute "BOM_COST" "PROC_SOCKET"
					( Origin gFrontEnd )
				)
				( attribute "CDS_LIB" "dev_discrete"
					( Origin gPackager )
				)
				( attribute "CDS_LOCATION" "C5D60"
					( Origin gPackager )
				)
				( attribute "CDS_SEC" "1"
					( Origin gPackager )
				)
				( attribute "LOCATION" "C5D60"
					( Origin gFrontEnd )
				)
				( attribute "MATERIAL" "X6S"
					( Origin gFrontEnd )
				)
				( attribute "PACK_TYPE" "0603V"
					( Origin gFrontEnd )
				)
				( attribute "PART_NUMBER" "E15431-004"
					( Origin gFrontEnd )
				)
				( attribute "PHYS_PAGE" "42"
					( Origin gFrontEnd )
				)
				( attribute "ROOM" "PVCCIN_CPU0_DECAP_VR"
					( Origin gFrontEnd )
				)
				( attribute "ROT" "0"
					( Origin gFrontEnd )
				)
				( attribute "SEC" "1"
					( Origin gPackager )
				)
				( attribute "TOLERANCE" "20%"
					( Origin gFrontEnd )
				)
				( attribute "VALUE" "22.0UF"
					( Origin gFrontEnd )
				)
				( attribute "VER" "1"
					( Origin gFrontEnd )
				)
				( attribute "VOLTAGE" "4V"
					( Units "uVoltage" "V" 1.000000)
					( Origin gFrontEnd )
				)
				( attribute "XY" "(-5350,3150)"
					( Origin gFrontEnd )
				)
				( attribute "CHIPS_PART_NAME" "CAP_A"
					( Origin gPackager )
				)
				( attribute "CDS_PART_NAME" "CAP_A_0603V-22.0UF,4V,20%,X6S,A"
					( Origin gPackager )
				)
				( objectStatus "C5D60" )
				( pin "a"
					( attribute "PN" "1"
						( Origin gPackager )
					)
					( objectStatus "C5D60.1" )
				)
				( pin "b"
					( attribute "PN" "2"
						( Origin gPackager )
					)
					( objectStatus "C5D60.2" )
				)
			)
			( gate "@baseboard_fab2_lib.baseboard_fab2(sch_1):page42_i113"
				( attribute "BOM_COST" "PROC_SOCKET"
					( Origin gFrontEnd )
				)
				( attribute "CDS_LIB" "dev_discrete"
					( Origin gPackager )
				)
				( attribute "CDS_LOCATION" "C5D61"
					( Origin gPackager )
				)
				( attribute "CDS_SEC" "1"
					( Origin gPackager )
				)
				( attribute "LOCATION" "C5D61"
					( Origin gFrontEnd )
				)
				( attribute "MATERIAL" "X6S"
					( Origin gFrontEnd )
				)
				( attribute "PACK_TYPE" "0603V"
					( Origin gFrontEnd )
				)
				( attribute "PART_NUMBER" "E15431-004"
					( Origin gFrontEnd )
				)
				( attribute "PHYS_PAGE" "42"
					( Origin gFrontEnd )
				)
				( attribute "ROOM" "PVCCIN_CPU0_DECAP_VR"
					( Origin gFrontEnd )
				)
				( attribute "ROT" "0"
					( Origin gFrontEnd )
				)
				( attribute "SEC" "1"
					( Origin gPackager )
				)
				( attribute "TOLERANCE" "20%"
					( Origin gFrontEnd )
				)
				( attribute "VALUE" "22.0UF"
					( Origin gFrontEnd )
				)
				( attribute "VER" "1"
					( Origin gFrontEnd )
				)
				( attribute "VOLTAGE" "4V"
					( Units "uVoltage" "V" 1.000000)
					( Origin gFrontEnd )
				)
				( attribute "XY" "(-5625,3175)"
					( Origin gFrontEnd )
				)
				( attribute "CHIPS_PART_NAME" "CAP_A"
					( Origin gPackager )
				)
				( attribute "CDS_PART_NAME" "CAP_A_0603V-22.0UF,4V,20%,X6S,A"
					( Origin gPackager )
				)
				( objectStatus "C5D61" )
				( pin "a"
					( attribute "PN" "1"
						( Origin gPackager )
					)
					( objectStatus "C5D61.1" )
				)
				( pin "b"
					( attribute "PN" "2"
						( Origin gPackager )
					)
					( objectStatus "C5D61.2" )
				)
			)
			( gate "@baseboard_fab2_lib.baseboard_fab2(sch_1):page42_i114"
				( attribute "BOM_COST" "PROC_SOCKET"
					( Origin gFrontEnd )
				)
				( attribute "CDS_LIB" "dev_discrete"
					( Origin gPackager )
				)
				( attribute "CDS_LOCATION" "C5D41"
					( Origin gPackager )
				)
				( attribute "CDS_SEC" "1"
					( Origin gPackager )
				)
				( attribute "LOCATION" "C5D41"
					( Origin gFrontEnd )
				)
				( attribute "MATERIAL" "X6S"
					( Origin gFrontEnd )
				)
				( attribute "PACK_TYPE" "0603V"
					( Origin gFrontEnd )
				)
				( attribute "PART_NUMBER" "E15431-004"
					( Origin gFrontEnd )
				)
				( attribute "PHYS_PAGE" "42"
					( Origin gFrontEnd )
				)
				( attribute "ROOM" "PVCCIN_CPU0_DECAP_VR"
					( Origin gFrontEnd )
				)
				( attribute "ROT" "0"
					( Origin gFrontEnd )
				)
				( attribute "SEC" "1"
					( Origin gPackager )
				)
				( attribute "TOLERANCE" "20%"
					( Origin gFrontEnd )
				)
				( attribute "VALUE" "22.0UF"
					( Origin gFrontEnd )
				)
				( attribute "VER" "1"
					( Origin gFrontEnd )
				)
				( attribute "VOLTAGE" "4V"
					( Units "uVoltage" "V" 1.000000)
					( Origin gFrontEnd )
				)
				( attribute "XY" "(-5625,3800)"
					( Origin gFrontEnd )
				)
				( attribute "CHIPS_PART_NAME" "CAP_A"
					( Origin gPackager )
				)
				( attribute "CDS_PART_NAME" "CAP_A_0603V-22.0UF,4V,20%,X6S,A"
					( Origin gPackager )
				)
				( objectStatus "C5D41" )
				( pin "a"
					( attribute "PN" "1"
						( Origin gPackager )
					)
					( objectStatus "C5D41.1" )
				)
				( pin "b"
					( attribute "PN" "2"
						( Origin gPackager )
					)
					( objectStatus "C5D41.2" )
				)
			)
			( gate "@baseboard_fab2_lib.baseboard_fab2(sch_1):page42_i115"
				( attribute "BOM_COST" "PROC_SOCKET"
					( Origin gFrontEnd )
				)
				( attribute "CDS_LIB" "dev_discrete"
					( Origin gPackager )
				)
				( attribute "CDS_LOCATION" "C5D40"
					( Origin gPackager )
				)
				( attribute "CDS_SEC" "1"
					( Origin gPackager )
				)
				( attribute "LOCATION" "C5D40"
					( Origin gFrontEnd )
				)
				( attribute "MATERIAL" "X6S"
					( Origin gFrontEnd )
				)
				( attribute "PACK_TYPE" "0603V"
					( Origin gFrontEnd )
				)
				( attribute "PART_NUMBER" "E15431-004"
					( Origin gFrontEnd )
				)
				( attribute "PHYS_PAGE" "42"
					( Origin gFrontEnd )
				)
				( attribute "ROOM" "PVCCIN_CPU0_DECAP_VR"
					( Origin gFrontEnd )
				)
				( attribute "ROT" "0"
					( Origin gFrontEnd )
				)
				( attribute "SEC" "1"
					( Origin gPackager )
				)
				( attribute "TOLERANCE" "20%"
					( Origin gFrontEnd )
				)
				( attribute "VALUE" "22.0UF"
					( Origin gFrontEnd )
				)
				( attribute "VER" "1"
					( Origin gFrontEnd )
				)
				( attribute "VOLTAGE" "4V"
					( Units "uVoltage" "V" 1.000000)
					( Origin gFrontEnd )
				)
				( attribute "XY" "(-5625,4475)"
					( Origin gFrontEnd )
				)
				( attribute "CHIPS_PART_NAME" "CAP_A"
					( Origin gPackager )
				)
				( attribute "CDS_PART_NAME" "CAP_A_0603V-22.0UF,4V,20%,X6S,A"
					( Origin gPackager )
				)
				( objectStatus "C5D40" )
				( pin "a"
					( attribute "PN" "1"
						( Origin gPackager )
					)
					( objectStatus "C5D40.1" )
				)
				( pin "b"
					( attribute "PN" "2"
						( Origin gPackager )
					)
					( objectStatus "C5D40.2" )
				)
			)
			( gate "@baseboard_fab2_lib.baseboard_fab2(sch_1):page42_i117"
				( attribute "BOM_COST" "PROC_SOCKET"
					( Origin gFrontEnd )
				)
				( attribute "CDS_LIB" "dev_discrete"
					( Origin gPackager )
				)
				( attribute "CDS_LOCATION" "C5D14"
					( Origin gPackager )
				)
				( attribute "CDS_SEC" "1"
					( Origin gPackager )
				)
				( attribute "LOCATION" "C5D14"
					( Origin gFrontEnd )
				)
				( attribute "MATERIAL" "X6S"
					( Origin gFrontEnd )
				)
				( attribute "PACK_TYPE" "0603V"
					( Origin gFrontEnd )
				)
				( attribute "PART_NUMBER" "E15431-004"
					( Origin gFrontEnd )
				)
				( attribute "PHYS_PAGE" "42"
					( Origin gFrontEnd )
				)
				( attribute "ROOM" "PVCCIN_CPU0_DECAP_VR"
					( Origin gFrontEnd )
				)
				( attribute "ROT" "0"
					( Origin gFrontEnd )
				)
				( attribute "SEC" "1"
					( Origin gPackager )
				)
				( attribute "TOLERANCE" "20%"
					( Origin gFrontEnd )
				)
				( attribute "VALUE" "22.0UF"
					( Origin gFrontEnd )
				)
				( attribute "VER" "1"
					( Origin gFrontEnd )
				)
				( attribute "VOLTAGE" "4V"
					( Units "uVoltage" "V" 1.000000)
					( Origin gFrontEnd )
				)
				( attribute "XY" "(-5950,4475)"
					( Origin gFrontEnd )
				)
				( attribute "CHIPS_PART_NAME" "CAP_A"
					( Origin gPackager )
				)
				( attribute "CDS_PART_NAME" "CAP_A_0603V-22.0UF,4V,20%,X6S,A"
					( Origin gPackager )
				)
				( objectStatus "C5D14" )
				( pin "a"
					( attribute "PN" "1"
						( Origin gPackager )
					)
					( objectStatus "C5D14.1" )
				)
				( pin "b"
					( attribute "PN" "2"
						( Origin gPackager )
					)
					( objectStatus "C5D14.2" )
				)
			)
			( gate "@baseboard_fab2_lib.baseboard_fab2(sch_1):page42_i118"
				( attribute "BOM_COST" "PROC_SOCKET"
					( Origin gFrontEnd )
				)
				( attribute "CDS_LIB" "dev_discrete"
					( Origin gPackager )
				)
				( attribute "CDS_LOCATION" "C5D17"
					( Origin gPackager )
				)
				( attribute "CDS_SEC" "1"
					( Origin gPackager )
				)
				( attribute "LOCATION" "C5D17"
					( Origin gFrontEnd )
				)
				( attribute "MATERIAL" "X6S"
					( Origin gFrontEnd )
				)
				( attribute "PACK_TYPE" "0603V"
					( Origin gFrontEnd )
				)
				( attribute "PART_NUMBER" "E15431-004"
					( Origin gFrontEnd )
				)
				( attribute "PHYS_PAGE" "42"
					( Origin gFrontEnd )
				)
				( attribute "ROOM" "PVCCIN_CPU0_DECAP_VR"
					( Origin gFrontEnd )
				)
				( attribute "ROT" "0"
					( Origin gFrontEnd )
				)
				( attribute "SEC" "1"
					( Origin gPackager )
				)
				( attribute "TOLERANCE" "20%"
					( Origin gFrontEnd )
				)
				( attribute "VALUE" "22.0UF"
					( Origin gFrontEnd )
				)
				( attribute "VER" "1"
					( Origin gFrontEnd )
				)
				( attribute "VOLTAGE" "4V"
					( Units "uVoltage" "V" 1.000000)
					( Origin gFrontEnd )
				)
				( attribute "XY" "(-6350,4475)"
					( Origin gFrontEnd )
				)
				( attribute "CHIPS_PART_NAME" "CAP_A"
					( Origin gPackager )
				)
				( attribute "CDS_PART_NAME" "CAP_A_0603V-22.0UF,4V,20%,X6S,A"
					( Origin gPackager )
				)
				( objectStatus "C5D17" )
				( pin "a"
					( attribute "PN" "1"
						( Origin gPackager )
					)
					( objectStatus "C5D17.1" )
				)
				( pin "b"
					( attribute "PN" "2"
						( Origin gPackager )
					)
					( objectStatus "C5D17.2" )
				)
			)
			( gate "@baseboard_fab2_lib.baseboard_fab2(sch_1):page42_i120"
				( attribute "BOM_COST" "PROC_SOCKET"
					( Origin gFrontEnd )
				)
				( attribute "CDS_LIB" "dev_discrete"
					( Origin gPackager )
				)
				( attribute "CDS_LOCATION" "C5D58"
					( Origin gPackager )
				)
				( attribute "CDS_SEC" "1"
					( Origin gPackager )
				)
				( attribute "LOCATION" "C5D58"
					( Origin gFrontEnd )
				)
				( attribute "MATERIAL" "X6S"
					( Origin gFrontEnd )
				)
				( attribute "PACK_TYPE" "0603V"
					( Origin gFrontEnd )
				)
				( attribute "PART_NUMBER" "E15431-004"
					( Origin gFrontEnd )
				)
				( attribute "PHYS_PAGE" "42"
					( Origin gFrontEnd )
				)
				( attribute "ROOM" "PVCCIN_CPU0_DECAP_VR"
					( Origin gFrontEnd )
				)
				( attribute "ROT" "0"
					( Origin gFrontEnd )
				)
				( attribute "SEC" "1"
					( Origin gPackager )
				)
				( attribute "TOLERANCE" "20%"
					( Origin gFrontEnd )
				)
				( attribute "VALUE" "22.0UF"
					( Origin gFrontEnd )
				)
				( attribute "VER" "1"
					( Origin gFrontEnd )
				)
				( attribute "VOLTAGE" "4V"
					( Units "uVoltage" "V" 1.000000)
					( Origin gFrontEnd )
				)
				( attribute "XY" "(-5925,3800)"
					( Origin gFrontEnd )
				)
				( attribute "CHIPS_PART_NAME" "CAP_A"
					( Origin gPackager )
				)
				( attribute "CDS_PART_NAME" "CAP_A_0603V-22.0UF,4V,20%,X6S,A"
					( Origin gPackager )
				)
				( objectStatus "C5D58" )
				( pin "a"
					( attribute "PN" "1"
						( Origin gPackager )
					)
					( objectStatus "C5D58.1" )
				)
				( pin "b"
					( attribute "PN" "2"
						( Origin gPackager )
					)
					( objectStatus "C5D58.2" )
				)
			)
			( gate "@baseboard_fab2_lib.baseboard_fab2(sch_1):page42_i123"
				( attribute "BOM_COST" "PROC_SOCKET"
					( Origin gFrontEnd )
				)
				( attribute "CDS_LIB" "dev_discrete"
					( Origin gPackager )
				)
				( attribute "CDS_LOCATION" "C5D16"
					( Origin gPackager )
				)
				( attribute "CDS_SEC" "1"
					( Origin gPackager )
				)
				( attribute "LOCATION" "C5D16"
					( Origin gFrontEnd )
				)
				( attribute "MATERIAL" "X6S"
					( Origin gFrontEnd )
				)
				( attribute "PACK_TYPE" "0603V"
					( Origin gFrontEnd )
				)
				( attribute "PART_NUMBER" "E15431-004"
					( Origin gFrontEnd )
				)
				( attribute "PHYS_PAGE" "42"
					( Origin gFrontEnd )
				)
				( attribute "ROOM" "PVCCIN_CPU0_DECAP_VR"
					( Origin gFrontEnd )
				)
				( attribute "ROT" "0"
					( Origin gFrontEnd )
				)
				( attribute "SEC" "1"
					( Origin gPackager )
				)
				( attribute "TOLERANCE" "20%"
					( Origin gFrontEnd )
				)
				( attribute "VALUE" "22.0UF"
					( Origin gFrontEnd )
				)
				( attribute "VER" "1"
					( Origin gFrontEnd )
				)
				( attribute "VOLTAGE" "4V"
					( Units "uVoltage" "V" 1.000000)
					( Origin gFrontEnd )
				)
				( attribute "XY" "(-6300,3800)"
					( Origin gFrontEnd )
				)
				( attribute "CHIPS_PART_NAME" "CAP_A"
					( Origin gPackager )
				)
				( attribute "CDS_PART_NAME" "CAP_A_0603V-22.0UF,4V,20%,X6S,A"
					( Origin gPackager )
				)
				( objectStatus "C5D16" )
				( pin "a"
					( attribute "PN" "1"
						( Origin gPackager )
					)
					( objectStatus "C5D16.1" )
				)
				( pin "b"
					( attribute "PN" "2"
						( Origin gPackager )
					)
					( objectStatus "C5D16.2" )
				)
			)
			( gate "@baseboard_fab2_lib.baseboard_fab2(sch_1):page42_i125"
				( attribute "BOM_COST" "PROC_SOCKET"
					( Origin gFrontEnd )
				)
				( attribute "CDS_LIB" "dev_discrete"
					( Origin gPackager )
				)
				( attribute "CDS_LOCATION" "C5D5"
					( Origin gPackager )
				)
				( attribute "CDS_SEC" "1"
					( Origin gPackager )
				)
				( attribute "LOCATION" "C5D5"
					( Origin gFrontEnd )
				)
				( attribute "MATERIAL" "X6S"
					( Origin gFrontEnd )
				)
				( attribute "PACK_TYPE" "0603V"
					( Origin gFrontEnd )
				)
				( attribute "PART_NUMBER" "E15431-004"
					( Origin gFrontEnd )
				)
				( attribute "PHYS_PAGE" "42"
					( Origin gFrontEnd )
				)
				( attribute "ROOM" "PVCCIN_CPU0_DECAP_VR"
					( Origin gFrontEnd )
				)
				( attribute "ROT" "0"
					( Origin gFrontEnd )
				)
				( attribute "SEC" "1"
					( Origin gPackager )
				)
				( attribute "TOLERANCE" "20%"
					( Origin gFrontEnd )
				)
				( attribute "VALUE" "22.0UF"
					( Origin gFrontEnd )
				)
				( attribute "VER" "1"
					( Origin gFrontEnd )
				)
				( attribute "VOLTAGE" "4V"
					( Units "uVoltage" "V" 1.000000)
					( Origin gFrontEnd )
				)
				( attribute "XY" "(-6675,4475)"
					( Origin gFrontEnd )
				)
				( attribute "CHIPS_PART_NAME" "CAP_A"
					( Origin gPackager )
				)
				( attribute "CDS_PART_NAME" "CAP_A_0603V-22.0UF,4V,20%,X6S,A"
					( Origin gPackager )
				)
				( objectStatus "C5D5" )
				( pin "a"
					( attribute "PN" "1"
						( Origin gPackager )
					)
					( objectStatus "C5D5.1" )
				)
				( pin "b"
					( attribute "PN" "2"
						( Origin gPackager )
					)
					( objectStatus "C5D5.2" )
				)
			)
			( gate "@baseboard_fab2_lib.baseboard_fab2(sch_1):page42_i126"
				( attribute "BOM_COST" "PROC_SOCKET"
					( Origin gFrontEnd )
				)
				( attribute "CDS_LIB" "dev_discrete"
					( Origin gPackager )
				)
				( attribute "CDS_LOCATION" "C5D1"
					( Origin gPackager )
				)
				( attribute "CDS_SEC" "1"
					( Origin gPackager )
				)
				( attribute "LOCATION" "C5D1"
					( Origin gFrontEnd )
				)
				( attribute "MATERIAL" "X6S"
					( Origin gFrontEnd )
				)
				( attribute "PACK_TYPE" "0603V"
					( Origin gFrontEnd )
				)
				( attribute "PART_NUMBER" "E15431-004"
					( Origin gFrontEnd )
				)
				( attribute "PHYS_PAGE" "42"
					( Origin gFrontEnd )
				)
				( attribute "ROOM" "PVCCIN_CPU0_DECAP_VR"
					( Origin gFrontEnd )
				)
				( attribute "ROT" "0"
					( Origin gFrontEnd )
				)
				( attribute "SEC" "1"
					( Origin gPackager )
				)
				( attribute "TOLERANCE" "20%"
					( Origin gFrontEnd )
				)
				( attribute "VALUE" "22.0UF"
					( Origin gFrontEnd )
				)
				( attribute "VER" "1"
					( Origin gFrontEnd )
				)
				( attribute "VOLTAGE" "4V"
					( Units "uVoltage" "V" 1.000000)
					( Origin gFrontEnd )
				)
				( attribute "XY" "(-7050,4475)"
					( Origin gFrontEnd )
				)
				( attribute "CHIPS_PART_NAME" "CAP_A"
					( Origin gPackager )
				)
				( attribute "CDS_PART_NAME" "CAP_A_0603V-22.0UF,4V,20%,X6S,A"
					( Origin gPackager )
				)
				( objectStatus "C5D1" )
				( pin "a"
					( attribute "PN" "1"
						( Origin gPackager )
					)
					( objectStatus "C5D1.1" )
				)
				( pin "b"
					( attribute "PN" "2"
						( Origin gPackager )
					)
					( objectStatus "C5D1.2" )
				)
			)
			( gate "@baseboard_fab2_lib.baseboard_fab2(sch_1):page42_i127"
				( attribute "BOM_COST" "PROC_SOCKET"
					( Origin gFrontEnd )
				)
				( attribute "CDS_LIB" "dev_discrete"
					( Origin gPackager )
				)
				( attribute "CDS_LOCATION" "C5D4"
					( Origin gPackager )
				)
				( attribute "CDS_SEC" "1"
					( Origin gPackager )
				)
				( attribute "LOCATION" "C5D4"
					( Origin gFrontEnd )
				)
				( attribute "MATERIAL" "X6S"
					( Origin gFrontEnd )
				)
				( attribute "PACK_TYPE" "0603V"
					( Origin gFrontEnd )
				)
				( attribute "PART_NUMBER" "E15431-004"
					( Origin gFrontEnd )
				)
				( attribute "PHYS_PAGE" "42"
					( Origin gFrontEnd )
				)
				( attribute "ROOM" "PVCCIN_CPU0_DECAP_VR"
					( Origin gFrontEnd )
				)
				( attribute "ROT" "0"
					( Origin gFrontEnd )
				)
				( attribute "SEC" "1"
					( Origin gPackager )
				)
				( attribute "TOLERANCE" "20%"
					( Origin gFrontEnd )
				)
				( attribute "VALUE" "22.0UF"
					( Origin gFrontEnd )
				)
				( attribute "VER" "1"
					( Origin gFrontEnd )
				)
				( attribute "VOLTAGE" "4V"
					( Units "uVoltage" "V" 1.000000)
					( Origin gFrontEnd )
				)
				( attribute "XY" "(-7375,4475)"
					( Origin gFrontEnd )
				)
				( attribute "CHIPS_PART_NAME" "CAP_A"
					( Origin gPackager )
				)
				( attribute "CDS_PART_NAME" "CAP_A_0603V-22.0UF,4V,20%,X6S,A"
					( Origin gPackager )
				)
				( objectStatus "C5D4" )
				( pin "a"
					( attribute "PN" "1"
						( Origin gPackager )
					)
					( objectStatus "C5D4.1" )
				)
				( pin "b"
					( attribute "PN" "2"
						( Origin gPackager )
					)
					( objectStatus "C5D4.2" )
				)
			)
			( gate "@baseboard_fab2_lib.baseboard_fab2(sch_1):page42_i128"
				( attribute "BOM_COST" "PROC_SOCKET"
					( Origin gFrontEnd )
				)
				( attribute "CDS_LIB" "dev_discrete"
					( Origin gPackager )
				)
				( attribute "CDS_LOCATION" "C5D19"
					( Origin gPackager )
				)
				( attribute "CDS_SEC" "1"
					( Origin gPackager )
				)
				( attribute "LOCATION" "C5D19"
					( Origin gFrontEnd )
				)
				( attribute "MATERIAL" "X6S"
					( Origin gFrontEnd )
				)
				( attribute "PACK_TYPE" "0603V"
					( Origin gFrontEnd )
				)
				( attribute "PART_NUMBER" "E15431-004"
					( Origin gFrontEnd )
				)
				( attribute "PHYS_PAGE" "42"
					( Origin gFrontEnd )
				)
				( attribute "ROOM" "PVCCIN_CPU0_DECAP_VR"
					( Origin gFrontEnd )
				)
				( attribute "ROT" "0"
					( Origin gFrontEnd )
				)
				( attribute "SEC" "1"
					( Origin gPackager )
				)
				( attribute "TOLERANCE" "20%"
					( Origin gFrontEnd )
				)
				( attribute "VALUE" "22.0UF"
					( Origin gFrontEnd )
				)
				( attribute "VER" "1"
					( Origin gFrontEnd )
				)
				( attribute "VOLTAGE" "4V"
					( Units "uVoltage" "V" 1.000000)
					( Origin gFrontEnd )
				)
				( attribute "XY" "(-6650,3800)"
					( Origin gFrontEnd )
				)
				( attribute "CHIPS_PART_NAME" "CAP_A"
					( Origin gPackager )
				)
				( attribute "CDS_PART_NAME" "CAP_A_0603V-22.0UF,4V,20%,X6S,A"
					( Origin gPackager )
				)
				( objectStatus "C5D19" )
				( pin "a"
					( attribute "PN" "1"
						( Origin gPackager )
					)
					( objectStatus "C5D19.1" )
				)
				( pin "b"
					( attribute "PN" "2"
						( Origin gPackager )
					)
					( objectStatus "C5D19.2" )
				)
			)
			( gate "@baseboard_fab2_lib.baseboard_fab2(sch_1):page42_i129"
				( attribute "BOM_COST" "PROC_SOCKET"
					( Origin gFrontEnd )
				)
				( attribute "CDS_LIB" "dev_discrete"
					( Origin gPackager )
				)
				( attribute "CDS_LOCATION" "C5D59"
					( Origin gPackager )
				)
				( attribute "CDS_SEC" "1"
					( Origin gPackager )
				)
				( attribute "LOCATION" "C5D59"
					( Origin gFrontEnd )
				)
				( attribute "MATERIAL" "X6S"
					( Origin gFrontEnd )
				)
				( attribute "PACK_TYPE" "0603V"
					( Origin gFrontEnd )
				)
				( attribute "PART_NUMBER" "E15431-004"
					( Origin gFrontEnd )
				)
				( attribute "PHYS_PAGE" "42"
					( Origin gFrontEnd )
				)
				( attribute "ROOM" "PVCCIN_CPU0_DECAP_VR"
					( Origin gFrontEnd )
				)
				( attribute "ROT" "0"
					( Origin gFrontEnd )
				)
				( attribute "SEC" "1"
					( Origin gPackager )
				)
				( attribute "TOLERANCE" "20%"
					( Origin gFrontEnd )
				)
				( attribute "VALUE" "22.0UF"
					( Origin gFrontEnd )
				)
				( attribute "VER" "1"
					( Origin gFrontEnd )
				)
				( attribute "VOLTAGE" "4V"
					( Units "uVoltage" "V" 1.000000)
					( Origin gFrontEnd )
				)
				( attribute "XY" "(-7000,3800)"
					( Origin gFrontEnd )
				)
				( attribute "CHIPS_PART_NAME" "CAP_A"
					( Origin gPackager )
				)
				( attribute "CDS_PART_NAME" "CAP_A_0603V-22.0UF,4V,20%,X6S,A"
					( Origin gPackager )
				)
				( objectStatus "C5D59" )
				( pin "a"
					( attribute "PN" "1"
						( Origin gPackager )
					)
					( objectStatus "C5D59.1" )
				)
				( pin "b"
					( attribute "PN" "2"
						( Origin gPackager )
					)
					( objectStatus "C5D59.2" )
				)
			)
			( gate "@baseboard_fab2_lib.baseboard_fab2(sch_1):page42_i130"
				( attribute "BOM_COST" "PROC_SOCKET"
					( Origin gFrontEnd )
				)
				( attribute "CDS_LIB" "dev_discrete"
					( Origin gPackager )
				)
				( attribute "CDS_LOCATION" "C5D3"
					( Origin gPackager )
				)
				( attribute "CDS_SEC" "1"
					( Origin gPackager )
				)
				( attribute "LOCATION" "C5D3"
					( Origin gFrontEnd )
				)
				( attribute "MATERIAL" "X6S"
					( Origin gFrontEnd )
				)
				( attribute "PACK_TYPE" "0603V"
					( Origin gFrontEnd )
				)
				( attribute "PART_NUMBER" "E15431-004"
					( Origin gFrontEnd )
				)
				( attribute "PHYS_PAGE" "42"
					( Origin gFrontEnd )
				)
				( attribute "ROOM" "PVCCIN_CPU0_DECAP_VR"
					( Origin gFrontEnd )
				)
				( attribute "ROT" "0"
					( Origin gFrontEnd )
				)
				( attribute "SEC" "1"
					( Origin gPackager )
				)
				( attribute "TOLERANCE" "20%"
					( Origin gFrontEnd )
				)
				( attribute "VALUE" "22.0UF"
					( Origin gFrontEnd )
				)
				( attribute "VER" "1"
					( Origin gFrontEnd )
				)
				( attribute "VOLTAGE" "4V"
					( Units "uVoltage" "V" 1.000000)
					( Origin gFrontEnd )
				)
				( attribute "XY" "(-7325,3800)"
					( Origin gFrontEnd )
				)
				( attribute "CHIPS_PART_NAME" "CAP_A"
					( Origin gPackager )
				)
				( attribute "CDS_PART_NAME" "CAP_A_0603V-22.0UF,4V,20%,X6S,A"
					( Origin gPackager )
				)
				( objectStatus "C5D3" )
				( pin "a"
					( attribute "PN" "1"
						( Origin gPackager )
					)
					( objectStatus "C5D3.1" )
				)
				( pin "b"
					( attribute "PN" "2"
						( Origin gPackager )
					)
					( objectStatus "C5D3.2" )
				)
			)
			( gate "@baseboard_fab2_lib.baseboard_fab2(sch_1):page42_i131"
				( attribute "BOM_COST" "PROC_SOCKET"
					( Origin gFrontEnd )
				)
				( attribute "CDS_LIB" "dev_discrete"
					( Origin gPackager )
				)
				( attribute "CDS_LOCATION" "C5D43"
					( Origin gPackager )
				)
				( attribute "CDS_SEC" "1"
					( Origin gPackager )
				)
				( attribute "LOCATION" "C5D43"
					( Origin gFrontEnd )
				)
				( attribute "MATERIAL" "X6S"
					( Origin gFrontEnd )
				)
				( attribute "PACK_TYPE" "0603V"
					( Origin gFrontEnd )
				)
				( attribute "PART_NUMBER" "E15431-004"
					( Origin gFrontEnd )
				)
				( attribute "PHYS_PAGE" "42"
					( Origin gFrontEnd )
				)
				( attribute "ROOM" "PVCCIN_CPU0_DECAP_VR"
					( Origin gFrontEnd )
				)
				( attribute "ROT" "0"
					( Origin gFrontEnd )
				)
				( attribute "SEC" "1"
					( Origin gPackager )
				)
				( attribute "TOLERANCE" "20%"
					( Origin gFrontEnd )
				)
				( attribute "VALUE" "22.0UF"
					( Origin gFrontEnd )
				)
				( attribute "VER" "1"
					( Origin gFrontEnd )
				)
				( attribute "VOLTAGE" "4V"
					( Units "uVoltage" "V" 1.000000)
					( Origin gFrontEnd )
				)
				( attribute "XY" "(-5900,3150)"
					( Origin gFrontEnd )
				)
				( attribute "CHIPS_PART_NAME" "CAP_A"
					( Origin gPackager )
				)
				( attribute "CDS_PART_NAME" "CAP_A_0603V-22.0UF,4V,20%,X6S,A"
					( Origin gPackager )
				)
				( objectStatus "C5D43" )
				( pin "a"
					( attribute "PN" "1"
						( Origin gPackager )
					)
					( objectStatus "C5D43.1" )
				)
				( pin "b"
					( attribute "PN" "2"
						( Origin gPackager )
					)
					( objectStatus "C5D43.2" )
				)
			)
			( gate "@baseboard_fab2_lib.baseboard_fab2(sch_1):page42_i132"
				( attribute "BOM_COST" "PROC_SOCKET"
					( Origin gFrontEnd )
				)
				( attribute "CDS_LIB" "dev_discrete"
					( Origin gPackager )
				)
				( attribute "CDS_LOCATION" "C5D15"
					( Origin gPackager )
				)
				( attribute "CDS_SEC" "1"
					( Origin gPackager )
				)
				( attribute "LOCATION" "C5D15"
					( Origin gFrontEnd )
				)
				( attribute "MATERIAL" "X6S"
					( Origin gFrontEnd )
				)
				( attribute "PACK_TYPE" "0603V"
					( Origin gFrontEnd )
				)
				( attribute "PART_NUMBER" "E15431-004"
					( Origin gFrontEnd )
				)
				( attribute "PHYS_PAGE" "42"
					( Origin gFrontEnd )
				)
				( attribute "ROOM" "PVCCIN_CPU0_DECAP_VR"
					( Origin gFrontEnd )
				)
				( attribute "ROT" "0"
					( Origin gFrontEnd )
				)
				( attribute "SEC" "1"
					( Origin gPackager )
				)
				( attribute "TOLERANCE" "20%"
					( Origin gFrontEnd )
				)
				( attribute "VALUE" "22.0UF"
					( Origin gFrontEnd )
				)
				( attribute "VER" "1"
					( Origin gFrontEnd )
				)
				( attribute "VOLTAGE" "4V"
					( Units "uVoltage" "V" 1.000000)
					( Origin gFrontEnd )
				)
				( attribute "XY" "(-6250,3175)"
					( Origin gFrontEnd )
				)
				( attribute "CHIPS_PART_NAME" "CAP_A"
					( Origin gPackager )
				)
				( attribute "CDS_PART_NAME" "CAP_A_0603V-22.0UF,4V,20%,X6S,A"
					( Origin gPackager )
				)
				( objectStatus "C5D15" )
				( pin "a"
					( attribute "PN" "1"
						( Origin gPackager )
					)
					( objectStatus "C5D15.1" )
				)
				( pin "b"
					( attribute "PN" "2"
						( Origin gPackager )
					)
					( objectStatus "C5D15.2" )
				)
			)
			( gate "@baseboard_fab2_lib.baseboard_fab2(sch_1):page42_i134"
				( attribute "BOM_COST" "PROC_SOCKET"
					( Origin gFrontEnd )
				)
				( attribute "CDS_LIB" "dev_discrete"
					( Origin gPackager )
				)
				( attribute "CDS_LOCATION" "C5D18"
					( Origin gPackager )
				)
				( attribute "CDS_SEC" "1"
					( Origin gPackager )
				)
				( attribute "LOCATION" "C5D18"
					( Origin gFrontEnd )
				)
				( attribute "MATERIAL" "X6S"
					( Origin gFrontEnd )
				)
				( attribute "PACK_TYPE" "0603V"
					( Origin gFrontEnd )
				)
				( attribute "PART_NUMBER" "E15431-004"
					( Origin gFrontEnd )
				)
				( attribute "PHYS_PAGE" "42"
					( Origin gFrontEnd )
				)
				( attribute "ROOM" "PVCCIN_CPU0_DECAP_VR"
					( Origin gFrontEnd )
				)
				( attribute "ROT" "0"
					( Origin gFrontEnd )
				)
				( attribute "SEC" "1"
					( Origin gPackager )
				)
				( attribute "TOLERANCE" "20%"
					( Origin gFrontEnd )
				)
				( attribute "VALUE" "22.0UF"
					( Origin gFrontEnd )
				)
				( attribute "VER" "1"
					( Origin gFrontEnd )
				)
				( attribute "VOLTAGE" "4V"
					( Units "uVoltage" "V" 1.000000)
					( Origin gFrontEnd )
				)
				( attribute "XY" "(-6600,3150)"
					( Origin gFrontEnd )
				)
				( attribute "CHIPS_PART_NAME" "CAP_A"
					( Origin gPackager )
				)
				( attribute "CDS_PART_NAME" "CAP_A_0603V-22.0UF,4V,20%,X6S,A"
					( Origin gPackager )
				)
				( objectStatus "C5D18" )
				( pin "a"
					( attribute "PN" "1"
						( Origin gPackager )
					)
					( objectStatus "C5D18.1" )
				)
				( pin "b"
					( attribute "PN" "2"
						( Origin gPackager )
					)
					( objectStatus "C5D18.2" )
				)
			)
			( gate "@baseboard_fab2_lib.baseboard_fab2(sch_1):page42_i135"
				( attribute "BOM_COST" "PROC_SOCKET"
					( Origin gFrontEnd )
				)
				( attribute "CDS_LIB" "dev_discrete"
					( Origin gPackager )
				)
				( attribute "CDS_LOCATION" "C5D42"
					( Origin gPackager )
				)
				( attribute "CDS_SEC" "1"
					( Origin gPackager )
				)
				( attribute "LOCATION" "C5D42"
					( Origin gFrontEnd )
				)
				( attribute "MATERIAL" "X6S"
					( Origin gFrontEnd )
				)
				( attribute "PACK_TYPE" "0603V"
					( Origin gFrontEnd )
				)
				( attribute "PART_NUMBER" "E15431-004"
					( Origin gFrontEnd )
				)
				( attribute "PHYS_PAGE" "42"
					( Origin gFrontEnd )
				)
				( attribute "ROOM" "PVCCIN_CPU0_DECAP_VR"
					( Origin gFrontEnd )
				)
				( attribute "ROT" "0"
					( Origin gFrontEnd )
				)
				( attribute "SEC" "1"
					( Origin gPackager )
				)
				( attribute "TOLERANCE" "20%"
					( Origin gFrontEnd )
				)
				( attribute "VALUE" "22.0UF"
					( Origin gFrontEnd )
				)
				( attribute "VER" "1"
					( Origin gFrontEnd )
				)
				( attribute "VOLTAGE" "4V"
					( Units "uVoltage" "V" 1.000000)
					( Origin gFrontEnd )
				)
				( attribute "XY" "(-6950,3175)"
					( Origin gFrontEnd )
				)
				( attribute "CHIPS_PART_NAME" "CAP_A"
					( Origin gPackager )
				)
				( attribute "CDS_PART_NAME" "CAP_A_0603V-22.0UF,4V,20%,X6S,A"
					( Origin gPackager )
				)
				( objectStatus "C5D42" )
				( pin "a"
					( attribute "PN" "1"
						( Origin gPackager )
					)
					( objectStatus "C5D42.1" )
				)
				( pin "b"
					( attribute "PN" "2"
						( Origin gPackager )
					)
					( objectStatus "C5D42.2" )
				)
			)
			( gate "@baseboard_fab2_lib.baseboard_fab2(sch_1):page42_i136"
				( attribute "BOM_COST" "PROC_SOCKET"
					( Origin gFrontEnd )
				)
				( attribute "CDS_LIB" "dev_discrete"
					( Origin gPackager )
				)
				( attribute "CDS_LOCATION" "C5D2"
					( Origin gPackager )
				)
				( attribute "CDS_SEC" "1"
					( Origin gPackager )
				)
				( attribute "LOCATION" "C5D2"
					( Origin gFrontEnd )
				)
				( attribute "MATERIAL" "X6S"
					( Origin gFrontEnd )
				)
				( attribute "PACK_TYPE" "0603V"
					( Origin gFrontEnd )
				)
				( attribute "PART_NUMBER" "E15431-004"
					( Origin gFrontEnd )
				)
				( attribute "PHYS_PAGE" "42"
					( Origin gFrontEnd )
				)
				( attribute "ROOM" "PVCCIN_CPU0_DECAP_VR"
					( Origin gFrontEnd )
				)
				( attribute "ROT" "0"
					( Origin gFrontEnd )
				)
				( attribute "SEC" "1"
					( Origin gPackager )
				)
				( attribute "TOLERANCE" "20%"
					( Origin gFrontEnd )
				)
				( attribute "VALUE" "22.0UF"
					( Origin gFrontEnd )
				)
				( attribute "VER" "1"
					( Origin gFrontEnd )
				)
				( attribute "VOLTAGE" "4V"
					( Units "uVoltage" "V" 1.000000)
					( Origin gFrontEnd )
				)
				( attribute "XY" "(-7275,3175)"
					( Origin gFrontEnd )
				)
				( attribute "CHIPS_PART_NAME" "CAP_A"
					( Origin gPackager )
				)
				( attribute "CDS_PART_NAME" "CAP_A_0603V-22.0UF,4V,20%,X6S,A"
					( Origin gPackager )
				)
				( objectStatus "C5D2" )
				( pin "a"
					( attribute "PN" "1"
						( Origin gPackager )
					)
					( objectStatus "C5D2.1" )
				)
				( pin "b"
					( attribute "PN" "2"
						( Origin gPackager )
					)
					( objectStatus "C5D2.2" )
				)
			)
			( gate "@baseboard_fab2_lib.baseboard_fab2(sch_1):page42_i138"
				( attribute "BOM_COST" "PROC_SOCKET"
					( Origin gFrontEnd )
				)
				( attribute "CDS_LIB" "dev_discrete"
					( Origin gPackager )
				)
				( attribute "CDS_LOCATION" "C5D24"
					( Origin gPackager )
				)
				( attribute "CDS_SEC" "1"
					( Origin gPackager )
				)
				( attribute "LOCATION" "C5D24"
					( Origin gFrontEnd )
				)
				( attribute "MATERIAL" "X6S"
					( Origin gFrontEnd )
				)
				( attribute "PACK_TYPE" "0603V"
					( Origin gFrontEnd )
				)
				( attribute "PART_NUMBER" "E15431-004"
					( Origin gFrontEnd )
				)
				( attribute "PHYS_PAGE" "42"
					( Origin gFrontEnd )
				)
				( attribute "ROOM" "PVCCIN_CPU0_DECAP_VR"
					( Origin gFrontEnd )
				)
				( attribute "ROT" "0"
					( Origin gFrontEnd )
				)
				( attribute "SEC" "1"
					( Origin gPackager )
				)
				( attribute "TOLERANCE" "20%"
					( Origin gFrontEnd )
				)
				( attribute "VALUE" "22.0UF"
					( Origin gFrontEnd )
				)
				( attribute "VER" "1"
					( Origin gFrontEnd )
				)
				( attribute "VOLTAGE" "4V"
					( Units "uVoltage" "V" 1.000000)
					( Origin gFrontEnd )
				)
				( attribute "XY" "(-7725,4475)"
					( Origin gFrontEnd )
				)
				( attribute "CHIPS_PART_NAME" "CAP_A"
					( Origin gPackager )
				)
				( attribute "CDS_PART_NAME" "CAP_A_0603V-22.0UF,4V,20%,X6S,A"
					( Origin gPackager )
				)
				( objectStatus "C5D24" )
				( pin "a"
					( attribute "PN" "1"
						( Origin gPackager )
					)
					( objectStatus "C5D24.1" )
				)
				( pin "b"
					( attribute "PN" "2"
						( Origin gPackager )
					)
					( objectStatus "C5D24.2" )
				)
			)
			( gate "@baseboard_fab2_lib.baseboard_fab2(sch_1):page42_i140"
				( attribute "BOM_COST" "PROC_SOCKET"
					( Origin gFrontEnd )
				)
				( attribute "CDS_LIB" "dev_discrete"
					( Origin gPackager )
				)
				( attribute "CDS_LOCATION" "C5D39"
					( Origin gPackager )
				)
				( attribute "CDS_SEC" "1"
					( Origin gPackager )
				)
				( attribute "LOCATION" "C5D39"
					( Origin gFrontEnd )
				)
				( attribute "MATERIAL" "X6S"
					( Origin gFrontEnd )
				)
				( attribute "PACK_TYPE" "0603V"
					( Origin gFrontEnd )
				)
				( attribute "PART_NUMBER" "E15431-004"
					( Origin gFrontEnd )
				)
				( attribute "PHYS_PAGE" "42"
					( Origin gFrontEnd )
				)
				( attribute "ROOM" "PVCCIN_CPU0_DECAP_VR"
					( Origin gFrontEnd )
				)
				( attribute "ROT" "0"
					( Origin gFrontEnd )
				)
				( attribute "SEC" "1"
					( Origin gPackager )
				)
				( attribute "TOLERANCE" "20%"
					( Origin gFrontEnd )
				)
				( attribute "VALUE" "22.0UF"
					( Origin gFrontEnd )
				)
				( attribute "VER" "1"
					( Origin gFrontEnd )
				)
				( attribute "VOLTAGE" "4V"
					( Units "uVoltage" "V" 1.000000)
					( Origin gFrontEnd )
				)
				( attribute "XY" "(-7675,3800)"
					( Origin gFrontEnd )
				)
				( attribute "CHIPS_PART_NAME" "CAP_A"
					( Origin gPackager )
				)
				( attribute "CDS_PART_NAME" "CAP_A_0603V-22.0UF,4V,20%,X6S,A"
					( Origin gPackager )
				)
				( objectStatus "C5D39" )
				( pin "a"
					( attribute "PN" "1"
						( Origin gPackager )
					)
					( objectStatus "C5D39.1" )
				)
				( pin "b"
					( attribute "PN" "2"
						( Origin gPackager )
					)
					( objectStatus "C5D39.2" )
				)
			)
			( gate "@baseboard_fab2_lib.baseboard_fab2(sch_1):page42_i142"
				( attribute "BOM_COST" "PROC_SOCKET"
					( Origin gFrontEnd )
				)
				( attribute "CDS_LIB" "dev_discrete"
					( Origin gPackager )
				)
				( attribute "CDS_LOCATION" "C5D44"
					( Origin gPackager )
				)
				( attribute "CDS_SEC" "1"
					( Origin gPackager )
				)
				( attribute "LOCATION" "C5D44"
					( Origin gFrontEnd )
				)
				( attribute "MATERIAL" "X6S"
					( Origin gFrontEnd )
				)
				( attribute "PACK_TYPE" "0603V"
					( Origin gFrontEnd )
				)
				( attribute "PART_NUMBER" "E15431-004"
					( Origin gFrontEnd )
				)
				( attribute "PHYS_PAGE" "42"
					( Origin gFrontEnd )
				)
				( attribute "ROOM" "PVCCIN_CPU0_DECAP_VR"
					( Origin gFrontEnd )
				)
				( attribute "ROT" "0"
					( Origin gFrontEnd )
				)
				( attribute "SEC" "1"
					( Origin gPackager )
				)
				( attribute "TOLERANCE" "20%"
					( Origin gFrontEnd )
				)
				( attribute "VALUE" "22.0UF"
					( Origin gFrontEnd )
				)
				( attribute "VER" "1"
					( Origin gFrontEnd )
				)
				( attribute "VOLTAGE" "4V"
					( Units "uVoltage" "V" 1.000000)
					( Origin gFrontEnd )
				)
				( attribute "XY" "(-7625,3175)"
					( Origin gFrontEnd )
				)
				( attribute "CHIPS_PART_NAME" "CAP_A"
					( Origin gPackager )
				)
				( attribute "CDS_PART_NAME" "CAP_A_0603V-22.0UF,4V,20%,X6S,A"
					( Origin gPackager )
				)
				( objectStatus "C5D44" )
				( pin "a"
					( attribute "PN" "1"
						( Origin gPackager )
					)
					( objectStatus "C5D44.1" )
				)
				( pin "b"
					( attribute "PN" "2"
						( Origin gPackager )
					)
					( objectStatus "C5D44.2" )
				)
			)
			( gate "@baseboard_fab2_lib.baseboard_fab2(sch_1):page42_i145"
				( attribute "CDS_LIB" "dev_discrete"
					( Origin gPackager )
				)
				( attribute "CDS_LOCATION" "C6D9"
					( Origin gPackager )
				)
				( attribute "CDS_SEC" "1"
					( Origin gPackager )
				)
				( attribute "LOCATION" "C6D9"
					( Origin gFrontEnd )
				)
				( attribute "MATERIAL" "X6S"
					( Origin gFrontEnd )
				)
				( attribute "PACK_TYPE" "0603V"
					( Origin gFrontEnd )
				)
				( attribute "PART_NUMBER" "E15431-004"
					( Origin gFrontEnd )
				)
				( attribute "PHYS_PAGE" "42"
					( Origin gFrontEnd )
				)
				( attribute "ROOM" "PVCCIN_CPU0_DECAP_VR"
					( Origin gFrontEnd )
				)
				( attribute "ROT" "0"
					( Origin gFrontEnd )
				)
				( attribute "SEC" "1"
					( Origin gPackager )
				)
				( attribute "TOLERANCE" "20%"
					( Origin gFrontEnd )
				)
				( attribute "VALUE" "22.0UF"
					( Origin gFrontEnd )
				)
				( attribute "VER" "1"
					( Origin gFrontEnd )
				)
				( attribute "VOLTAGE" "4V"
					( Units "uVoltage" "V" 1.000000)
					( Origin gFrontEnd )
				)
				( attribute "XY" "(-2850,3775)"
					( Origin gFrontEnd )
				)
				( attribute "CHIPS_PART_NAME" "CAP_A"
					( Origin gPackager )
				)
				( attribute "CDS_PART_NAME" "CAP_A_0603V-22.0UF,4V,20%,X6S,A"
					( Origin gPackager )
				)
				( objectStatus "C6D9" )
				( pin "a"
					( attribute "PN" "1"
						( Origin gPackager )
					)
					( objectStatus "C6D9.1" )
				)
				( pin "b"
					( attribute "PN" "2"
						( Origin gPackager )
					)
					( objectStatus "C6D9.2" )
				)
			)
			( gate "@baseboard_fab2_lib.baseboard_fab2(sch_1):page42_i147"
				( attribute "CDS_LIB" "dev_discrete"
					( Origin gPackager )
				)
				( attribute "CDS_LOCATION" "C6D10"
					( Origin gPackager )
				)
				( attribute "CDS_SEC" "1"
					( Origin gPackager )
				)
				( attribute "LOCATION" "C6D10"
					( Origin gFrontEnd )
				)
				( attribute "MATERIAL" "X6S"
					( Origin gFrontEnd )
				)
				( attribute "PACK_TYPE" "0603V"
					( Origin gFrontEnd )
				)
				( attribute "PART_NUMBER" "E15431-004"
					( Origin gFrontEnd )
				)
				( attribute "PHYS_PAGE" "42"
					( Origin gFrontEnd )
				)
				( attribute "ROOM" "PVCCIN_CPU0_DECAP_VR"
					( Origin gFrontEnd )
				)
				( attribute "ROT" "0"
					( Origin gFrontEnd )
				)
				( attribute "SEC" "1"
					( Origin gPackager )
				)
				( attribute "TOLERANCE" "20%"
					( Origin gFrontEnd )
				)
				( attribute "VALUE" "22.0UF"
					( Origin gFrontEnd )
				)
				( attribute "VER" "1"
					( Origin gFrontEnd )
				)
				( attribute "VOLTAGE" "4V"
					( Units "uVoltage" "V" 1.000000)
					( Origin gFrontEnd )
				)
				( attribute "XY" "(-3125,3775)"
					( Origin gFrontEnd )
				)
				( attribute "CHIPS_PART_NAME" "CAP_A"
					( Origin gPackager )
				)
				( attribute "CDS_PART_NAME" "CAP_A_0603V-22.0UF,4V,20%,X6S,A"
					( Origin gPackager )
				)
				( objectStatus "C6D10" )
				( pin "a"
					( attribute "PN" "1"
						( Origin gPackager )
					)
					( objectStatus "C6D10.1" )
				)
				( pin "b"
					( attribute "PN" "2"
						( Origin gPackager )
					)
					( objectStatus "C6D10.2" )
				)
			)
			( gate "@baseboard_fab2_lib.baseboard_fab2(sch_1):page42_i148"
				( attribute "CDS_LIB" "mstr_discrete"
					( Origin gPackager )
				)
				( attribute "CDS_LOCATION" "C5P30"
					( Origin gPackager )
				)
				( attribute "CDS_SEC" "1"
					( Origin gPackager )
				)
				( attribute "LOCATION" "C5P30"
					( Origin gFrontEnd )
				)
				( attribute "MATERIAL" "X6S"
					( Origin gFrontEnd )
				)
				( attribute "PACK_TYPE" "0805"
					( Origin gFrontEnd )
				)
				( attribute "PART_NUMBER" "C95333-006"
					( Origin gFrontEnd )
				)
				( attribute "PHYS_PAGE" "42"
					( Origin gFrontEnd )
				)
				( attribute "ROOM" "PVCCIN_CPU0_DECAP_VR"
					( Origin gFrontEnd )
				)
				( attribute "ROT" "0"
					( Origin gFrontEnd )
				)
				( attribute "SEC" "1"
					( Origin gPackager )
				)
				( attribute "TOLERANCE" "20%"
					( Origin gFrontEnd )
				)
				( attribute "VALUE" "47UF"
					( Origin gFrontEnd )
				)
				( attribute "VER" "1"
					( Origin gFrontEnd )
				)
				( attribute "VOLTAGE" "4V"
					( Units "uVoltage" "V" 1.000000)
					( Origin gFrontEnd )
				)
				( attribute "XY" "(-4425,2175)"
					( Origin gFrontEnd )
				)
				( attribute "CHIPS_PART_NAME" "CAP"
					( Origin gPackager )
				)
				( attribute "CDS_PART_NAME" "CAP_0805-47UF,4V,20%,X6S,C9533A"
					( Origin gPackager )
				)
				( objectStatus "C5P30" )
				( pin "a"
					( attribute "PN" "1"
						( Origin gPackager )
					)
					( objectStatus "C5P30.1" )
				)
				( pin "b"
					( attribute "PN" "2"
						( Origin gPackager )
					)
					( objectStatus "C5P30.2" )
				)
			)
			( gate "@baseboard_fab2_lib.baseboard_fab2(sch_1):page42_i149"
				( attribute "CDS_LIB" "mstr_discrete"
					( Origin gPackager )
				)
				( attribute "CDS_LOCATION" "C5P29"
					( Origin gPackager )
				)
				( attribute "CDS_SEC" "1"
					( Origin gPackager )
				)
				( attribute "LOCATION" "C5P29"
					( Origin gFrontEnd )
				)
				( attribute "MATERIAL" "X6S"
					( Origin gFrontEnd )
				)
				( attribute "PACK_TYPE" "0805"
					( Origin gFrontEnd )
				)
				( attribute "PART_NUMBER" "C95333-006"
					( Origin gFrontEnd )
				)
				( attribute "PHYS_PAGE" "42"
					( Origin gFrontEnd )
				)
				( attribute "ROOM" "PVCCIN_CPU0_DECAP_VR"
					( Origin gFrontEnd )
				)
				( attribute "ROT" "0"
					( Origin gFrontEnd )
				)
				( attribute "SEC" "1"
					( Origin gPackager )
				)
				( attribute "TOLERANCE" "20%"
					( Origin gFrontEnd )
				)
				( attribute "VALUE" "47UF"
					( Origin gFrontEnd )
				)
				( attribute "VER" "1"
					( Origin gFrontEnd )
				)
				( attribute "VOLTAGE" "4V"
					( Units "uVoltage" "V" 1.000000)
					( Origin gFrontEnd )
				)
				( attribute "XY" "(-4675,2175)"
					( Origin gFrontEnd )
				)
				( attribute "CHIPS_PART_NAME" "CAP"
					( Origin gPackager )
				)
				( attribute "CDS_PART_NAME" "CAP_0805-47UF,4V,20%,X6S,C9533A"
					( Origin gPackager )
				)
				( objectStatus "C5P29" )
				( pin "a"
					( attribute "PN" "1"
						( Origin gPackager )
					)
					( objectStatus "C5P29.1" )
				)
				( pin "b"
					( attribute "PN" "2"
						( Origin gPackager )
					)
					( objectStatus "C5P29.2" )
				)
			)
			( gate "@baseboard_fab2_lib.baseboard_fab2(sch_1):page42_i151"
				( attribute "BOM_COST" "PROC_SOCKET"
					( Origin gFrontEnd )
				)
				( attribute "CDS_LIB" "dev_discrete"
					( Origin gPackager )
				)
				( attribute "CDS_LOCATION" "C5D36"
					( Origin gPackager )
				)
				( attribute "CDS_SEC" "1"
					( Origin gPackager )
				)
				( attribute "LOCATION" "C5D36"
					( Origin gFrontEnd )
				)
				( attribute "MATERIAL" "X6S"
					( Origin gFrontEnd )
				)
				( attribute "PACK_TYPE" "0603V"
					( Origin gFrontEnd )
				)
				( attribute "PART_NUMBER" "E15431-004"
					( Origin gFrontEnd )
				)
				( attribute "PHYS_PAGE" "42"
					( Origin gFrontEnd )
				)
				( attribute "ROOM" "PVCCIN_CPU0_DECAP_VR"
					( Origin gFrontEnd )
				)
				( attribute "ROT" "0"
					( Origin gFrontEnd )
				)
				( attribute "SEC" "1"
					( Origin gPackager )
				)
				( attribute "TOLERANCE" "20%"
					( Origin gFrontEnd )
				)
				( attribute "VALUE" "22.0UF"
					( Origin gFrontEnd )
				)
				( attribute "VER" "1"
					( Origin gFrontEnd )
				)
				( attribute "VOLTAGE" "4V"
					( Units "uVoltage" "V" 1.000000)
					( Origin gFrontEnd )
				)
				( attribute "XY" "(-2575,4475)"
					( Origin gFrontEnd )
				)
				( attribute "CHIPS_PART_NAME" "CAP_A"
					( Origin gPackager )
				)
				( attribute "CDS_PART_NAME" "CAP_A_0603V-22.0UF,4V,20%,X6S,A"
					( Origin gPackager )
				)
				( objectStatus "C5D36" )
				( pin "a"
					( attribute "PN" "1"
						( Origin gPackager )
					)
					( objectStatus "C5D36.1" )
				)
				( pin "b"
					( attribute "PN" "2"
						( Origin gPackager )
					)
					( objectStatus "C5D36.2" )
				)
			)
			( gate "@baseboard_fab2_lib.baseboard_fab2(sch_1):page42_i152"
				( attribute "BOM_COST" "PROC_SOCKET"
					( Origin gFrontEnd )
				)
				( attribute "CDS_LIB" "dev_discrete"
					( Origin gPackager )
				)
				( attribute "CDS_LOCATION" "C5D49"
					( Origin gPackager )
				)
				( attribute "CDS_SEC" "1"
					( Origin gPackager )
				)
				( attribute "LOCATION" "C5D49"
					( Origin gFrontEnd )
				)
				( attribute "MATERIAL" "X6S"
					( Origin gFrontEnd )
				)
				( attribute "PACK_TYPE" "0603V"
					( Origin gFrontEnd )
				)
				( attribute "PART_NUMBER" "E15431-004"
					( Origin gFrontEnd )
				)
				( attribute "PHYS_PAGE" "42"
					( Origin gFrontEnd )
				)
				( attribute "ROOM" "PVCCIN_CPU0_DECAP_VR"
					( Origin gFrontEnd )
				)
				( attribute "ROT" "0"
					( Origin gFrontEnd )
				)
				( attribute "SEC" "1"
					( Origin gPackager )
				)
				( attribute "TOLERANCE" "20%"
					( Origin gFrontEnd )
				)
				( attribute "VALUE" "22.0UF"
					( Origin gFrontEnd )
				)
				( attribute "VER" "1"
					( Origin gFrontEnd )
				)
				( attribute "VOLTAGE" "4V"
					( Units "uVoltage" "V" 1.000000)
					( Origin gFrontEnd )
				)
				( attribute "XY" "(-2275,4450)"
					( Origin gFrontEnd )
				)
				( attribute "CHIPS_PART_NAME" "CAP_A"
					( Origin gPackager )
				)
				( attribute "CDS_PART_NAME" "CAP_A_0603V-22.0UF,4V,20%,X6S,A"
					( Origin gPackager )
				)
				( objectStatus "C5D49" )
				( pin "a"
					( attribute "PN" "1"
						( Origin gPackager )
					)
					( objectStatus "C5D49.1" )
				)
				( pin "b"
					( attribute "PN" "2"
						( Origin gPackager )
					)
					( objectStatus "C5D49.2" )
				)
			)
			( gate "@baseboard_fab2_lib.baseboard_fab2(sch_1):page42_i153"
				( attribute "BOM_COST" "PROC_SOCKET"
					( Origin gFrontEnd )
				)
				( attribute "CDS_LIB" "dev_discrete"
					( Origin gPackager )
				)
				( attribute "CDS_LOCATION" "C5D22"
					( Origin gPackager )
				)
				( attribute "CDS_SEC" "1"
					( Origin gPackager )
				)
				( attribute "LOCATION" "C5D22"
					( Origin gFrontEnd )
				)
				( attribute "MATERIAL" "X6S"
					( Origin gFrontEnd )
				)
				( attribute "PACK_TYPE" "0603V"
					( Origin gFrontEnd )
				)
				( attribute "PART_NUMBER" "E15431-004"
					( Origin gFrontEnd )
				)
				( attribute "PHYS_PAGE" "42"
					( Origin gFrontEnd )
				)
				( attribute "ROOM" "PVCCIN_CPU0_DECAP_VR"
					( Origin gFrontEnd )
				)
				( attribute "ROT" "0"
					( Origin gFrontEnd )
				)
				( attribute "SEC" "1"
					( Origin gPackager )
				)
				( attribute "TOLERANCE" "20%"
					( Origin gFrontEnd )
				)
				( attribute "VALUE" "22.0UF"
					( Origin gFrontEnd )
				)
				( attribute "VER" "1"
					( Origin gFrontEnd )
				)
				( attribute "VOLTAGE" "4V"
					( Units "uVoltage" "V" 1.000000)
					( Origin gFrontEnd )
				)
				( attribute "XY" "(-525,4475)"
					( Origin gFrontEnd )
				)
				( attribute "CHIPS_PART_NAME" "CAP_A"
					( Origin gPackager )
				)
				( attribute "CDS_PART_NAME" "CAP_A_0603V-22.0UF,4V,20%,X6S,A"
					( Origin gPackager )
				)
				( objectStatus "C5D22" )
				( pin "a"
					( attribute "PN" "1"
						( Origin gPackager )
					)
					( objectStatus "C5D22.1" )
				)
				( pin "b"
					( attribute "PN" "2"
						( Origin gPackager )
					)
					( objectStatus "C5D22.2" )
				)
			)
			( gate "@baseboard_fab2_lib.baseboard_fab2(sch_1):page42_i154"
				( attribute "BOM_COST" "PROC_SOCKET"
					( Origin gFrontEnd )
				)
				( attribute "CDS_LIB" "dev_discrete"
					( Origin gPackager )
				)
				( attribute "CDS_LOCATION" "C5D26"
					( Origin gPackager )
				)
				( attribute "CDS_SEC" "1"
					( Origin gPackager )
				)
				( attribute "LOCATION" "C5D26"
					( Origin gFrontEnd )
				)
				( attribute "MATERIAL" "X6S"
					( Origin gFrontEnd )
				)
				( attribute "PACK_TYPE" "0603V"
					( Origin gFrontEnd )
				)
				( attribute "PART_NUMBER" "E15431-004"
					( Origin gFrontEnd )
				)
				( attribute "PHYS_PAGE" "42"
					( Origin gFrontEnd )
				)
				( attribute "ROOM" "PVCCIN_CPU0_DECAP_VR"
					( Origin gFrontEnd )
				)
				( attribute "ROT" "0"
					( Origin gFrontEnd )
				)
				( attribute "SEC" "1"
					( Origin gPackager )
				)
				( attribute "TOLERANCE" "20%"
					( Origin gFrontEnd )
				)
				( attribute "VALUE" "22.0UF"
					( Origin gFrontEnd )
				)
				( attribute "VER" "1"
					( Origin gFrontEnd )
				)
				( attribute "VOLTAGE" "4V"
					( Units "uVoltage" "V" 1.000000)
					( Origin gFrontEnd )
				)
				( attribute "XY" "(-4450,4475)"
					( Origin gFrontEnd )
				)
				( attribute "CHIPS_PART_NAME" "CAP_A"
					( Origin gPackager )
				)
				( attribute "CDS_PART_NAME" "CAP_A_0603V-22.0UF,4V,20%,X6S,A"
					( Origin gPackager )
				)
				( objectStatus "C5D26" )
				( pin "a"
					( attribute "PN" "1"
						( Origin gPackager )
					)
					( objectStatus "C5D26.1" )
				)
				( pin "b"
					( attribute "PN" "2"
						( Origin gPackager )
					)
					( objectStatus "C5D26.2" )
				)
			)
			( gate "@baseboard_fab2_lib.baseboard_fab2(sch_1):page42_i155"
				( attribute "BOM_COST" "PROC_SOCKET"
					( Origin gFrontEnd )
				)
				( attribute "CDS_LIB" "dev_discrete"
					( Origin gPackager )
				)
				( attribute "CDS_LOCATION" "C5D25"
					( Origin gPackager )
				)
				( attribute "CDS_SEC" "1"
					( Origin gPackager )
				)
				( attribute "LOCATION" "C5D25"
					( Origin gFrontEnd )
				)
				( attribute "MATERIAL" "X6S"
					( Origin gFrontEnd )
				)
				( attribute "PACK_TYPE" "0603V"
					( Origin gFrontEnd )
				)
				( attribute "PART_NUMBER" "E15431-004"
					( Origin gFrontEnd )
				)
				( attribute "PHYS_PAGE" "42"
					( Origin gFrontEnd )
				)
				( attribute "ROOM" "PVCCIN_CPU0_DECAP_VR"
					( Origin gFrontEnd )
				)
				( attribute "ROT" "0"
					( Origin gFrontEnd )
				)
				( attribute "SEC" "1"
					( Origin gPackager )
				)
				( attribute "TOLERANCE" "20%"
					( Origin gFrontEnd )
				)
				( attribute "VALUE" "22.0UF"
					( Origin gFrontEnd )
				)
				( attribute "VER" "1"
					( Origin gFrontEnd )
				)
				( attribute "VOLTAGE" "4V"
					( Units "uVoltage" "V" 1.000000)
					( Origin gFrontEnd )
				)
				( attribute "XY" "(-4425,3800)"
					( Origin gFrontEnd )
				)
				( attribute "CHIPS_PART_NAME" "CAP_A"
					( Origin gPackager )
				)
				( attribute "CDS_PART_NAME" "CAP_A_0603V-22.0UF,4V,20%,X6S,A"
					( Origin gPackager )
				)
				( objectStatus "C5D25" )
				( pin "a"
					( attribute "PN" "1"
						( Origin gPackager )
					)
					( objectStatus "C5D25.1" )
				)
				( pin "b"
					( attribute "PN" "2"
						( Origin gPackager )
					)
					( objectStatus "C5D25.2" )
				)
			)
			( gate "@baseboard_fab2_lib.baseboard_fab2(sch_1):page42_i156"
				( attribute "BOM_COST" "PROC_SOCKET"
					( Origin gFrontEnd )
				)
				( attribute "CDS_LIB" "dev_discrete"
					( Origin gPackager )
				)
				( attribute "CDS_LOCATION" "C5D45"
					( Origin gPackager )
				)
				( attribute "CDS_SEC" "1"
					( Origin gPackager )
				)
				( attribute "LOCATION" "C5D45"
					( Origin gFrontEnd )
				)
				( attribute "MATERIAL" "X6S"
					( Origin gFrontEnd )
				)
				( attribute "PACK_TYPE" "0603V"
					( Origin gFrontEnd )
				)
				( attribute "PART_NUMBER" "E15431-004"
					( Origin gFrontEnd )
				)
				( attribute "PHYS_PAGE" "42"
					( Origin gFrontEnd )
				)
				( attribute "ROOM" "PVCCIN_CPU0_DECAP_VR"
					( Origin gFrontEnd )
				)
				( attribute "ROT" "0"
					( Origin gFrontEnd )
				)
				( attribute "SEC" "1"
					( Origin gPackager )
				)
				( attribute "TOLERANCE" "20%"
					( Origin gFrontEnd )
				)
				( attribute "VALUE" "22.0UF"
					( Origin gFrontEnd )
				)
				( attribute "VER" "1"
					( Origin gFrontEnd )
				)
				( attribute "VOLTAGE" "4V"
					( Units "uVoltage" "V" 1.000000)
					( Origin gFrontEnd )
				)
				( attribute "XY" "(-4450,3200)"
					( Origin gFrontEnd )
				)
				( attribute "CHIPS_PART_NAME" "CAP_A"
					( Origin gPackager )
				)
				( attribute "CDS_PART_NAME" "CAP_A_0603V-22.0UF,4V,20%,X6S,A"
					( Origin gPackager )
				)
				( objectStatus "C5D45" )
				( pin "a"
					( attribute "PN" "1"
						( Origin gPackager )
					)
					( objectStatus "C5D45.1" )
				)
				( pin "b"
					( attribute "PN" "2"
						( Origin gPackager )
					)
					( objectStatus "C5D45.2" )
				)
			)
			( gate "@baseboard_fab2_lib.baseboard_fab2(sch_1):page42_i162"
				( attribute "CDS_LIB" "mstr_discrete"
					( Origin gPackager )
				)
				( attribute "CDS_LOCATION" "C5P31"
					( Origin gPackager )
				)
				( attribute "CDS_SEC" "1"
					( Origin gPackager )
				)
				( attribute "LOCATION" "C5P31"
					( Origin gFrontEnd )
				)
				( attribute "MATERIAL" "X6S"
					( Origin gFrontEnd )
				)
				( attribute "PACK_TYPE" "0805"
					( Origin gFrontEnd )
				)
				( attribute "PART_NUMBER" "C95333-006"
					( Origin gFrontEnd )
				)
				( attribute "PHYS_PAGE" "42"
					( Origin gFrontEnd )
				)
				( attribute "ROOM" "PVCCIN_CPU0_DECAP_VR"
					( Origin gFrontEnd )
				)
				( attribute "ROT" "0"
					( Origin gFrontEnd )
				)
				( attribute "SEC" "1"
					( Origin gPackager )
				)
				( attribute "TOLERANCE" "20%"
					( Origin gFrontEnd )
				)
				( attribute "VALUE" "47UF"
					( Origin gFrontEnd )
				)
				( attribute "VER" "1"
					( Origin gFrontEnd )
				)
				( attribute "VOLTAGE" "4V"
					( Units "uVoltage" "V" 1.000000)
					( Origin gFrontEnd )
				)
				( attribute "XY" "(-1900,2150)"
					( Origin gFrontEnd )
				)
				( attribute "CHIPS_PART_NAME" "CAP"
					( Origin gPackager )
				)
				( attribute "CDS_PART_NAME" "CAP_0805-47UF,4V,20%,X6S,C9533A"
					( Origin gPackager )
				)
				( objectStatus "C5P31" )
				( pin "a"
					( attribute "PN" "1"
						( Origin gPackager )
					)
					( objectStatus "C5P31.1" )
				)
				( pin "b"
					( attribute "PN" "2"
						( Origin gPackager )
					)
					( objectStatus "C5P31.2" )
				)
			)
			( gate "@baseboard_fab2_lib.baseboard_fab2(sch_1):page42_i163"
				( attribute "CDS_LIB" "mstr_discrete"
					( Origin gPackager )
				)
				( attribute "CDS_LOCATION" "C4P2"
					( Origin gPackager )
				)
				( attribute "CDS_SEC" "1"
					( Origin gPackager )
				)
				( attribute "LOCATION" "C4P2"
					( Origin gFrontEnd )
				)
				( attribute "MATERIAL" "X6S"
					( Origin gFrontEnd )
				)
				( attribute "PACK_TYPE" "0805"
					( Origin gFrontEnd )
				)
				( attribute "PART_NUMBER" "C95333-006"
					( Origin gFrontEnd )
				)
				( attribute "PHYS_PAGE" "42"
					( Origin gFrontEnd )
				)
				( attribute "ROOM" "PVCCIN_CPU0_DECAP_VR"
					( Origin gFrontEnd )
				)
				( attribute "ROT" "0"
					( Origin gFrontEnd )
				)
				( attribute "SEC" "1"
					( Origin gPackager )
				)
				( attribute "TOLERANCE" "20%"
					( Origin gFrontEnd )
				)
				( attribute "VALUE" "47UF"
					( Origin gFrontEnd )
				)
				( attribute "VER" "1"
					( Origin gFrontEnd )
				)
				( attribute "VOLTAGE" "4V"
					( Units "uVoltage" "V" 1.000000)
					( Origin gFrontEnd )
				)
				( attribute "XY" "(-1650,2150)"
					( Origin gFrontEnd )
				)
				( attribute "CHIPS_PART_NAME" "CAP"
					( Origin gPackager )
				)
				( attribute "CDS_PART_NAME" "CAP_0805-47UF,4V,20%,X6S,C9533A"
					( Origin gPackager )
				)
				( objectStatus "C4P2" )
				( pin "a"
					( attribute "PN" "1"
						( Origin gPackager )
					)
					( objectStatus "C4P2.1" )
				)
				( pin "b"
					( attribute "PN" "2"
						( Origin gPackager )
					)
					( objectStatus "C4P2.2" )
				)
			)
			( gate "@baseboard_fab2_lib.baseboard_fab2(sch_1):page42_i164"
				( attribute "CDS_LIB" "dev_discrete"
					( Origin gPackager )
				)
				( attribute "CDS_LOCATION" "C4P6"
					( Origin gPackager )
				)
				( attribute "CDS_SEC" "1"
					( Origin gPackager )
				)
				( attribute "LOCATION" "C4P6"
					( Origin gFrontEnd )
				)
				( attribute "MATERIAL" "X6S"
					( Origin gFrontEnd )
				)
				( attribute "PACK_TYPE" "0603V"
					( Origin gFrontEnd )
				)
				( attribute "PART_NUMBER" "E15431-004"
					( Origin gFrontEnd )
				)
				( attribute "PHYS_PAGE" "42"
					( Origin gFrontEnd )
				)
				( attribute "ROOM" "PVCCIN_CPU0_DECAP_VR"
					( Origin gFrontEnd )
				)
				( attribute "ROT" "0"
					( Origin gFrontEnd )
				)
				( attribute "SEC" "1"
					( Origin gPackager )
				)
				( attribute "TOLERANCE" "20%"
					( Origin gFrontEnd )
				)
				( attribute "VALUE" "22.0UF"
					( Origin gFrontEnd )
				)
				( attribute "VER" "1"
					( Origin gFrontEnd )
				)
				( attribute "VOLTAGE" "4V"
					( Units "uVoltage" "V" 1.000000)
					( Origin gFrontEnd )
				)
				( attribute "XY" "(-2250,950)"
					( Origin gFrontEnd )
				)
				( attribute "CHIPS_PART_NAME" "CAP_A"
					( Origin gPackager )
				)
				( attribute "CDS_PART_NAME" "CAP_A_0603V-22.0UF,4V,20%,X6S,A"
					( Origin gPackager )
				)
				( objectStatus "C4P6" )
				( pin "a"
					( attribute "PN" "1"
						( Origin gPackager )
					)
					( objectStatus "C4P6.1" )
				)
				( pin "b"
					( attribute "PN" "2"
						( Origin gPackager )
					)
					( objectStatus "C4P6.2" )
				)
			)
			( gate "@baseboard_fab2_lib.baseboard_fab2(sch_1):page42_i172"
				( attribute "CDS_LIB" "mstr_discrete"
					( Origin gPackager )
				)
				( attribute "CDS_LOCATION" "C4P5"
					( Origin gPackager )
				)
				( attribute "CDS_SEC" "1"
					( Origin gPackager )
				)
				( attribute "LOCATION" "C4P5"
					( Origin gFrontEnd )
				)
				( attribute "MATERIAL" "X6S"
					( Origin gFrontEnd )
				)
				( attribute "PACK_TYPE" "0805"
					( Origin gFrontEnd )
				)
				( attribute "PART_NUMBER" "C95333-006"
					( Origin gFrontEnd )
				)
				( attribute "PHYS_PAGE" "42"
					( Origin gFrontEnd )
				)
				( attribute "ROOM" "PVCCIN_CPU0_DECAP_VR"
					( Origin gFrontEnd )
				)
				( attribute "ROT" "0"
					( Origin gFrontEnd )
				)
				( attribute "SEC" "1"
					( Origin gPackager )
				)
				( attribute "TOLERANCE" "20%"
					( Origin gFrontEnd )
				)
				( attribute "VALUE" "47UF"
					( Origin gFrontEnd )
				)
				( attribute "VER" "1"
					( Origin gFrontEnd )
				)
				( attribute "VOLTAGE" "4V"
					( Units "uVoltage" "V" 1.000000)
					( Origin gFrontEnd )
				)
				( attribute "XY" "(-1400,2150)"
					( Origin gFrontEnd )
				)
				( attribute "CHIPS_PART_NAME" "CAP"
					( Origin gPackager )
				)
				( attribute "CDS_PART_NAME" "CAP_0805-47UF,4V,20%,X6S,C9533A"
					( Origin gPackager )
				)
				( objectStatus "C4P5" )
				( pin "a"
					( attribute "PN" "1"
						( Origin gPackager )
					)
					( objectStatus "C4P5.1" )
				)
				( pin "b"
					( attribute "PN" "2"
						( Origin gPackager )
					)
					( objectStatus "C4P5.2" )
				)
			)
			( gate "@baseboard_fab2_lib.baseboard_fab2(sch_1):page42_i173"
				( attribute "BOM_COST" "PROC_SOCKET"
					( Origin gFrontEnd )
				)
				( attribute "CDS_LIB" "dev_discrete"
					( Origin gPackager )
				)
				( attribute "CDS_LOCATION" "C5D20"
					( Origin gPackager )
				)
				( attribute "CDS_SEC" "1"
					( Origin gPackager )
				)
				( attribute "LOCATION" "C5D20"
					( Origin gFrontEnd )
				)
				( attribute "MATERIAL" "X6S"
					( Origin gFrontEnd )
				)
				( attribute "PACK_TYPE" "0603V"
					( Origin gFrontEnd )
				)
				( attribute "PART_NUMBER" "E15431-004"
					( Origin gFrontEnd )
				)
				( attribute "PHYS_PAGE" "42"
					( Origin gFrontEnd )
				)
				( attribute "ROOM" "PVCCIN_CPU0_DECAP_VR"
					( Origin gFrontEnd )
				)
				( attribute "ROT" "0"
					( Origin gFrontEnd )
				)
				( attribute "SEC" "1"
					( Origin gPackager )
				)
				( attribute "TOLERANCE" "20%"
					( Origin gFrontEnd )
				)
				( attribute "VALUE" "22.0UF"
					( Origin gFrontEnd )
				)
				( attribute "VER" "1"
					( Origin gFrontEnd )
				)
				( attribute "VOLTAGE" "4V"
					( Units "uVoltage" "V" 1.000000)
					( Origin gFrontEnd )
				)
				( attribute "XY" "(-1375,3850)"
					( Origin gFrontEnd )
				)
				( attribute "CHIPS_PART_NAME" "CAP_A"
					( Origin gPackager )
				)
				( attribute "CDS_PART_NAME" "CAP_A_0603V-22.0UF,4V,20%,X6S,A"
					( Origin gPackager )
				)
				( objectStatus "C5D20" )
				( pin "a"
					( attribute "PN" "1"
						( Origin gPackager )
					)
					( objectStatus "C5D20.1" )
				)
				( pin "b"
					( attribute "PN" "2"
						( Origin gPackager )
					)
					( objectStatus "C5D20.2" )
				)
			)
			( gate "@baseboard_fab2_lib.baseboard_fab2(sch_1):page42_i174"
				( attribute "BOM_COST" "PROC_SOCKET"
					( Origin gFrontEnd )
				)
				( attribute "CDS_LIB" "dev_discrete"
					( Origin gPackager )
				)
				( attribute "CDS_LOCATION" "C5D33"
					( Origin gPackager )
				)
				( attribute "CDS_SEC" "1"
					( Origin gPackager )
				)
				( attribute "LOCATION" "C5D33"
					( Origin gFrontEnd )
				)
				( attribute "MATERIAL" "X6S"
					( Origin gFrontEnd )
				)
				( attribute "PACK_TYPE" "0603V"
					( Origin gFrontEnd )
				)
				( attribute "PART_NUMBER" "E15431-004"
					( Origin gFrontEnd )
				)
				( attribute "PHYS_PAGE" "42"
					( Origin gFrontEnd )
				)
				( attribute "ROOM" "PVCCIN_CPU0_DECAP_VR"
					( Origin gFrontEnd )
				)
				( attribute "ROT" "0"
					( Origin gFrontEnd )
				)
				( attribute "SEC" "1"
					( Origin gPackager )
				)
				( attribute "TOLERANCE" "20%"
					( Origin gFrontEnd )
				)
				( attribute "VALUE" "22.0UF"
					( Origin gFrontEnd )
				)
				( attribute "VER" "1"
					( Origin gFrontEnd )
				)
				( attribute "VOLTAGE" "4V"
					( Units "uVoltage" "V" 1.000000)
					( Origin gFrontEnd )
				)
				( attribute "XY" "(-975,3825)"
					( Origin gFrontEnd )
				)
				( attribute "CHIPS_PART_NAME" "CAP_A"
					( Origin gPackager )
				)
				( attribute "CDS_PART_NAME" "CAP_A_0603V-22.0UF,4V,20%,X6S,A"
					( Origin gPackager )
				)
				( objectStatus "C5D33" )
				( pin "a"
					( attribute "PN" "1"
						( Origin gPackager )
					)
					( objectStatus "C5D33.1" )
				)
				( pin "b"
					( attribute "PN" "2"
						( Origin gPackager )
					)
					( objectStatus "C5D33.2" )
				)
			)
			( gate "@baseboard_fab2_lib.baseboard_fab2(sch_1):page42_i175"
				( attribute "BOM_COST" "PROC_SOCKET"
					( Origin gFrontEnd )
				)
				( attribute "CDS_LIB" "dev_discrete"
					( Origin gPackager )
				)
				( attribute "CDS_LOCATION" "C5D34"
					( Origin gPackager )
				)
				( attribute "CDS_SEC" "1"
					( Origin gPackager )
				)
				( attribute "LOCATION" "C5D34"
					( Origin gFrontEnd )
				)
				( attribute "MATERIAL" "X6S"
					( Origin gFrontEnd )
				)
				( attribute "PACK_TYPE" "0603V"
					( Origin gFrontEnd )
				)
				( attribute "PART_NUMBER" "E15431-004"
					( Origin gFrontEnd )
				)
				( attribute "PHYS_PAGE" "42"
					( Origin gFrontEnd )
				)
				( attribute "ROOM" "PVCCIN_CPU0_DECAP_VR"
					( Origin gFrontEnd )
				)
				( attribute "ROT" "0"
					( Origin gFrontEnd )
				)
				( attribute "SEC" "1"
					( Origin gPackager )
				)
				( attribute "TOLERANCE" "20%"
					( Origin gFrontEnd )
				)
				( attribute "VALUE" "22.0UF"
					( Origin gFrontEnd )
				)
				( attribute "VER" "1"
					( Origin gFrontEnd )
				)
				( attribute "VOLTAGE" "4V"
					( Units "uVoltage" "V" 1.000000)
					( Origin gFrontEnd )
				)
				( attribute "XY" "(-600,3800)"
					( Origin gFrontEnd )
				)
				( attribute "CHIPS_PART_NAME" "CAP_A"
					( Origin gPackager )
				)
				( attribute "CDS_PART_NAME" "CAP_A_0603V-22.0UF,4V,20%,X6S,A"
					( Origin gPackager )
				)
				( objectStatus "C5D34" )
				( pin "a"
					( attribute "PN" "1"
						( Origin gPackager )
					)
					( objectStatus "C5D34.1" )
				)
				( pin "b"
					( attribute "PN" "2"
						( Origin gPackager )
					)
					( objectStatus "C5D34.2" )
				)
			)
			( gate "@baseboard_fab2_lib.baseboard_fab2(sch_1):page42_i176"
				( attribute "BOM_COST" "PROC_SOCKET"
					( Origin gFrontEnd )
				)
				( attribute "CDS_LIB" "dev_discrete"
					( Origin gPackager )
				)
				( attribute "CDS_LOCATION" "C5D35"
					( Origin gPackager )
				)
				( attribute "CDS_SEC" "1"
					( Origin gPackager )
				)
				( attribute "LOCATION" "C5D35"
					( Origin gFrontEnd )
				)
				( attribute "MATERIAL" "X6S"
					( Origin gFrontEnd )
				)
				( attribute "PACK_TYPE" "0603V"
					( Origin gFrontEnd )
				)
				( attribute "PART_NUMBER" "E15431-004"
					( Origin gFrontEnd )
				)
				( attribute "PHYS_PAGE" "42"
					( Origin gFrontEnd )
				)
				( attribute "ROOM" "PVCCIN_CPU0_DECAP_VR"
					( Origin gFrontEnd )
				)
				( attribute "ROT" "0"
					( Origin gFrontEnd )
				)
				( attribute "SEC" "1"
					( Origin gPackager )
				)
				( attribute "TOLERANCE" "20%"
					( Origin gFrontEnd )
				)
				( attribute "VALUE" "22.0UF"
					( Origin gFrontEnd )
				)
				( attribute "VER" "1"
					( Origin gFrontEnd )
				)
				( attribute "VOLTAGE" "4V"
					( Units "uVoltage" "V" 1.000000)
					( Origin gFrontEnd )
				)
				( attribute "XY" "(-1700,3850)"
					( Origin gFrontEnd )
				)
				( attribute "CHIPS_PART_NAME" "CAP_A"
					( Origin gPackager )
				)
				( attribute "CDS_PART_NAME" "CAP_A_0603V-22.0UF,4V,20%,X6S,A"
					( Origin gPackager )
				)
				( objectStatus "C5D35" )
				( pin "a"
					( attribute "PN" "1"
						( Origin gPackager )
					)
					( objectStatus "C5D35.1" )
				)
				( pin "b"
					( attribute "PN" "2"
						( Origin gPackager )
					)
					( objectStatus "C5D35.2" )
				)
			)
			( gate "@baseboard_fab2_lib.baseboard_fab2(sch_1):page42_i178"
				( attribute "CDS_LIB" "dev_discrete"
					( Origin gPackager )
				)
				( attribute "CDS_LOCATION" "C4P8"
					( Origin gPackager )
				)
				( attribute "CDS_SEC" "1"
					( Origin gPackager )
				)
				( attribute "LOCATION" "C4P8"
					( Origin gFrontEnd )
				)
				( attribute "MATERIAL" "X6S"
					( Origin gFrontEnd )
				)
				( attribute "PACK_TYPE" "0603V"
					( Origin gFrontEnd )
				)
				( attribute "PART_NUMBER" "E15431-004"
					( Origin gFrontEnd )
				)
				( attribute "PHYS_PAGE" "42"
					( Origin gFrontEnd )
				)
				( attribute "ROOM" "PVCCIN_CPU0_DECAP_VR"
					( Origin gFrontEnd )
				)
				( attribute "ROT" "0"
					( Origin gFrontEnd )
				)
				( attribute "SEC" "1"
					( Origin gPackager )
				)
				( attribute "TOLERANCE" "20%"
					( Origin gFrontEnd )
				)
				( attribute "VALUE" "22.0UF"
					( Origin gFrontEnd )
				)
				( attribute "VER" "1"
					( Origin gFrontEnd )
				)
				( attribute "VOLTAGE" "4V"
					( Units "uVoltage" "V" 1.000000)
					( Origin gFrontEnd )
				)
				( attribute "XY" "(-1950,950)"
					( Origin gFrontEnd )
				)
				( attribute "CHIPS_PART_NAME" "CAP_A"
					( Origin gPackager )
				)
				( attribute "CDS_PART_NAME" "CAP_A_0603V-22.0UF,4V,20%,X6S,A"
					( Origin gPackager )
				)
				( objectStatus "C4P8" )
				( pin "a"
					( attribute "PN" "1"
						( Origin gPackager )
					)
					( objectStatus "C4P8.1" )
				)
				( pin "b"
					( attribute "PN" "2"
						( Origin gPackager )
					)
					( objectStatus "C4P8.2" )
				)
			)
			( gate "@baseboard_fab2_lib.baseboard_fab2(sch_1):page42_i179"
				( attribute "CDS_LIB" "dev_discrete"
					( Origin gPackager )
				)
				( attribute "CDS_LOCATION" "C5D53"
					( Origin gPackager )
				)
				( attribute "CDS_SEC" "1"
					( Origin gPackager )
				)
				( attribute "LOCATION" "C5D53"
					( Origin gFrontEnd )
				)
				( attribute "MATERIAL" "X6S"
					( Origin gFrontEnd )
				)
				( attribute "PACK_TYPE" "0603V"
					( Origin gFrontEnd )
				)
				( attribute "PART_NUMBER" "E15431-004"
					( Origin gFrontEnd )
				)
				( attribute "PHYS_PAGE" "42"
					( Origin gFrontEnd )
				)
				( attribute "ROOM" "PVCCIN_CPU0_DECAP_VR"
					( Origin gFrontEnd )
				)
				( attribute "ROT" "0"
					( Origin gFrontEnd )
				)
				( attribute "SEC" "1"
					( Origin gPackager )
				)
				( attribute "TOLERANCE" "20%"
					( Origin gFrontEnd )
				)
				( attribute "VALUE" "22.0UF"
					( Origin gFrontEnd )
				)
				( attribute "VER" "1"
					( Origin gFrontEnd )
				)
				( attribute "VOLTAGE" "4V"
					( Units "uVoltage" "V" 1.000000)
					( Origin gFrontEnd )
				)
				( attribute "XY" "(-2150,3850)"
					( Origin gFrontEnd )
				)
				( attribute "CHIPS_PART_NAME" "CAP_A"
					( Origin gPackager )
				)
				( attribute "CDS_PART_NAME" "CAP_A_0603V-22.0UF,4V,20%,X6S,A"
					( Origin gPackager )
				)
				( objectStatus "C5D53" )
				( pin "a"
					( attribute "PN" "1"
						( Origin gPackager )
					)
					( objectStatus "C5D53.1" )
				)
				( pin "b"
					( attribute "PN" "2"
						( Origin gPackager )
					)
					( objectStatus "C5D53.2" )
				)
			)
			( gate "@baseboard_fab2_lib.baseboard_fab2(sch_1):page42_i180"
				( attribute "CDS_LIB" "dev_discrete"
					( Origin gPackager )
				)
				( attribute "CDS_LOCATION" "C5D52"
					( Origin gPackager )
				)
				( attribute "CDS_SEC" "1"
					( Origin gPackager )
				)
				( attribute "LOCATION" "C5D52"
					( Origin gFrontEnd )
				)
				( attribute "MATERIAL" "X6S"
					( Origin gFrontEnd )
				)
				( attribute "PACK_TYPE" "0603V"
					( Origin gFrontEnd )
				)
				( attribute "PART_NUMBER" "E15431-004"
					( Origin gFrontEnd )
				)
				( attribute "PHYS_PAGE" "42"
					( Origin gFrontEnd )
				)
				( attribute "ROOM" "PVCCIN_CPU0_DECAP_VR"
					( Origin gFrontEnd )
				)
				( attribute "ROT" "0"
					( Origin gFrontEnd )
				)
				( attribute "SEC" "1"
					( Origin gPackager )
				)
				( attribute "TOLERANCE" "20%"
					( Origin gFrontEnd )
				)
				( attribute "VALUE" "22.0UF"
					( Origin gFrontEnd )
				)
				( attribute "VER" "1"
					( Origin gFrontEnd )
				)
				( attribute "VOLTAGE" "4V"
					( Units "uVoltage" "V" 1.000000)
					( Origin gFrontEnd )
				)
				( attribute "XY" "(-2525,3825)"
					( Origin gFrontEnd )
				)
				( attribute "CHIPS_PART_NAME" "CAP_A"
					( Origin gPackager )
				)
				( attribute "CDS_PART_NAME" "CAP_A_0603V-22.0UF,4V,20%,X6S,A"
					( Origin gPackager )
				)
				( objectStatus "C5D52" )
				( pin "a"
					( attribute "PN" "1"
						( Origin gPackager )
					)
					( objectStatus "C5D52.1" )
				)
				( pin "b"
					( attribute "PN" "2"
						( Origin gPackager )
					)
					( objectStatus "C5D52.2" )
				)
			)
			( gate "@baseboard_fab2_lib.baseboard_fab2(sch_1):page42_i183"
				( attribute "BOM_COST" "PROC_SOCKET"
					( Origin gFrontEnd )
				)
				( attribute "CDS_LIB" "mstr_discrete"
					( Origin gPackager )
				)
				( attribute "CDS_LOCATION" "C5P12"
					( Origin gPackager )
				)
				( attribute "CDS_SEC" "1"
					( Origin gPackager )
				)
				( attribute "LOCATION" "C5P12"
					( Origin gFrontEnd )
				)
				( attribute "MATERIAL" "X6S"
					( Origin gFrontEnd )
				)
				( attribute "PACK_TYPE" "0805"
					( Origin gFrontEnd )
				)
				( attribute "PART_NUMBER" "C95333-006"
					( Origin gFrontEnd )
				)
				( attribute "PHYS_PAGE" "42"
					( Origin gFrontEnd )
				)
				( attribute "ROOM" "PVCCIN_CPU0_DECAP_VR"
					( Origin gFrontEnd )
				)
				( attribute "ROT" "0"
					( Origin gFrontEnd )
				)
				( attribute "SEC" "1"
					( Origin gPackager )
				)
				( attribute "TOLERANCE" "20%"
					( Origin gFrontEnd )
				)
				( attribute "VALUE" "47UF"
					( Origin gFrontEnd )
				)
				( attribute "VER" "1"
					( Origin gFrontEnd )
				)
				( attribute "VOLTAGE" "4V"
					( Units "uVoltage" "V" 1.000000)
					( Origin gFrontEnd )
				)
				( attribute "XY" "(-375,2150)"
					( Origin gFrontEnd )
				)
				( attribute "CHIPS_PART_NAME" "CAP"
					( Origin gPackager )
				)
				( attribute "CDS_PART_NAME" "CAP_0805-47UF,4V,20%,X6S,C9533A"
					( Origin gPackager )
				)
				( objectStatus "C5P12" )
				( pin "a"
					( attribute "PN" "1"
						( Origin gPackager )
					)
					( objectStatus "C5P12.1" )
				)
				( pin "b"
					( attribute "PN" "2"
						( Origin gPackager )
					)
					( objectStatus "C5P12.2" )
				)
			)
			( gate "@baseboard_fab2_lib.baseboard_fab2(sch_1):page42_i184"
				( attribute "BOM_COST" "PROC_SOCKET"
					( Origin gFrontEnd )
				)
				( attribute "CDS_LIB" "mstr_discrete"
					( Origin gPackager )
				)
				( attribute "CDS_LOCATION" "C5P21"
					( Origin gPackager )
				)
				( attribute "CDS_SEC" "1"
					( Origin gPackager )
				)
				( attribute "LOCATION" "C5P21"
					( Origin gFrontEnd )
				)
				( attribute "MATERIAL" "X6S"
					( Origin gFrontEnd )
				)
				( attribute "PACK_TYPE" "0805"
					( Origin gFrontEnd )
				)
				( attribute "PART_NUMBER" "C95333-006"
					( Origin gFrontEnd )
				)
				( attribute "PHYS_PAGE" "42"
					( Origin gFrontEnd )
				)
				( attribute "ROOM" "PVCCIN_CPU0_DECAP_VR"
					( Origin gFrontEnd )
				)
				( attribute "ROT" "0"
					( Origin gFrontEnd )
				)
				( attribute "SEC" "1"
					( Origin gPackager )
				)
				( attribute "TOLERANCE" "20%"
					( Origin gFrontEnd )
				)
				( attribute "VALUE" "47UF"
					( Origin gFrontEnd )
				)
				( attribute "VER" "1"
					( Origin gFrontEnd )
				)
				( attribute "VOLTAGE" "4V"
					( Units "uVoltage" "V" 1.000000)
					( Origin gFrontEnd )
				)
				( attribute "XY" "(-625,2150)"
					( Origin gFrontEnd )
				)
				( attribute "CHIPS_PART_NAME" "CAP"
					( Origin gPackager )
				)
				( attribute "CDS_PART_NAME" "CAP_0805-47UF,4V,20%,X6S,C9533A"
					( Origin gPackager )
				)
				( objectStatus "C5P21" )
				( pin "a"
					( attribute "PN" "1"
						( Origin gPackager )
					)
					( objectStatus "C5P21.1" )
				)
				( pin "b"
					( attribute "PN" "2"
						( Origin gPackager )
					)
					( objectStatus "C5P21.2" )
				)
			)
			( gate "@baseboard_fab2_lib.baseboard_fab2(sch_1):page42_i185"
				( attribute "BOM_COST" "PROC_SOCKET"
					( Origin gFrontEnd )
				)
				( attribute "CDS_LIB" "mstr_discrete"
					( Origin gPackager )
				)
				( attribute "CDS_LOCATION" "C5P20"
					( Origin gPackager )
				)
				( attribute "CDS_SEC" "1"
					( Origin gPackager )
				)
				( attribute "LOCATION" "C5P20"
					( Origin gFrontEnd )
				)
				( attribute "MATERIAL" "X6S"
					( Origin gFrontEnd )
				)
				( attribute "PACK_TYPE" "0805"
					( Origin gFrontEnd )
				)
				( attribute "PART_NUMBER" "C95333-006"
					( Origin gFrontEnd )
				)
				( attribute "PHYS_PAGE" "42"
					( Origin gFrontEnd )
				)
				( attribute "ROOM" "PVCCIN_CPU0_DECAP_VR"
					( Origin gFrontEnd )
				)
				( attribute "ROT" "0"
					( Origin gFrontEnd )
				)
				( attribute "SEC" "1"
					( Origin gPackager )
				)
				( attribute "TOLERANCE" "20%"
					( Origin gFrontEnd )
				)
				( attribute "VALUE" "47UF"
					( Origin gFrontEnd )
				)
				( attribute "VER" "1"
					( Origin gFrontEnd )
				)
				( attribute "VOLTAGE" "4V"
					( Units "uVoltage" "V" 1.000000)
					( Origin gFrontEnd )
				)
				( attribute "XY" "(-875,2150)"
					( Origin gFrontEnd )
				)
				( attribute "CHIPS_PART_NAME" "CAP"
					( Origin gPackager )
				)
				( attribute "CDS_PART_NAME" "CAP_0805-47UF,4V,20%,X6S,C9533A"
					( Origin gPackager )
				)
				( objectStatus "C5P20" )
				( pin "a"
					( attribute "PN" "1"
						( Origin gPackager )
					)
					( objectStatus "C5P20.1" )
				)
				( pin "b"
					( attribute "PN" "2"
						( Origin gPackager )
					)
					( objectStatus "C5P20.2" )
				)
			)
			( gate "@baseboard_fab2_lib.baseboard_fab2(sch_1):page42_i186"
				( attribute "BOM_COST" "PROC_SOCKET"
					( Origin gFrontEnd )
				)
				( attribute "CDS_LIB" "mstr_discrete"
					( Origin gPackager )
				)
				( attribute "CDS_LOCATION" "C5P13"
					( Origin gPackager )
				)
				( attribute "CDS_SEC" "1"
					( Origin gPackager )
				)
				( attribute "LOCATION" "C5P13"
					( Origin gFrontEnd )
				)
				( attribute "MATERIAL" "X6S"
					( Origin gFrontEnd )
				)
				( attribute "PACK_TYPE" "0805"
					( Origin gFrontEnd )
				)
				( attribute "PART_NUMBER" "C95333-006"
					( Origin gFrontEnd )
				)
				( attribute "PHYS_PAGE" "42"
					( Origin gFrontEnd )
				)
				( attribute "ROOM" "PVCCIN_CPU0_DECAP_VR"
					( Origin gFrontEnd )
				)
				( attribute "ROT" "0"
					( Origin gFrontEnd )
				)
				( attribute "SEC" "1"
					( Origin gPackager )
				)
				( attribute "TOLERANCE" "20%"
					( Origin gFrontEnd )
				)
				( attribute "VALUE" "47UF"
					( Origin gFrontEnd )
				)
				( attribute "VER" "1"
					( Origin gFrontEnd )
				)
				( attribute "VOLTAGE" "4V"
					( Units "uVoltage" "V" 1.000000)
					( Origin gFrontEnd )
				)
				( attribute "XY" "(-1125,2150)"
					( Origin gFrontEnd )
				)
				( attribute "CHIPS_PART_NAME" "CAP"
					( Origin gPackager )
				)
				( attribute "CDS_PART_NAME" "CAP_0805-47UF,4V,20%,X6S,C9533A"
					( Origin gPackager )
				)
				( objectStatus "C5P13" )
				( pin "a"
					( attribute "PN" "1"
						( Origin gPackager )
					)
					( objectStatus "C5P13.1" )
				)
				( pin "b"
					( attribute "PN" "2"
						( Origin gPackager )
					)
					( objectStatus "C5P13.2" )
				)
			)
			( gate "@baseboard_fab2_lib.baseboard_fab2(sch_1):page42_i187"
				( attribute "BOM_COST" "PROC_SOCKET"
					( Origin gFrontEnd )
				)
				( attribute "CDS_LIB" "mstr_discrete"
					( Origin gPackager )
				)
				( attribute "CDS_LOCATION" "C5P15"
					( Origin gPackager )
				)
				( attribute "CDS_SEC" "1"
					( Origin gPackager )
				)
				( attribute "LOCATION" "C5P15"
					( Origin gFrontEnd )
				)
				( attribute "MATERIAL" "X6S"
					( Origin gFrontEnd )
				)
				( attribute "PACK_TYPE" "0805"
					( Origin gFrontEnd )
				)
				( attribute "PART_NUMBER" "C95333-006"
					( Origin gFrontEnd )
				)
				( attribute "PHYS_PAGE" "42"
					( Origin gFrontEnd )
				)
				( attribute "ROOM" "PVCCIN_CPU0_DECAP_VR"
					( Origin gFrontEnd )
				)
				( attribute "ROT" "0"
					( Origin gFrontEnd )
				)
				( attribute "SEC" "1"
					( Origin gPackager )
				)
				( attribute "TOLERANCE" "20%"
					( Origin gFrontEnd )
				)
				( attribute "VALUE" "47UF"
					( Origin gFrontEnd )
				)
				( attribute "VER" "1"
					( Origin gFrontEnd )
				)
				( attribute "VOLTAGE" "4V"
					( Units "uVoltage" "V" 1.000000)
					( Origin gFrontEnd )
				)
				( attribute "XY" "(-6700,1575)"
					( Origin gFrontEnd )
				)
				( attribute "CHIPS_PART_NAME" "CAP"
					( Origin gPackager )
				)
				( attribute "CDS_PART_NAME" "CAP_0805-47UF,4V,20%,X6S,C9533A"
					( Origin gPackager )
				)
				( objectStatus "C5P15" )
				( pin "a"
					( attribute "PN" "1"
						( Origin gPackager )
					)
					( objectStatus "C5P15.1" )
				)
				( pin "b"
					( attribute "PN" "2"
						( Origin gPackager )
					)
					( objectStatus "C5P15.2" )
				)
			)
			( gate "@baseboard_fab2_lib.baseboard_fab2(sch_1):page42_i188"
				( attribute "BOM_COST" "PROC_SOCKET"
					( Origin gFrontEnd )
				)
				( attribute "CDS_LIB" "mstr_discrete"
					( Origin gPackager )
				)
				( attribute "CDS_LOCATION" "C5P16"
					( Origin gPackager )
				)
				( attribute "CDS_SEC" "1"
					( Origin gPackager )
				)
				( attribute "LOCATION" "C5P16"
					( Origin gFrontEnd )
				)
				( attribute "MATERIAL" "X6S"
					( Origin gFrontEnd )
				)
				( attribute "PACK_TYPE" "0805"
					( Origin gFrontEnd )
				)
				( attribute "PART_NUMBER" "C95333-006"
					( Origin gFrontEnd )
				)
				( attribute "PHYS_PAGE" "42"
					( Origin gFrontEnd )
				)
				( attribute "ROOM" "PVCCIN_CPU0_DECAP_VR"
					( Origin gFrontEnd )
				)
				( attribute "ROT" "0"
					( Origin gFrontEnd )
				)
				( attribute "SEC" "1"
					( Origin gPackager )
				)
				( attribute "TOLERANCE" "20%"
					( Origin gFrontEnd )
				)
				( attribute "VALUE" "47UF"
					( Origin gFrontEnd )
				)
				( attribute "VER" "1"
					( Origin gFrontEnd )
				)
				( attribute "VOLTAGE" "4V"
					( Units "uVoltage" "V" 1.000000)
					( Origin gFrontEnd )
				)
				( attribute "XY" "(-6700,2225)"
					( Origin gFrontEnd )
				)
				( attribute "CHIPS_PART_NAME" "CAP"
					( Origin gPackager )
				)
				( attribute "CDS_PART_NAME" "CAP_0805-47UF,4V,20%,X6S,C9533A"
					( Origin gPackager )
				)
				( objectStatus "C5P16" )
				( pin "a"
					( attribute "PN" "1"
						( Origin gPackager )
					)
					( objectStatus "C5P16.1" )
				)
				( pin "b"
					( attribute "PN" "2"
						( Origin gPackager )
					)
					( objectStatus "C5P16.2" )
				)
			)
			( gate "@baseboard_fab2_lib.baseboard_fab2(sch_1):page42_i189"
				( attribute "BOM_COST" "PROC_SOCKET"
					( Origin gFrontEnd )
				)
				( attribute "CDS_LIB" "mstr_discrete"
					( Origin gPackager )
				)
				( attribute "CDS_LOCATION" "C5P3"
					( Origin gPackager )
				)
				( attribute "CDS_SEC" "1"
					( Origin gPackager )
				)
				( attribute "LOCATION" "C5P3"
					( Origin gFrontEnd )
				)
				( attribute "MATERIAL" "X6S"
					( Origin gFrontEnd )
				)
				( attribute "PACK_TYPE" "0805"
					( Origin gFrontEnd )
				)
				( attribute "PART_NUMBER" "C95333-006"
					( Origin gFrontEnd )
				)
				( attribute "PHYS_PAGE" "42"
					( Origin gFrontEnd )
				)
				( attribute "ROOM" "PVCCIN_CPU0_DECAP_VR"
					( Origin gFrontEnd )
				)
				( attribute "ROT" "0"
					( Origin gFrontEnd )
				)
				( attribute "SEC" "1"
					( Origin gPackager )
				)
				( attribute "TOLERANCE" "20%"
					( Origin gFrontEnd )
				)
				( attribute "VALUE" "47UF"
					( Origin gFrontEnd )
				)
				( attribute "VER" "1"
					( Origin gFrontEnd )
				)
				( attribute "VOLTAGE" "4V"
					( Units "uVoltage" "V" 1.000000)
					( Origin gFrontEnd )
				)
				( attribute "XY" "(-7725,925)"
					( Origin gFrontEnd )
				)
				( attribute "CHIPS_PART_NAME" "CAP"
					( Origin gPackager )
				)
				( attribute "CDS_PART_NAME" "CAP_0805-47UF,4V,20%,X6S,C9533A"
					( Origin gPackager )
				)
				( objectStatus "C5P3" )
				( pin "a"
					( attribute "PN" "1"
						( Origin gPackager )
					)
					( objectStatus "C5P3.1" )
				)
				( pin "b"
					( attribute "PN" "2"
						( Origin gPackager )
					)
					( objectStatus "C5P3.2" )
				)
			)
			( gate "@baseboard_fab2_lib.baseboard_fab2(sch_1):page42_i190"
				( attribute "BOM_COST" "PROC_SOCKET"
					( Origin gFrontEnd )
				)
				( attribute "CDS_LIB" "mstr_discrete"
					( Origin gPackager )
				)
				( attribute "CDS_LOCATION" "C5P17"
					( Origin gPackager )
				)
				( attribute "CDS_SEC" "1"
					( Origin gPackager )
				)
				( attribute "LOCATION" "C5P17"
					( Origin gFrontEnd )
				)
				( attribute "MATERIAL" "X6S"
					( Origin gFrontEnd )
				)
				( attribute "PACK_TYPE" "0805"
					( Origin gFrontEnd )
				)
				( attribute "PART_NUMBER" "C95333-006"
					( Origin gFrontEnd )
				)
				( attribute "PHYS_PAGE" "42"
					( Origin gFrontEnd )
				)
				( attribute "ROOM" "PVCCIN_CPU0_DECAP_VR"
					( Origin gFrontEnd )
				)
				( attribute "ROT" "0"
					( Origin gFrontEnd )
				)
				( attribute "SEC" "1"
					( Origin gPackager )
				)
				( attribute "TOLERANCE" "20%"
					( Origin gFrontEnd )
				)
				( attribute "VALUE" "47UF"
					( Origin gFrontEnd )
				)
				( attribute "VER" "1"
					( Origin gFrontEnd )
				)
				( attribute "VOLTAGE" "4V"
					( Units "uVoltage" "V" 1.000000)
					( Origin gFrontEnd )
				)
				( attribute "XY" "(-6350,1575)"
					( Origin gFrontEnd )
				)
				( attribute "CHIPS_PART_NAME" "CAP"
					( Origin gPackager )
				)
				( attribute "CDS_PART_NAME" "CAP_0805-47UF,4V,20%,X6S,C9533A"
					( Origin gPackager )
				)
				( objectStatus "C5P17" )
				( pin "a"
					( attribute "PN" "1"
						( Origin gPackager )
					)
					( objectStatus "C5P17.1" )
				)
				( pin "b"
					( attribute "PN" "2"
						( Origin gPackager )
					)
					( objectStatus "C5P17.2" )
				)
			)
			( gate "@baseboard_fab2_lib.baseboard_fab2(sch_1):page43_i1"
				( attribute "BOM_COST" "MEM"
					( Origin gFrontEnd )
				)
				( attribute "CDS_LIB" "mstr_sconn"
					( Origin gPackager )
				)
				( attribute "CDS_LOCATION" "J4G1"
					( Origin gPackager )
				)
				( attribute "CDS_SEC" "1"
					( Origin gPackager )
				)
				( attribute "LOCATION" "J4G1"
					( Origin gFrontEnd )
				)
				( attribute "MATERIAL" "SCONN"
					( Origin gFrontEnd )
				)
				( attribute "PACK_TYPE" "PIP"
					( Origin gFrontEnd )
				)
				( attribute "PART_NUMBER" "H44441-004"
					( Origin gFrontEnd )
				)
				( attribute "PHYS_PAGE" "43"
					( Origin gFrontEnd )
				)
				( attribute "ROOM" "DDR4_CH_A"
					( Origin gFrontEnd )
				)
				( attribute "ROT" "0"
					( Origin gFrontEnd )
				)
				( attribute "SEC" "1"
					( Origin gFrontEnd )
				)
				( attribute "SEC_TYPE" "PIP"
					( Origin gFrontEnd )
				)
				( attribute "VER" "1"
					( Origin gFrontEnd )
				)
				( attribute "XY" "(-2400,2750)"
					( Origin gFrontEnd )
				)
				( attribute "CHIPS_PART_NAME" "SCONN288_H44441004"
					( Origin gPackager )
				)
				( attribute "CDS_PART_NAME" "SCONN288_H44441004_PIP-SCONN,HA"
					( Origin gPackager )
				)
				( objectStatus "J4G1" )
				( pin "a0"
					( attribute "PN" "79"
						( Origin gPackager )
					)
					( objectStatus "J4G1.79" )
				)
				( pin "a1"
					( attribute "PN" "72"
						( Origin gPackager )
					)
					( objectStatus "J4G1.72" )
				)
				( pin "a2"
					( attribute "PN" "216"
						( Origin gPackager )
					)
					( objectStatus "J4G1.216" )
				)
				( pin "a3"
					( attribute "PN" "71"
						( Origin gPackager )
					)
					( objectStatus "J4G1.71" )
				)
				( pin "a4"
					( attribute "PN" "214"
						( Origin gPackager )
					)
					( objectStatus "J4G1.214" )
				)
				( pin "a5"
					( attribute "PN" "213"
						( Origin gPackager )
					)
					( objectStatus "J4G1.213" )
				)
				( pin "a6"
					( attribute "PN" "69"
						( Origin gPackager )
					)
					( objectStatus "J4G1.69" )
				)
				( pin "a7"
					( attribute "PN" "211"
						( Origin gPackager )
					)
					( objectStatus "J4G1.211" )
				)
				( pin "a8"
					( attribute "PN" "68"
						( Origin gPackager )
					)
					( objectStatus "J4G1.68" )
				)
				( pin "a9"
					( attribute "PN" "66"
						( Origin gPackager )
					)
					( objectStatus "J4G1.66" )
				)
				( pin "a10"
					( attribute "PN" "225"
						( Origin gPackager )
					)
					( objectStatus "J4G1.225" )
				)
				( pin "a11"
					( attribute "PN" "210"
						( Origin gPackager )
					)
					( objectStatus "J4G1.210" )
				)
				( pin "a12"
					( attribute "PN" "65"
						( Origin gPackager )
					)
					( objectStatus "J4G1.65" )
				)
				( pin "a13"
					( attribute "PN" "232"
						( Origin gPackager )
					)
					( objectStatus "J4G1.232" )
				)
				( pin "a14_we_n"
					( attribute "PN" "228"
						( Origin gPackager )
					)
					( objectStatus "J4G1.228" )
				)
				( pin "a15_cas_n"
					( attribute "PN" "86"
						( Origin gPackager )
					)
					( objectStatus "J4G1.86" )
				)
				( pin "a16_ras_n"
					( attribute "PN" "82"
						( Origin gPackager )
					)
					( objectStatus "J4G1.82" )
				)
				( pin "a17"
					( attribute "PN" "234"
						( Origin gPackager )
					)
					( objectStatus "J4G1.234" )
				)
				( pin "act_n"
					( attribute "PN" "62"
						( Origin gPackager )
					)
					( objectStatus "J4G1.62" )
				)
				( pin "alert_n"
					( attribute "PN" "208"
						( Origin gPackager )
					)
					( objectStatus "J4G1.208" )
				)
				( pin "ba(0)"
					( attribute "PN" "81"
						( Origin gPackager )
					)
					( objectStatus "J4G1.81" )
				)
				( pin "ba(1)"
					( attribute "PN" "224"
						( Origin gPackager )
					)
					( objectStatus "J4G1.224" )
				)
				( pin "bg(0)"
					( attribute "PN" "63"
						( Origin gPackager )
					)
					( objectStatus "J4G1.63" )
				)
				( pin "bg(1)"
					( attribute "PN" "207"
						( Origin gPackager )
					)
					( objectStatus "J4G1.207" )
				)
				( pin "c(2)"
					( attribute "PN" "235"
						( Origin gPackager )
					)
					( objectStatus "J4G1.235" )
				)
				( pin "cb(0)"
					( attribute "PN" "49"
						( Origin gPackager )
					)
					( objectStatus "J4G1.49" )
				)
				( pin "cb(1)"
					( attribute "PN" "194"
						( Origin gPackager )
					)
					( objectStatus "J4G1.194" )
				)
				( pin "cb(2)"
					( attribute "PN" "56"
						( Origin gPackager )
					)
					( objectStatus "J4G1.56" )
				)
				( pin "cb(3)"
					( attribute "PN" "201"
						( Origin gPackager )
					)
					( objectStatus "J4G1.201" )
				)
				( pin "cb(4)"
					( attribute "PN" "47"
						( Origin gPackager )
					)
					( objectStatus "J4G1.47" )
				)
				( pin "cb(5)"
					( attribute "PN" "192"
						( Origin gPackager )
					)
					( objectStatus "J4G1.192" )
				)
				( pin "cb(6)"
					( attribute "PN" "54"
						( Origin gPackager )
					)
					( objectStatus "J4G1.54" )
				)
				( pin "cb(7)"
					( attribute "PN" "199"
						( Origin gPackager )
					)
					( objectStatus "J4G1.199" )
				)
				( pin "ck0n"
					( attribute "PN" "75"
						( Origin gPackager )
					)
					( objectStatus "J4G1.75" )
				)
				( pin "ck0p"
					( attribute "PN" "74"
						( Origin gPackager )
					)
					( objectStatus "J4G1.74" )
				)
				( pin "ck1n"
					( attribute "PN" "219"
						( Origin gPackager )
					)
					( objectStatus "J4G1.219" )
				)
				( pin "ck1p"
					( attribute "PN" "218"
						( Origin gPackager )
					)
					( objectStatus "J4G1.218" )
				)
				( pin "cke(0)"
					( attribute "PN" "60"
						( Origin gPackager )
					)
					( objectStatus "J4G1.60" )
				)
				( pin "cke(1)"
					( attribute "PN" "203"
						( Origin gPackager )
					)
					( objectStatus "J4G1.203" )
				)
				( pin "dq(0)"
					( attribute "PN" "5"
						( Origin gPackager )
					)
					( objectStatus "J4G1.5" )
				)
				( pin "dq(1)"
					( attribute "PN" "150"
						( Origin gPackager )
					)
					( objectStatus "J4G1.150" )
				)
				( pin "dq(2)"
					( attribute "PN" "12"
						( Origin gPackager )
					)
					( objectStatus "J4G1.12" )
				)
				( pin "dq(3)"
					( attribute "PN" "157"
						( Origin gPackager )
					)
					( objectStatus "J4G1.157" )
				)
				( pin "dq(4)"
					( attribute "PN" "3"
						( Origin gPackager )
					)
					( objectStatus "J4G1.3" )
				)
				( pin "dq(5)"
					( attribute "PN" "148"
						( Origin gPackager )
					)
					( objectStatus "J4G1.148" )
				)
				( pin "dq(6)"
					( attribute "PN" "10"
						( Origin gPackager )
					)
					( objectStatus "J4G1.10" )
				)
				( pin "dq(7)"
					( attribute "PN" "155"
						( Origin gPackager )
					)
					( objectStatus "J4G1.155" )
				)
				( pin "dq(8)"
					( attribute "PN" "16"
						( Origin gPackager )
					)
					( objectStatus "J4G1.16" )
				)
				( pin "dq(9)"
					( attribute "PN" "161"
						( Origin gPackager )
					)
					( objectStatus "J4G1.161" )
				)
				( pin "dq(10)"
					( attribute "PN" "23"
						( Origin gPackager )
					)
					( objectStatus "J4G1.23" )
				)
				( pin "dq(11)"
					( attribute "PN" "168"
						( Origin gPackager )
					)
					( objectStatus "J4G1.168" )
				)
				( pin "dq(12)"
					( attribute "PN" "14"
						( Origin gPackager )
					)
					( objectStatus "J4G1.14" )
				)
				( pin "dq(13)"
					( attribute "PN" "159"
						( Origin gPackager )
					)
					( objectStatus "J4G1.159" )
				)
				( pin "dq(14)"
					( attribute "PN" "21"
						( Origin gPackager )
					)
					( objectStatus "J4G1.21" )
				)
				( pin "dq(15)"
					( attribute "PN" "166"
						( Origin gPackager )
					)
					( objectStatus "J4G1.166" )
				)
				( pin "dq(16)"
					( attribute "PN" "27"
						( Origin gPackager )
					)
					( objectStatus "J4G1.27" )
				)
				( pin "dq(17)"
					( attribute "PN" "172"
						( Origin gPackager )
					)
					( objectStatus "J4G1.172" )
				)
				( pin "dq(18)"
					( attribute "PN" "34"
						( Origin gPackager )
					)
					( objectStatus "J4G1.34" )
				)
				( pin "dq(19)"
					( attribute "PN" "179"
						( Origin gPackager )
					)
					( objectStatus "J4G1.179" )
				)
				( pin "dq(20)"
					( attribute "PN" "25"
						( Origin gPackager )
					)
					( objectStatus "J4G1.25" )
				)
				( pin "dq(21)"
					( attribute "PN" "170"
						( Origin gPackager )
					)
					( objectStatus "J4G1.170" )
				)
				( pin "dq(22)"
					( attribute "PN" "32"
						( Origin gPackager )
					)
					( objectStatus "J4G1.32" )
				)
				( pin "dq(23)"
					( attribute "PN" "177"
						( Origin gPackager )
					)
					( objectStatus "J4G1.177" )
				)
				( pin "dq(24)"
					( attribute "PN" "38"
						( Origin gPackager )
					)
					( objectStatus "J4G1.38" )
				)
				( pin "dq(25)"
					( attribute "PN" "183"
						( Origin gPackager )
					)
					( objectStatus "J4G1.183" )
				)
				( pin "dq(26)"
					( attribute "PN" "45"
						( Origin gPackager )
					)
					( objectStatus "J4G1.45" )
				)
				( pin "dq(27)"
					( attribute "PN" "190"
						( Origin gPackager )
					)
					( objectStatus "J4G1.190" )
				)
				( pin "dq(28)"
					( attribute "PN" "36"
						( Origin gPackager )
					)
					( objectStatus "J4G1.36" )
				)
				( pin "dq(29)"
					( attribute "PN" "181"
						( Origin gPackager )
					)
					( objectStatus "J4G1.181" )
				)
				( pin "dq(30)"
					( attribute "PN" "43"
						( Origin gPackager )
					)
					( objectStatus "J4G1.43" )
				)
				( pin "dq(31)"
					( attribute "PN" "188"
						( Origin gPackager )
					)
					( objectStatus "J4G1.188" )
				)
				( pin "dq(32)"
					( attribute "PN" "97"
						( Origin gPackager )
					)
					( objectStatus "J4G1.97" )
				)
				( pin "dq(33)"
					( attribute "PN" "242"
						( Origin gPackager )
					)
					( objectStatus "J4G1.242" )
				)
				( pin "dq(34)"
					( attribute "PN" "104"
						( Origin gPackager )
					)
					( objectStatus "J4G1.104" )
				)
				( pin "dq(35)"
					( attribute "PN" "249"
						( Origin gPackager )
					)
					( objectStatus "J4G1.249" )
				)
				( pin "dq(36)"
					( attribute "PN" "95"
						( Origin gPackager )
					)
					( objectStatus "J4G1.95" )
				)
				( pin "dq(37)"
					( attribute "PN" "240"
						( Origin gPackager )
					)
					( objectStatus "J4G1.240" )
				)
				( pin "dq(38)"
					( attribute "PN" "102"
						( Origin gPackager )
					)
					( objectStatus "J4G1.102" )
				)
				( pin "dq(39)"
					( attribute "PN" "247"
						( Origin gPackager )
					)
					( objectStatus "J4G1.247" )
				)
				( pin "dq(40)"
					( attribute "PN" "108"
						( Origin gPackager )
					)
					( objectStatus "J4G1.108" )
				)
				( pin "dq(41)"
					( attribute "PN" "253"
						( Origin gPackager )
					)
					( objectStatus "J4G1.253" )
				)
				( pin "dq(42)"
					( attribute "PN" "115"
						( Origin gPackager )
					)
					( objectStatus "J4G1.115" )
				)
				( pin "dq(43)"
					( attribute "PN" "260"
						( Origin gPackager )
					)
					( objectStatus "J4G1.260" )
				)
				( pin "dq(44)"
					( attribute "PN" "106"
						( Origin gPackager )
					)
					( objectStatus "J4G1.106" )
				)
				( pin "dq(45)"
					( attribute "PN" "251"
						( Origin gPackager )
					)
					( objectStatus "J4G1.251" )
				)
				( pin "dq(46)"
					( attribute "PN" "113"
						( Origin gPackager )
					)
					( objectStatus "J4G1.113" )
				)
				( pin "dq(47)"
					( attribute "PN" "258"
						( Origin gPackager )
					)
					( objectStatus "J4G1.258" )
				)
				( pin "dq(48)"
					( attribute "PN" "119"
						( Origin gPackager )
					)
					( objectStatus "J4G1.119" )
				)
				( pin "dq(49)"
					( attribute "PN" "264"
						( Origin gPackager )
					)
					( objectStatus "J4G1.264" )
				)
				( pin "dq(50)"
					( attribute "PN" "126"
						( Origin gPackager )
					)
					( objectStatus "J4G1.126" )
				)
				( pin "dq(51)"
					( attribute "PN" "271"
						( Origin gPackager )
					)
					( objectStatus "J4G1.271" )
				)
				( pin "dq(52)"
					( attribute "PN" "117"
						( Origin gPackager )
					)
					( objectStatus "J4G1.117" )
				)
				( pin "dq(53)"
					( attribute "PN" "262"
						( Origin gPackager )
					)
					( objectStatus "J4G1.262" )
				)
				( pin "dq(54)"
					( attribute "PN" "124"
						( Origin gPackager )
					)
					( objectStatus "J4G1.124" )
				)
				( pin "dq(55)"
					( attribute "PN" "269"
						( Origin gPackager )
					)
					( objectStatus "J4G1.269" )
				)
				( pin "dq(56)"
					( attribute "PN" "130"
						( Origin gPackager )
					)
					( objectStatus "J4G1.130" )
				)
				( pin "dq(57)"
					( attribute "PN" "275"
						( Origin gPackager )
					)
					( objectStatus "J4G1.275" )
				)
				( pin "dq(58)"
					( attribute "PN" "137"
						( Origin gPackager )
					)
					( objectStatus "J4G1.137" )
				)
				( pin "dq(59)"
					( attribute "PN" "282"
						( Origin gPackager )
					)
					( objectStatus "J4G1.282" )
				)
				( pin "dq(60)"
					( attribute "PN" "128"
						( Origin gPackager )
					)
					( objectStatus "J4G1.128" )
				)
				( pin "dq(61)"
					( attribute "PN" "273"
						( Origin gPackager )
					)
					( objectStatus "J4G1.273" )
				)
				( pin "dq(62)"
					( attribute "PN" "135"
						( Origin gPackager )
					)
					( objectStatus "J4G1.135" )
				)
				( pin "dq(63)"
					( attribute "PN" "280"
						( Origin gPackager )
					)
					( objectStatus "J4G1.280" )
				)
				( pin "event_n"
					( attribute "PN" "78"
						( Origin gPackager )
					)
					( objectStatus "J4G1.78" )
				)
				( pin "odt(0)"
					( attribute "PN" "87"
						( Origin gPackager )
					)
					( objectStatus "J4G1.87" )
				)
				( pin "odt(1)"
					( attribute "PN" "91"
						( Origin gPackager )
					)
					( objectStatus "J4G1.91" )
				)
				( pin "par"
					( attribute "PN" "222"
						( Origin gPackager )
					)
					( objectStatus "J4G1.222" )
				)
				( pin "reset_n"
					( attribute "PN" "58"
						( Origin gPackager )
					)
					( objectStatus "J4G1.58" )
				)
				( pin "rfu(0)"
					( attribute "PN" "205"
						( Origin gPackager )
					)
					( objectStatus "J4G1.205" )
				)
				( pin "rfu(1)"
					( attribute "PN" "227"
						( Origin gPackager )
					)
					( objectStatus "J4G1.227" )
				)
				( pin "rfu(2)"
					( attribute "PN" "144"
						( Origin gPackager )
					)
					( objectStatus "J4G1.144" )
				)
				( pin "s0_n"
					( attribute "PN" "84"
						( Origin gPackager )
					)
					( objectStatus "J4G1.84" )
				)
				( pin "s1_n"
					( attribute "PN" "89"
						( Origin gPackager )
					)
					( objectStatus "J4G1.89" )
				)
				( pin "s2_n_c(0)"
					( attribute "PN" "93"
						( Origin gPackager )
					)
					( objectStatus "J4G1.93" )
				)
				( pin "s3_n_c(1)"
					( attribute "PN" "237"
						( Origin gPackager )
					)
					( objectStatus "J4G1.237" )
				)
				( pin "sa(0)"
					( attribute "PN" "139"
						( Origin gPackager )
					)
					( objectStatus "J4G1.139" )
				)
				( pin "sa(1)"
					( attribute "PN" "140"
						( Origin gPackager )
					)
					( objectStatus "J4G1.140" )
				)
				( pin "sa(2)"
					( attribute "PN" "238"
						( Origin gPackager )
					)
					( objectStatus "J4G1.238" )
				)
				( pin "save_n_nc"
					( attribute "PN" "230"
						( Origin gPackager )
					)
					( objectStatus "J4G1.230" )
				)
				( pin "scl"
					( attribute "PN" "141"
						( Origin gPackager )
					)
					( objectStatus "J4G1.141" )
				)
				( pin "sda"
					( attribute "PN" "285"
						( Origin gPackager )
					)
					( objectStatus "J4G1.285" )
				)
				( pin "vddspd"
					( attribute "PN" "284"
						( Origin gPackager )
					)
					( objectStatus "J4G1.284" )
				)
				( pin "vrefca"
					( attribute "PN" "146"
						( Origin gPackager )
					)
					( objectStatus "J4G1.146" )
				)
			)
			( gate "@baseboard_fab2_lib.baseboard_fab2(sch_1):page43_i2"
				( attribute "BOM_COST" "MEM"
					( Origin gFrontEnd )
				)
				( attribute "CDS_LIB" "mstr_sconn"
					( Origin gPackager )
				)
				( attribute "CDS_LOCATION" "J4G1"
					( Origin gPackager )
				)
				( attribute "CDS_SEC" "2"
					( Origin gPackager )
				)
				( attribute "LOCATION" "J4G1"
					( Origin gFrontEnd )
				)
				( attribute "MATERIAL" "SCONN"
					( Origin gFrontEnd )
				)
				( attribute "PACK_TYPE" "PIP"
					( Origin gFrontEnd )
				)
				( attribute "PART_NUMBER" "H44441-004"
					( Origin gFrontEnd )
				)
				( attribute "PHYS_PAGE" "43"
					( Origin gFrontEnd )
				)
				( attribute "ROOM" "DDR4_CH_A"
					( Origin gFrontEnd )
				)
				( attribute "ROT" "0"
					( Origin gFrontEnd )
				)
				( attribute "SEC" "2"
					( Origin gFrontEnd )
				)
				( attribute "SEC_TYPE" "PIP"
					( Origin gFrontEnd )
				)
				( attribute "VER" "2"
					( Origin gFrontEnd )
				)
				( attribute "XY" "(-50,4050)"
					( Origin gFrontEnd )
				)
				( attribute "CHIPS_PART_NAME" "SCONN288_H44441004"
					( Origin gPackager )
				)
				( attribute "CDS_PART_NAME" "SCONN288_H44441004_PIP-SCONN,HA"
					( Origin gPackager )
				)
				( objectStatus "J4G1" )
				( pin "dqs0n"
					( attribute "PN" "152"
						( Origin gPackager )
					)
					( objectStatus "J4G1.152" )
				)
				( pin "dqs0p"
					( attribute "PN" "153"
						( Origin gPackager )
					)
					( objectStatus "J4G1.153" )
				)
				( pin "dqs1n"
					( attribute "PN" "163"
						( Origin gPackager )
					)
					( objectStatus "J4G1.163" )
				)
				( pin "dqs1p"
					( attribute "PN" "164"
						( Origin gPackager )
					)
					( objectStatus "J4G1.164" )
				)
				( pin "dqs2n"
					( attribute "PN" "174"
						( Origin gPackager )
					)
					( objectStatus "J4G1.174" )
				)
				( pin "dqs2p"
					( attribute "PN" "175"
						( Origin gPackager )
					)
					( objectStatus "J4G1.175" )
				)
				( pin "dqs3n"
					( attribute "PN" "185"
						( Origin gPackager )
					)
					( objectStatus "J4G1.185" )
				)
				( pin "dqs3p"
					( attribute "PN" "186"
						( Origin gPackager )
					)
					( objectStatus "J4G1.186" )
				)
				( pin "dqs4n"
					( attribute "PN" "244"
						( Origin gPackager )
					)
					( objectStatus "J4G1.244" )
				)
				( pin "dqs4p"
					( attribute "PN" "245"
						( Origin gPackager )
					)
					( objectStatus "J4G1.245" )
				)
				( pin "dqs5n"
					( attribute "PN" "255"
						( Origin gPackager )
					)
					( objectStatus "J4G1.255" )
				)
				( pin "dqs5p"
					( attribute "PN" "256"
						( Origin gPackager )
					)
					( objectStatus "J4G1.256" )
				)
				( pin "dqs6n"
					( attribute "PN" "266"
						( Origin gPackager )
					)
					( objectStatus "J4G1.266" )
				)
				( pin "dqs6p"
					( attribute "PN" "267"
						( Origin gPackager )
					)
					( objectStatus "J4G1.267" )
				)
				( pin "dqs7n"
					( attribute "PN" "277"
						( Origin gPackager )
					)
					( objectStatus "J4G1.277" )
				)
				( pin "dqs7p"
					( attribute "PN" "278"
						( Origin gPackager )
					)
					( objectStatus "J4G1.278" )
				)
				( pin "dqs8n"
					( attribute "PN" "196"
						( Origin gPackager )
					)
					( objectStatus "J4G1.196" )
				)
				( pin "dqs8p"
					( attribute "PN" "197"
						( Origin gPackager )
					)
					( objectStatus "J4G1.197" )
				)
				( pin "dqs9n"
					( attribute "PN" "8"
						( Origin gPackager )
					)
					( objectStatus "J4G1.8" )
				)
				( pin "dqs9p"
					( attribute "PN" "7"
						( Origin gPackager )
					)
					( objectStatus "J4G1.7" )
				)
				( pin "dqs10n"
					( attribute "PN" "19"
						( Origin gPackager )
					)
					( objectStatus "J4G1.19" )
				)
				( pin "dqs10p"
					( attribute "PN" "18"
						( Origin gPackager )
					)
					( objectStatus "J4G1.18" )
				)
				( pin "dqs11n"
					( attribute "PN" "30"
						( Origin gPackager )
					)
					( objectStatus "J4G1.30" )
				)
				( pin "dqs11p"
					( attribute "PN" "29"
						( Origin gPackager )
					)
					( objectStatus "J4G1.29" )
				)
				( pin "dqs12n"
					( attribute "PN" "41"
						( Origin gPackager )
					)
					( objectStatus "J4G1.41" )
				)
				( pin "dqs12p"
					( attribute "PN" "40"
						( Origin gPackager )
					)
					( objectStatus "J4G1.40" )
				)
				( pin "dqs13n"
					( attribute "PN" "100"
						( Origin gPackager )
					)
					( objectStatus "J4G1.100" )
				)
				( pin "dqs13p"
					( attribute "PN" "99"
						( Origin gPackager )
					)
					( objectStatus "J4G1.99" )
				)
				( pin "dqs14n"
					( attribute "PN" "111"
						( Origin gPackager )
					)
					( objectStatus "J4G1.111" )
				)
				( pin "dqs14p"
					( attribute "PN" "110"
						( Origin gPackager )
					)
					( objectStatus "J4G1.110" )
				)
				( pin "dqs15n"
					( attribute "PN" "122"
						( Origin gPackager )
					)
					( objectStatus "J4G1.122" )
				)
				( pin "dqs15p"
					( attribute "PN" "121"
						( Origin gPackager )
					)
					( objectStatus "J4G1.121" )
				)
				( pin "dqs16n"
					( attribute "PN" "133"
						( Origin gPackager )
					)
					( objectStatus "J4G1.133" )
				)
				( pin "dqs16p"
					( attribute "PN" "132"
						( Origin gPackager )
					)
					( objectStatus "J4G1.132" )
				)
				( pin "dqs17n"
					( attribute "PN" "52"
						( Origin gPackager )
					)
					( objectStatus "J4G1.52" )
				)
				( pin "dqs17p"
					( attribute "PN" "51"
						( Origin gPackager )
					)
					( objectStatus "J4G1.51" )
				)
			)
			( gate "@baseboard_fab2_lib.baseboard_fab2(sch_1):page43_i259"
				( attribute "BOM_COST" "MEM"
					( Origin gFrontEnd )
				)
				( attribute "CDS_LIB" "mstr_sconn"
					( Origin gPackager )
				)
				( attribute "CDS_LOCATION" "J4G1"
					( Origin gPackager )
				)
				( attribute "CDS_SEC" "3"
					( Origin gPackager )
				)
				( attribute "LOCATION" "J4G1"
					( Origin gFrontEnd )
				)
				( attribute "MATERIAL" "SCONN"
					( Origin gFrontEnd )
				)
				( attribute "PACK_TYPE" "PIP"
					( Origin gFrontEnd )
				)
				( attribute "PART_NUMBER" "H44441-004"
					( Origin gFrontEnd )
				)
				( attribute "PHYS_PAGE" "43"
					( Origin gFrontEnd )
				)
				( attribute "ROOM" "DDR4_CH_A"
					( Origin gFrontEnd )
				)
				( attribute "ROT" "0"
					( Origin gFrontEnd )
				)
				( attribute "SEC" "3"
					( Origin gFrontEnd )
				)
				( attribute "SEC_TYPE" "PIP"
					( Origin gFrontEnd )
				)
				( attribute "VER" "3"
					( Origin gFrontEnd )
				)
				( attribute "XY" "(1750,2450)"
					( Origin gFrontEnd )
				)
				( attribute "CHIPS_PART_NAME" "SCONN288_H44441004"
					( Origin gPackager )
				)
				( attribute "CDS_PART_NAME" "SCONN288_H44441004_PIP-SCONN,HA"
					( Origin gPackager )
				)
				( objectStatus "J4G1" )
				( pin "vss(0)"
					( attribute "PN" "283"
						( Origin gPackager )
					)
					( objectStatus "J4G1.283" )
				)
				( pin "vss(1)"
					( attribute "PN" "281"
						( Origin gPackager )
					)
					( objectStatus "J4G1.281" )
				)
				( pin "vss(2)"
					( attribute "PN" "279"
						( Origin gPackager )
					)
					( objectStatus "J4G1.279" )
				)
				( pin "vss(3)"
					( attribute "PN" "276"
						( Origin gPackager )
					)
					( objectStatus "J4G1.276" )
				)
				( pin "vss(4)"
					( attribute "PN" "274"
						( Origin gPackager )
					)
					( objectStatus "J4G1.274" )
				)
				( pin "vss(5)"
					( attribute "PN" "272"
						( Origin gPackager )
					)
					( objectStatus "J4G1.272" )
				)
				( pin "vss(6)"
					( attribute "PN" "270"
						( Origin gPackager )
					)
					( objectStatus "J4G1.270" )
				)
				( pin "vss(7)"
					( attribute "PN" "268"
						( Origin gPackager )
					)
					( objectStatus "J4G1.268" )
				)
				( pin "vss(8)"
					( attribute "PN" "265"
						( Origin gPackager )
					)
					( objectStatus "J4G1.265" )
				)
				( pin "vss(9)"
					( attribute "PN" "263"
						( Origin gPackager )
					)
					( objectStatus "J4G1.263" )
				)
				( pin "vss(10)"
					( attribute "PN" "261"
						( Origin gPackager )
					)
					( objectStatus "J4G1.261" )
				)
				( pin "vss(11)"
					( attribute "PN" "259"
						( Origin gPackager )
					)
					( objectStatus "J4G1.259" )
				)
				( pin "vss(12)"
					( attribute "PN" "257"
						( Origin gPackager )
					)
					( objectStatus "J4G1.257" )
				)
				( pin "vss(13)"
					( attribute "PN" "254"
						( Origin gPackager )
					)
					( objectStatus "J4G1.254" )
				)
				( pin "vss(14)"
					( attribute "PN" "252"
						( Origin gPackager )
					)
					( objectStatus "J4G1.252" )
				)
				( pin "vss(15)"
					( attribute "PN" "250"
						( Origin gPackager )
					)
					( objectStatus "J4G1.250" )
				)
				( pin "vss(16)"
					( attribute "PN" "248"
						( Origin gPackager )
					)
					( objectStatus "J4G1.248" )
				)
				( pin "vss(17)"
					( attribute "PN" "246"
						( Origin gPackager )
					)
					( objectStatus "J4G1.246" )
				)
				( pin "vss(18)"
					( attribute "PN" "243"
						( Origin gPackager )
					)
					( objectStatus "J4G1.243" )
				)
				( pin "vss(19)"
					( attribute "PN" "241"
						( Origin gPackager )
					)
					( objectStatus "J4G1.241" )
				)
				( pin "vss(20)"
					( attribute "PN" "239"
						( Origin gPackager )
					)
					( objectStatus "J4G1.239" )
				)
				( pin "vss(21)"
					( attribute "PN" "202"
						( Origin gPackager )
					)
					( objectStatus "J4G1.202" )
				)
				( pin "vss(22)"
					( attribute "PN" "200"
						( Origin gPackager )
					)
					( objectStatus "J4G1.200" )
				)
				( pin "vss(23)"
					( attribute "PN" "198"
						( Origin gPackager )
					)
					( objectStatus "J4G1.198" )
				)
				( pin "vss(24)"
					( attribute "PN" "195"
						( Origin gPackager )
					)
					( objectStatus "J4G1.195" )
				)
				( pin "vss(25)"
					( attribute "PN" "193"
						( Origin gPackager )
					)
					( objectStatus "J4G1.193" )
				)
				( pin "vss(26)"
					( attribute "PN" "191"
						( Origin gPackager )
					)
					( objectStatus "J4G1.191" )
				)
				( pin "vss(27)"
					( attribute "PN" "189"
						( Origin gPackager )
					)
					( objectStatus "J4G1.189" )
				)
				( pin "vss(28)"
					( attribute "PN" "187"
						( Origin gPackager )
					)
					( objectStatus "J4G1.187" )
				)
				( pin "vss(29)"
					( attribute "PN" "184"
						( Origin gPackager )
					)
					( objectStatus "J4G1.184" )
				)
				( pin "vss(30)"
					( attribute "PN" "182"
						( Origin gPackager )
					)
					( objectStatus "J4G1.182" )
				)
				( pin "vss(31)"
					( attribute "PN" "180"
						( Origin gPackager )
					)
					( objectStatus "J4G1.180" )
				)
				( pin "vss(32)"
					( attribute "PN" "178"
						( Origin gPackager )
					)
					( objectStatus "J4G1.178" )
				)
				( pin "vss(33)"
					( attribute "PN" "176"
						( Origin gPackager )
					)
					( objectStatus "J4G1.176" )
				)
				( pin "vss(34)"
					( attribute "PN" "173"
						( Origin gPackager )
					)
					( objectStatus "J4G1.173" )
				)
				( pin "vss(35)"
					( attribute "PN" "171"
						( Origin gPackager )
					)
					( objectStatus "J4G1.171" )
				)
				( pin "vss(36)"
					( attribute "PN" "169"
						( Origin gPackager )
					)
					( objectStatus "J4G1.169" )
				)
				( pin "vss(37)"
					( attribute "PN" "167"
						( Origin gPackager )
					)
					( objectStatus "J4G1.167" )
				)
				( pin "vss(38)"
					( attribute "PN" "165"
						( Origin gPackager )
					)
					( objectStatus "J4G1.165" )
				)
				( pin "vss(39)"
					( attribute "PN" "162"
						( Origin gPackager )
					)
					( objectStatus "J4G1.162" )
				)
				( pin "vss(40)"
					( attribute "PN" "160"
						( Origin gPackager )
					)
					( objectStatus "J4G1.160" )
				)
				( pin "vss(41)"
					( attribute "PN" "158"
						( Origin gPackager )
					)
					( objectStatus "J4G1.158" )
				)
				( pin "vss(42)"
					( attribute "PN" "156"
						( Origin gPackager )
					)
					( objectStatus "J4G1.156" )
				)
				( pin "vss(43)"
					( attribute "PN" "154"
						( Origin gPackager )
					)
					( objectStatus "J4G1.154" )
				)
				( pin "vss(44)"
					( attribute "PN" "151"
						( Origin gPackager )
					)
					( objectStatus "J4G1.151" )
				)
				( pin "vss(45)"
					( attribute "PN" "149"
						( Origin gPackager )
					)
					( objectStatus "J4G1.149" )
				)
				( pin "vss(46)"
					( attribute "PN" "147"
						( Origin gPackager )
					)
					( objectStatus "J4G1.147" )
				)
				( pin "vss(47)"
					( attribute "PN" "138"
						( Origin gPackager )
					)
					( objectStatus "J4G1.138" )
				)
				( pin "vss(48)"
					( attribute "PN" "136"
						( Origin gPackager )
					)
					( objectStatus "J4G1.136" )
				)
				( pin "vss(49)"
					( attribute "PN" "134"
						( Origin gPackager )
					)
					( objectStatus "J4G1.134" )
				)
				( pin "vss(50)"
					( attribute "PN" "131"
						( Origin gPackager )
					)
					( objectStatus "J4G1.131" )
				)
				( pin "vss(51)"
					( attribute "PN" "129"
						( Origin gPackager )
					)
					( objectStatus "J4G1.129" )
				)
				( pin "vss(52)"
					( attribute "PN" "127"
						( Origin gPackager )
					)
					( objectStatus "J4G1.127" )
				)
				( pin "vss(53)"
					( attribute "PN" "125"
						( Origin gPackager )
					)
					( objectStatus "J4G1.125" )
				)
				( pin "vss(54)"
					( attribute "PN" "123"
						( Origin gPackager )
					)
					( objectStatus "J4G1.123" )
				)
				( pin "vss(55)"
					( attribute "PN" "120"
						( Origin gPackager )
					)
					( objectStatus "J4G1.120" )
				)
				( pin "vss(56)"
					( attribute "PN" "118"
						( Origin gPackager )
					)
					( objectStatus "J4G1.118" )
				)
				( pin "vss(57)"
					( attribute "PN" "116"
						( Origin gPackager )
					)
					( objectStatus "J4G1.116" )
				)
				( pin "vss(58)"
					( attribute "PN" "114"
						( Origin gPackager )
					)
					( objectStatus "J4G1.114" )
				)
				( pin "vss(59)"
					( attribute "PN" "112"
						( Origin gPackager )
					)
					( objectStatus "J4G1.112" )
				)
				( pin "vss(60)"
					( attribute "PN" "109"
						( Origin gPackager )
					)
					( objectStatus "J4G1.109" )
				)
				( pin "vss(61)"
					( attribute "PN" "107"
						( Origin gPackager )
					)
					( objectStatus "J4G1.107" )
				)
				( pin "vss(62)"
					( attribute "PN" "105"
						( Origin gPackager )
					)
					( objectStatus "J4G1.105" )
				)
				( pin "vss(63)"
					( attribute "PN" "103"
						( Origin gPackager )
					)
					( objectStatus "J4G1.103" )
				)
				( pin "vss(64)"
					( attribute "PN" "101"
						( Origin gPackager )
					)
					( objectStatus "J4G1.101" )
				)
				( pin "vss(65)"
					( attribute "PN" "98"
						( Origin gPackager )
					)
					( objectStatus "J4G1.98" )
				)
				( pin "vss(66)"
					( attribute "PN" "96"
						( Origin gPackager )
					)
					( objectStatus "J4G1.96" )
				)
				( pin "vss(67)"
					( attribute "PN" "94"
						( Origin gPackager )
					)
					( objectStatus "J4G1.94" )
				)
				( pin "vss(68)"
					( attribute "PN" "57"
						( Origin gPackager )
					)
					( objectStatus "J4G1.57" )
				)
				( pin "vss(69)"
					( attribute "PN" "55"
						( Origin gPackager )
					)
					( objectStatus "J4G1.55" )
				)
				( pin "vss(70)"
					( attribute "PN" "53"
						( Origin gPackager )
					)
					( objectStatus "J4G1.53" )
				)
				( pin "vss(71)"
					( attribute "PN" "50"
						( Origin gPackager )
					)
					( objectStatus "J4G1.50" )
				)
				( pin "vss(72)"
					( attribute "PN" "48"
						( Origin gPackager )
					)
					( objectStatus "J4G1.48" )
				)
				( pin "vss(73)"
					( attribute "PN" "46"
						( Origin gPackager )
					)
					( objectStatus "J4G1.46" )
				)
				( pin "vss(74)"
					( attribute "PN" "44"
						( Origin gPackager )
					)
					( objectStatus "J4G1.44" )
				)
				( pin "vss(75)"
					( attribute "PN" "42"
						( Origin gPackager )
					)
					( objectStatus "J4G1.42" )
				)
				( pin "vss(76)"
					( attribute "PN" "39"
						( Origin gPackager )
					)
					( objectStatus "J4G1.39" )
				)
				( pin "vss(77)"
					( attribute "PN" "37"
						( Origin gPackager )
					)
					( objectStatus "J4G1.37" )
				)
				( pin "vss(78)"
					( attribute "PN" "35"
						( Origin gPackager )
					)
					( objectStatus "J4G1.35" )
				)
				( pin "vss(79)"
					( attribute "PN" "33"
						( Origin gPackager )
					)
					( objectStatus "J4G1.33" )
				)
				( pin "vss(80)"
					( attribute "PN" "31"
						( Origin gPackager )
					)
					( objectStatus "J4G1.31" )
				)
				( pin "vss(81)"
					( attribute "PN" "28"
						( Origin gPackager )
					)
					( objectStatus "J4G1.28" )
				)
				( pin "vss(82)"
					( attribute "PN" "26"
						( Origin gPackager )
					)
					( objectStatus "J4G1.26" )
				)
				( pin "vss(83)"
					( attribute "PN" "24"
						( Origin gPackager )
					)
					( objectStatus "J4G1.24" )
				)
				( pin "vss(84)"
					( attribute "PN" "22"
						( Origin gPackager )
					)
					( objectStatus "J4G1.22" )
				)
				( pin "vss(85)"
					( attribute "PN" "20"
						( Origin gPackager )
					)
					( objectStatus "J4G1.20" )
				)
				( pin "vss(86)"
					( attribute "PN" "17"
						( Origin gPackager )
					)
					( objectStatus "J4G1.17" )
				)
				( pin "vss(87)"
					( attribute "PN" "15"
						( Origin gPackager )
					)
					( objectStatus "J4G1.15" )
				)
				( pin "vss(88)"
					( attribute "PN" "13"
						( Origin gPackager )
					)
					( objectStatus "J4G1.13" )
				)
				( pin "vss(89)"
					( attribute "PN" "11"
						( Origin gPackager )
					)
					( objectStatus "J4G1.11" )
				)
				( pin "vss(90)"
					( attribute "PN" "9"
						( Origin gPackager )
					)
					( objectStatus "J4G1.9" )
				)
				( pin "vss(91)"
					( attribute "PN" "6"
						( Origin gPackager )
					)
					( objectStatus "J4G1.6" )
				)
				( pin "vss(92)"
					( attribute "PN" "4"
						( Origin gPackager )
					)
					( objectStatus "J4G1.4" )
				)
				( pin "vss(93)"
					( attribute "PN" "2"
						( Origin gPackager )
					)
					( objectStatus "J4G1.2" )
				)
			)
			( gate "@baseboard_fab2_lib.baseboard_fab2(sch_1):page43_i260"
				( attribute "BOM_COST" "MEM"
					( Origin gFrontEnd )
				)
				( attribute "CDS_LIB" "mstr_sconn"
					( Origin gPackager )
				)
				( attribute "CDS_LOCATION" "J4G1"
					( Origin gPackager )
				)
				( attribute "CDS_SEC" "4"
					( Origin gPackager )
				)
				( attribute "LOCATION" "J4G1"
					( Origin gFrontEnd )
				)
				( attribute "MATERIAL" "SCONN"
					( Origin gFrontEnd )
				)
				( attribute "PACK_TYPE" "PIP"
					( Origin gFrontEnd )
				)
				( attribute "PART_NUMBER" "H44441-004"
					( Origin gFrontEnd )
				)
				( attribute "PHYS_PAGE" "43"
					( Origin gFrontEnd )
				)
				( attribute "ROOM" "DDR4_CH_A"
					( Origin gFrontEnd )
				)
				( attribute "ROT" "0"
					( Origin gFrontEnd )
				)
				( attribute "SEC" "4"
					( Origin gFrontEnd )
				)
				( attribute "SEC_TYPE" "PIP"
					( Origin gFrontEnd )
				)
				( attribute "VER" "4"
					( Origin gFrontEnd )
				)
				( attribute "XY" "(-100,1700)"
					( Origin gFrontEnd )
				)
				( attribute "CHIPS_PART_NAME" "SCONN288_H44441004"
					( Origin gPackager )
				)
				( attribute "CDS_PART_NAME" "SCONN288_H44441004_PIP-SCONN,HA"
					( Origin gPackager )
				)
				( objectStatus "J4G1" )
				( pin "\12v\(0)"
					( attribute "PN" "145"
						( Origin gPackager )
					)
					( objectStatus "J4G1.145" )
				)
				( pin "\12v\(1)"
					( attribute "PN" "1"
						( Origin gPackager )
					)
					( objectStatus "J4G1.1" )
				)
				( pin "vdd(0)"
					( attribute "PN" "236"
						( Origin gPackager )
					)
					( objectStatus "J4G1.236" )
				)
				( pin "vdd(1)"
					( attribute "PN" "233"
						( Origin gPackager )
					)
					( objectStatus "J4G1.233" )
				)
				( pin "vdd(2)"
					( attribute "PN" "231"
						( Origin gPackager )
					)
					( objectStatus "J4G1.231" )
				)
				( pin "vdd(3)"
					( attribute "PN" "229"
						( Origin gPackager )
					)
					( objectStatus "J4G1.229" )
				)
				( pin "vdd(4)"
					( attribute "PN" "226"
						( Origin gPackager )
					)
					( objectStatus "J4G1.226" )
				)
				( pin "vdd(5)"
					( attribute "PN" "223"
						( Origin gPackager )
					)
					( objectStatus "J4G1.223" )
				)
				( pin "vdd(6)"
					( attribute "PN" "220"
						( Origin gPackager )
					)
					( objectStatus "J4G1.220" )
				)
				( pin "vdd(7)"
					( attribute "PN" "217"
						( Origin gPackager )
					)
					( objectStatus "J4G1.217" )
				)
				( pin "vdd(8)"
					( attribute "PN" "215"
						( Origin gPackager )
					)
					( objectStatus "J4G1.215" )
				)
				( pin "vdd(9)"
					( attribute "PN" "212"
						( Origin gPackager )
					)
					( objectStatus "J4G1.212" )
				)
				( pin "vdd(10)"
					( attribute "PN" "209"
						( Origin gPackager )
					)
					( objectStatus "J4G1.209" )
				)
				( pin "vdd(11)"
					( attribute "PN" "206"
						( Origin gPackager )
					)
					( objectStatus "J4G1.206" )
				)
				( pin "vdd(12)"
					( attribute "PN" "204"
						( Origin gPackager )
					)
					( objectStatus "J4G1.204" )
				)
				( pin "vdd(13)"
					( attribute "PN" "92"
						( Origin gPackager )
					)
					( objectStatus "J4G1.92" )
				)
				( pin "vdd(14)"
					( attribute "PN" "90"
						( Origin gPackager )
					)
					( objectStatus "J4G1.90" )
				)
				( pin "vdd(15)"
					( attribute "PN" "88"
						( Origin gPackager )
					)
					( objectStatus "J4G1.88" )
				)
				( pin "vdd(16)"
					( attribute "PN" "85"
						( Origin gPackager )
					)
					( objectStatus "J4G1.85" )
				)
				( pin "vdd(17)"
					( attribute "PN" "83"
						( Origin gPackager )
					)
					( objectStatus "J4G1.83" )
				)
				( pin "vdd(18)"
					( attribute "PN" "80"
						( Origin gPackager )
					)
					( objectStatus "J4G1.80" )
				)
				( pin "vdd(19)"
					( attribute "PN" "76"
						( Origin gPackager )
					)
					( objectStatus "J4G1.76" )
				)
				( pin "vdd(20)"
					( attribute "PN" "73"
						( Origin gPackager )
					)
					( objectStatus "J4G1.73" )
				)
				( pin "vdd(21)"
					( attribute "PN" "70"
						( Origin gPackager )
					)
					( objectStatus "J4G1.70" )
				)
				( pin "vdd(22)"
					( attribute "PN" "67"
						( Origin gPackager )
					)
					( objectStatus "J4G1.67" )
				)
				( pin "vdd(23)"
					( attribute "PN" "64"
						( Origin gPackager )
					)
					( objectStatus "J4G1.64" )
				)
				( pin "vdd(24)"
					( attribute "PN" "61"
						( Origin gPackager )
					)
					( objectStatus "J4G1.61" )
				)
				( pin "vdd(25)"
					( attribute "PN" "59"
						( Origin gPackager )
					)
					( objectStatus "J4G1.59" )
				)
				( pin "vpp(0)"
					( attribute "PN" "287"
						( Origin gPackager )
					)
					( objectStatus "J4G1.287" )
				)
				( pin "vpp(1)"
					( attribute "PN" "286"
						( Origin gPackager )
					)
					( objectStatus "J4G1.286" )
				)
				( pin "vpp(2)"
					( attribute "PN" "288"
						( Origin gPackager )
					)
					( objectStatus "J4G1.288" )
				)
				( pin "vpp(3)"
					( attribute "PN" "143"
						( Origin gPackager )
					)
					( objectStatus "J4G1.143" )
				)
				( pin "vpp(4)"
					( attribute "PN" "142"
						( Origin gPackager )
					)
					( objectStatus "J4G1.142" )
				)
				( pin "vtt(0)"
					( attribute "PN" "221"
						( Origin gPackager )
					)
					( objectStatus "J4G1.221" )
				)
				( pin "vtt(1)"
					( attribute "PN" "77"
						( Origin gPackager )
					)
					( objectStatus "J4G1.77" )
				)
			)
			( gate "@baseboard_fab2_lib.baseboard_fab2(sch_1):page43_i272"
				( attribute "BOM_COST" "MEM"
					( Origin gFrontEnd )
				)
				( attribute "CDS_LIB" "dev_discrete"
					( Origin gPackager )
				)
				( attribute "CDS_LOCATION" "C4F10"
					( Origin gPackager )
				)
				( attribute "CDS_SEC" "1"
					( Origin gPackager )
				)
				( attribute "LOCATION" "C4F10"
					( Origin gFrontEnd )
				)
				( attribute "MATERIAL" "X7R"
					( Origin gFrontEnd )
				)
				( attribute "PACK_TYPE" "0402V"
					( Origin gFrontEnd )
				)
				( attribute "PART_NUMBER" "A36096-045"
					( Origin gFrontEnd )
				)
				( attribute "PHYS_PAGE" "43"
					( Origin gFrontEnd )
				)
				( attribute "ROOM" "DDR4_CH_A"
					( Origin gFrontEnd )
				)
				( attribute "ROT" "2"
					( Origin gFrontEnd )
				)
				( attribute "SEC" "1"
					( Origin gPackager )
				)
				( attribute "TOLERANCE" "10%"
					( Origin gFrontEnd )
				)
				( attribute "VALUE" "0.01UF"
					( Origin gFrontEnd )
				)
				( attribute "VER" "1"
					( Origin gFrontEnd )
				)
				( attribute "VOLTAGE" "25V"
					( Units "uVoltage" "V" 1.000000)
					( Origin gFrontEnd )
				)
				( attribute "XY" "(-4350,1050)"
					( Origin gFrontEnd )
				)
				( attribute "CHIPS_PART_NAME" "CAP_A"
					( Origin gPackager )
				)
				( attribute "CDS_PART_NAME" "CAP_A_0402V-0.01UF,25V,10%,X7RA"
					( Origin gPackager )
				)
				( objectStatus "C4F10" )
				( pin "a"
					( attribute "PN" "1"
						( Origin gPackager )
					)
					( objectStatus "C4F10.1" )
				)
				( pin "b"
					( attribute "PN" "2"
						( Origin gPackager )
					)
					( objectStatus "C4F10.2" )
				)
			)
			( gate "@baseboard_fab2_lib.baseboard_fab2(sch_1):page44_i2"
				( attribute "BOM_COST" "MEM"
					( Origin gFrontEnd )
				)
				( attribute "CDS_LIB" "dev_discrete"
					( Origin gPackager )
				)
				( attribute "CDS_LOCATION" "C6T1"
					( Origin gPackager )
				)
				( attribute "CDS_SEC" "1"
					( Origin gPackager )
				)
				( attribute "LOCATION" "C6T1"
					( Origin gFrontEnd )
				)
				( attribute "MATERIAL" "X7R"
					( Origin gFrontEnd )
				)
				( attribute "PACK_TYPE" "0402V"
					( Origin gFrontEnd )
				)
				( attribute "PART_NUMBER" "A36096-045"
					( Origin gFrontEnd )
				)
				( attribute "PHYS_PAGE" "44"
					( Origin gFrontEnd )
				)
				( attribute "ROOM" "DDR4_CH_A"
					( Origin gFrontEnd )
				)
				( attribute "ROT" "2"
					( Origin gFrontEnd )
				)
				( attribute "SEC" "1"
					( Origin gFrontEnd )
				)
				( attribute "SEC_TYPE" "0402V"
					( Origin gFrontEnd )
				)
				( attribute "TOLERANCE" "10%"
					( Origin gFrontEnd )
				)
				( attribute "VALUE" "0.01UF"
					( Origin gFrontEnd )
				)
				( attribute "VER" "1"
					( Origin gFrontEnd )
				)
				( attribute "VOLTAGE" "25V"
					( Units "uVoltage" "V" 1.000000)
					( Origin gFrontEnd )
				)
				( attribute "XY" "(-2650,1000)"
					( Origin gFrontEnd )
				)
				( attribute "CHIPS_PART_NAME" "CAP_A"
					( Origin gPackager )
				)
				( attribute "CDS_PART_NAME" "CAP_A_0402V-0.01UF,25V,10%,X7RA"
					( Origin gPackager )
				)
				( objectStatus "C6T1" )
				( pin "a"
					( attribute "PN" "1"
						( Origin gPackager )
					)
					( objectStatus "C6T1.1" )
				)
				( pin "b"
					( attribute "PN" "2"
						( Origin gPackager )
					)
					( objectStatus "C6T1.2" )
				)
			)
			( gate "@baseboard_fab2_lib.baseboard_fab2(sch_1):page44_i13"
				( attribute "BOM_COST" "MEM"
					( Origin gFrontEnd )
				)
				( attribute "CDS_LIB" "mstr_sconn"
					( Origin gPackager )
				)
				( attribute "CDS_LOCATION" "J6T1"
					( Origin gPackager )
				)
				( attribute "CDS_SEC" "1"
					( Origin gPackager )
				)
				( attribute "LOCATION" "J6T1"
					( Origin gFrontEnd )
				)
				( attribute "MATERIAL" "SCONN"
					( Origin gFrontEnd )
				)
				( attribute "PACK_TYPE" "PIP"
					( Origin gFrontEnd )
				)
				( attribute "PART_NUMBER" "H44441-003"
					( Origin gFrontEnd )
				)
				( attribute "PHYS_PAGE" "44"
					( Origin gFrontEnd )
				)
				( attribute "ROOM" "DDR4_CH_A"
					( Origin gFrontEnd )
				)
				( attribute "ROT" "0"
					( Origin gFrontEnd )
				)
				( attribute "SEC" "1"
					( Origin gFrontEnd )
				)
				( attribute "SEC_TYPE" "PIP"
					( Origin gFrontEnd )
				)
				( attribute "VER" "1"
					( Origin gFrontEnd )
				)
				( attribute "XY" "(-700,2700)"
					( Origin gFrontEnd )
				)
				( attribute "CHIPS_PART_NAME" "SCONN288_H44441003"
					( Origin gPackager )
				)
				( attribute "CDS_PART_NAME" "SCONN288_H44441003_PIP-SCONN,HA"
					( Origin gPackager )
				)
				( objectStatus "J6T1" )
				( pin "a0"
					( attribute "PN" "79"
						( Origin gPackager )
					)
					( objectStatus "J6T1.79" )
				)
				( pin "a1"
					( attribute "PN" "72"
						( Origin gPackager )
					)
					( objectStatus "J6T1.72" )
				)
				( pin "a2"
					( attribute "PN" "216"
						( Origin gPackager )
					)
					( objectStatus "J6T1.216" )
				)
				( pin "a3"
					( attribute "PN" "71"
						( Origin gPackager )
					)
					( objectStatus "J6T1.71" )
				)
				( pin "a4"
					( attribute "PN" "214"
						( Origin gPackager )
					)
					( objectStatus "J6T1.214" )
				)
				( pin "a5"
					( attribute "PN" "213"
						( Origin gPackager )
					)
					( objectStatus "J6T1.213" )
				)
				( pin "a6"
					( attribute "PN" "69"
						( Origin gPackager )
					)
					( objectStatus "J6T1.69" )
				)
				( pin "a7"
					( attribute "PN" "211"
						( Origin gPackager )
					)
					( objectStatus "J6T1.211" )
				)
				( pin "a8"
					( attribute "PN" "68"
						( Origin gPackager )
					)
					( objectStatus "J6T1.68" )
				)
				( pin "a9"
					( attribute "PN" "66"
						( Origin gPackager )
					)
					( objectStatus "J6T1.66" )
				)
				( pin "a10"
					( attribute "PN" "225"
						( Origin gPackager )
					)
					( objectStatus "J6T1.225" )
				)
				( pin "a11"
					( attribute "PN" "210"
						( Origin gPackager )
					)
					( objectStatus "J6T1.210" )
				)
				( pin "a12"
					( attribute "PN" "65"
						( Origin gPackager )
					)
					( objectStatus "J6T1.65" )
				)
				( pin "a13"
					( attribute "PN" "232"
						( Origin gPackager )
					)
					( objectStatus "J6T1.232" )
				)
				( pin "a14_we_n"
					( attribute "PN" "228"
						( Origin gPackager )
					)
					( objectStatus "J6T1.228" )
				)
				( pin "a15_cas_n"
					( attribute "PN" "86"
						( Origin gPackager )
					)
					( objectStatus "J6T1.86" )
				)
				( pin "a16_ras_n"
					( attribute "PN" "82"
						( Origin gPackager )
					)
					( objectStatus "J6T1.82" )
				)
				( pin "a17"
					( attribute "PN" "234"
						( Origin gPackager )
					)
					( objectStatus "J6T1.234" )
				)
				( pin "act_n"
					( attribute "PN" "62"
						( Origin gPackager )
					)
					( objectStatus "J6T1.62" )
				)
				( pin "alert_n"
					( attribute "PN" "208"
						( Origin gPackager )
					)
					( objectStatus "J6T1.208" )
				)
				( pin "ba(0)"
					( attribute "PN" "81"
						( Origin gPackager )
					)
					( objectStatus "J6T1.81" )
				)
				( pin "ba(1)"
					( attribute "PN" "224"
						( Origin gPackager )
					)
					( objectStatus "J6T1.224" )
				)
				( pin "bg(0)"
					( attribute "PN" "63"
						( Origin gPackager )
					)
					( objectStatus "J6T1.63" )
				)
				( pin "bg(1)"
					( attribute "PN" "207"
						( Origin gPackager )
					)
					( objectStatus "J6T1.207" )
				)
				( pin "c(2)"
					( attribute "PN" "235"
						( Origin gPackager )
					)
					( objectStatus "J6T1.235" )
				)
				( pin "cb(0)"
					( attribute "PN" "49"
						( Origin gPackager )
					)
					( objectStatus "J6T1.49" )
				)
				( pin "cb(1)"
					( attribute "PN" "194"
						( Origin gPackager )
					)
					( objectStatus "J6T1.194" )
				)
				( pin "cb(2)"
					( attribute "PN" "56"
						( Origin gPackager )
					)
					( objectStatus "J6T1.56" )
				)
				( pin "cb(3)"
					( attribute "PN" "201"
						( Origin gPackager )
					)
					( objectStatus "J6T1.201" )
				)
				( pin "cb(4)"
					( attribute "PN" "47"
						( Origin gPackager )
					)
					( objectStatus "J6T1.47" )
				)
				( pin "cb(5)"
					( attribute "PN" "192"
						( Origin gPackager )
					)
					( objectStatus "J6T1.192" )
				)
				( pin "cb(6)"
					( attribute "PN" "54"
						( Origin gPackager )
					)
					( objectStatus "J6T1.54" )
				)
				( pin "cb(7)"
					( attribute "PN" "199"
						( Origin gPackager )
					)
					( objectStatus "J6T1.199" )
				)
				( pin "ck0n"
					( attribute "PN" "75"
						( Origin gPackager )
					)
					( objectStatus "J6T1.75" )
				)
				( pin "ck0p"
					( attribute "PN" "74"
						( Origin gPackager )
					)
					( objectStatus "J6T1.74" )
				)
				( pin "ck1n"
					( attribute "PN" "219"
						( Origin gPackager )
					)
					( objectStatus "J6T1.219" )
				)
				( pin "ck1p"
					( attribute "PN" "218"
						( Origin gPackager )
					)
					( objectStatus "J6T1.218" )
				)
				( pin "cke(0)"
					( attribute "PN" "60"
						( Origin gPackager )
					)
					( objectStatus "J6T1.60" )
				)
				( pin "cke(1)"
					( attribute "PN" "203"
						( Origin gPackager )
					)
					( objectStatus "J6T1.203" )
				)
				( pin "dq(0)"
					( attribute "PN" "5"
						( Origin gPackager )
					)
					( objectStatus "J6T1.5" )
				)
				( pin "dq(1)"
					( attribute "PN" "150"
						( Origin gPackager )
					)
					( objectStatus "J6T1.150" )
				)
				( pin "dq(2)"
					( attribute "PN" "12"
						( Origin gPackager )
					)
					( objectStatus "J6T1.12" )
				)
				( pin "dq(3)"
					( attribute "PN" "157"
						( Origin gPackager )
					)
					( objectStatus "J6T1.157" )
				)
				( pin "dq(4)"
					( attribute "PN" "3"
						( Origin gPackager )
					)
					( objectStatus "J6T1.3" )
				)
				( pin "dq(5)"
					( attribute "PN" "148"
						( Origin gPackager )
					)
					( objectStatus "J6T1.148" )
				)
				( pin "dq(6)"
					( attribute "PN" "10"
						( Origin gPackager )
					)
					( objectStatus "J6T1.10" )
				)
				( pin "dq(7)"
					( attribute "PN" "155"
						( Origin gPackager )
					)
					( objectStatus "J6T1.155" )
				)
				( pin "dq(8)"
					( attribute "PN" "16"
						( Origin gPackager )
					)
					( objectStatus "J6T1.16" )
				)
				( pin "dq(9)"
					( attribute "PN" "161"
						( Origin gPackager )
					)
					( objectStatus "J6T1.161" )
				)
				( pin "dq(10)"
					( attribute "PN" "23"
						( Origin gPackager )
					)
					( objectStatus "J6T1.23" )
				)
				( pin "dq(11)"
					( attribute "PN" "168"
						( Origin gPackager )
					)
					( objectStatus "J6T1.168" )
				)
				( pin "dq(12)"
					( attribute "PN" "14"
						( Origin gPackager )
					)
					( objectStatus "J6T1.14" )
				)
				( pin "dq(13)"
					( attribute "PN" "159"
						( Origin gPackager )
					)
					( objectStatus "J6T1.159" )
				)
				( pin "dq(14)"
					( attribute "PN" "21"
						( Origin gPackager )
					)
					( objectStatus "J6T1.21" )
				)
				( pin "dq(15)"
					( attribute "PN" "166"
						( Origin gPackager )
					)
					( objectStatus "J6T1.166" )
				)
				( pin "dq(16)"
					( attribute "PN" "27"
						( Origin gPackager )
					)
					( objectStatus "J6T1.27" )
				)
				( pin "dq(17)"
					( attribute "PN" "172"
						( Origin gPackager )
					)
					( objectStatus "J6T1.172" )
				)
				( pin "dq(18)"
					( attribute "PN" "34"
						( Origin gPackager )
					)
					( objectStatus "J6T1.34" )
				)
				( pin "dq(19)"
					( attribute "PN" "179"
						( Origin gPackager )
					)
					( objectStatus "J6T1.179" )
				)
				( pin "dq(20)"
					( attribute "PN" "25"
						( Origin gPackager )
					)
					( objectStatus "J6T1.25" )
				)
				( pin "dq(21)"
					( attribute "PN" "170"
						( Origin gPackager )
					)
					( objectStatus "J6T1.170" )
				)
				( pin "dq(22)"
					( attribute "PN" "32"
						( Origin gPackager )
					)
					( objectStatus "J6T1.32" )
				)
				( pin "dq(23)"
					( attribute "PN" "177"
						( Origin gPackager )
					)
					( objectStatus "J6T1.177" )
				)
				( pin "dq(24)"
					( attribute "PN" "38"
						( Origin gPackager )
					)
					( objectStatus "J6T1.38" )
				)
				( pin "dq(25)"
					( attribute "PN" "183"
						( Origin gPackager )
					)
					( objectStatus "J6T1.183" )
				)
				( pin "dq(26)"
					( attribute "PN" "45"
						( Origin gPackager )
					)
					( objectStatus "J6T1.45" )
				)
				( pin "dq(27)"
					( attribute "PN" "190"
						( Origin gPackager )
					)
					( objectStatus "J6T1.190" )
				)
				( pin "dq(28)"
					( attribute "PN" "36"
						( Origin gPackager )
					)
					( objectStatus "J6T1.36" )
				)
				( pin "dq(29)"
					( attribute "PN" "181"
						( Origin gPackager )
					)
					( objectStatus "J6T1.181" )
				)
				( pin "dq(30)"
					( attribute "PN" "43"
						( Origin gPackager )
					)
					( objectStatus "J6T1.43" )
				)
				( pin "dq(31)"
					( attribute "PN" "188"
						( Origin gPackager )
					)
					( objectStatus "J6T1.188" )
				)
				( pin "dq(32)"
					( attribute "PN" "97"
						( Origin gPackager )
					)
					( objectStatus "J6T1.97" )
				)
				( pin "dq(33)"
					( attribute "PN" "242"
						( Origin gPackager )
					)
					( objectStatus "J6T1.242" )
				)
				( pin "dq(34)"
					( attribute "PN" "104"
						( Origin gPackager )
					)
					( objectStatus "J6T1.104" )
				)
				( pin "dq(35)"
					( attribute "PN" "249"
						( Origin gPackager )
					)
					( objectStatus "J6T1.249" )
				)
				( pin "dq(36)"
					( attribute "PN" "95"
						( Origin gPackager )
					)
					( objectStatus "J6T1.95" )
				)
				( pin "dq(37)"
					( attribute "PN" "240"
						( Origin gPackager )
					)
					( objectStatus "J6T1.240" )
				)
				( pin "dq(38)"
					( attribute "PN" "102"
						( Origin gPackager )
					)
					( objectStatus "J6T1.102" )
				)
				( pin "dq(39)"
					( attribute "PN" "247"
						( Origin gPackager )
					)
					( objectStatus "J6T1.247" )
				)
				( pin "dq(40)"
					( attribute "PN" "108"
						( Origin gPackager )
					)
					( objectStatus "J6T1.108" )
				)
				( pin "dq(41)"
					( attribute "PN" "253"
						( Origin gPackager )
					)
					( objectStatus "J6T1.253" )
				)
				( pin "dq(42)"
					( attribute "PN" "115"
						( Origin gPackager )
					)
					( objectStatus "J6T1.115" )
				)
				( pin "dq(43)"
					( attribute "PN" "260"
						( Origin gPackager )
					)
					( objectStatus "J6T1.260" )
				)
				( pin "dq(44)"
					( attribute "PN" "106"
						( Origin gPackager )
					)
					( objectStatus "J6T1.106" )
				)
				( pin "dq(45)"
					( attribute "PN" "251"
						( Origin gPackager )
					)
					( objectStatus "J6T1.251" )
				)
				( pin "dq(46)"
					( attribute "PN" "113"
						( Origin gPackager )
					)
					( objectStatus "J6T1.113" )
				)
				( pin "dq(47)"
					( attribute "PN" "258"
						( Origin gPackager )
					)
					( objectStatus "J6T1.258" )
				)
				( pin "dq(48)"
					( attribute "PN" "119"
						( Origin gPackager )
					)
					( objectStatus "J6T1.119" )
				)
				( pin "dq(49)"
					( attribute "PN" "264"
						( Origin gPackager )
					)
					( objectStatus "J6T1.264" )
				)
				( pin "dq(50)"
					( attribute "PN" "126"
						( Origin gPackager )
					)
					( objectStatus "J6T1.126" )
				)
				( pin "dq(51)"
					( attribute "PN" "271"
						( Origin gPackager )
					)
					( objectStatus "J6T1.271" )
				)
				( pin "dq(52)"
					( attribute "PN" "117"
						( Origin gPackager )
					)
					( objectStatus "J6T1.117" )
				)
				( pin "dq(53)"
					( attribute "PN" "262"
						( Origin gPackager )
					)
					( objectStatus "J6T1.262" )
				)
				( pin "dq(54)"
					( attribute "PN" "124"
						( Origin gPackager )
					)
					( objectStatus "J6T1.124" )
				)
				( pin "dq(55)"
					( attribute "PN" "269"
						( Origin gPackager )
					)
					( objectStatus "J6T1.269" )
				)
				( pin "dq(56)"
					( attribute "PN" "130"
						( Origin gPackager )
					)
					( objectStatus "J6T1.130" )
				)
				( pin "dq(57)"
					( attribute "PN" "275"
						( Origin gPackager )
					)
					( objectStatus "J6T1.275" )
				)
				( pin "dq(58)"
					( attribute "PN" "137"
						( Origin gPackager )
					)
					( objectStatus "J6T1.137" )
				)
				( pin "dq(59)"
					( attribute "PN" "282"
						( Origin gPackager )
					)
					( objectStatus "J6T1.282" )
				)
				( pin "dq(60)"
					( attribute "PN" "128"
						( Origin gPackager )
					)
					( objectStatus "J6T1.128" )
				)
				( pin "dq(61)"
					( attribute "PN" "273"
						( Origin gPackager )
					)
					( objectStatus "J6T1.273" )
				)
				( pin "dq(62)"
					( attribute "PN" "135"
						( Origin gPackager )
					)
					( objectStatus "J6T1.135" )
				)
				( pin "dq(63)"
					( attribute "PN" "280"
						( Origin gPackager )
					)
					( objectStatus "J6T1.280" )
				)
				( pin "event_n"
					( attribute "PN" "78"
						( Origin gPackager )
					)
					( objectStatus "J6T1.78" )
				)
				( pin "odt(0)"
					( attribute "PN" "87"
						( Origin gPackager )
					)
					( objectStatus "J6T1.87" )
				)
				( pin "odt(1)"
					( attribute "PN" "91"
						( Origin gPackager )
					)
					( objectStatus "J6T1.91" )
				)
				( pin "par"
					( attribute "PN" "222"
						( Origin gPackager )
					)
					( objectStatus "J6T1.222" )
				)
				( pin "reset_n"
					( attribute "PN" "58"
						( Origin gPackager )
					)
					( objectStatus "J6T1.58" )
				)
				( pin "rfu(0)"
					( attribute "PN" "205"
						( Origin gPackager )
					)
					( objectStatus "J6T1.205" )
				)
				( pin "rfu(1)"
					( attribute "PN" "227"
						( Origin gPackager )
					)
					( objectStatus "J6T1.227" )
				)
				( pin "rfu(2)"
					( attribute "PN" "144"
						( Origin gPackager )
					)
					( objectStatus "J6T1.144" )
				)
				( pin "s0_n"
					( attribute "PN" "84"
						( Origin gPackager )
					)
					( objectStatus "J6T1.84" )
				)
				( pin "s1_n"
					( attribute "PN" "89"
						( Origin gPackager )
					)
					( objectStatus "J6T1.89" )
				)
				( pin "s2_n_c(0)"
					( attribute "PN" "93"
						( Origin gPackager )
					)
					( objectStatus "J6T1.93" )
				)
				( pin "s3_n_c(1)"
					( attribute "PN" "237"
						( Origin gPackager )
					)
					( objectStatus "J6T1.237" )
				)
				( pin "sa(0)"
					( attribute "PN" "139"
						( Origin gPackager )
					)
					( objectStatus "J6T1.139" )
				)
				( pin "sa(1)"
					( attribute "PN" "140"
						( Origin gPackager )
					)
					( objectStatus "J6T1.140" )
				)
				( pin "sa(2)"
					( attribute "PN" "238"
						( Origin gPackager )
					)
					( objectStatus "J6T1.238" )
				)
				( pin "save_n_nc"
					( attribute "PN" "230"
						( Origin gPackager )
					)
					( objectStatus "J6T1.230" )
				)
				( pin "scl"
					( attribute "PN" "141"
						( Origin gPackager )
					)
					( objectStatus "J6T1.141" )
				)
				( pin "sda"
					( attribute "PN" "285"
						( Origin gPackager )
					)
					( objectStatus "J6T1.285" )
				)
				( pin "vddspd"
					( attribute "PN" "284"
						( Origin gPackager )
					)
					( objectStatus "J6T1.284" )
				)
				( pin "vrefca"
					( attribute "PN" "146"
						( Origin gPackager )
					)
					( objectStatus "J6T1.146" )
				)
			)
			( gate "@baseboard_fab2_lib.baseboard_fab2(sch_1):page44_i75"
				( attribute "BOM_COST" "MEM"
					( Origin gFrontEnd )
				)
				( attribute "CDS_LIB" "mstr_sconn"
					( Origin gPackager )
				)
				( attribute "CDS_LOCATION" "J6T1"
					( Origin gPackager )
				)
				( attribute "CDS_SEC" "4"
					( Origin gPackager )
				)
				( attribute "LOCATION" "J6T1"
					( Origin gFrontEnd )
				)
				( attribute "MATERIAL" "SCONN"
					( Origin gFrontEnd )
				)
				( attribute "PACK_TYPE" "PIP"
					( Origin gFrontEnd )
				)
				( attribute "PART_NUMBER" "H44441-003"
					( Origin gFrontEnd )
				)
				( attribute "PHYS_PAGE" "44"
					( Origin gFrontEnd )
				)
				( attribute "ROOM" "DDR4_CH_A"
					( Origin gFrontEnd )
				)
				( attribute "ROT" "0"
					( Origin gFrontEnd )
				)
				( attribute "SEC" "4"
					( Origin gFrontEnd )
				)
				( attribute "SEC_TYPE" "PIP"
					( Origin gFrontEnd )
				)
				( attribute "VER" "4"
					( Origin gFrontEnd )
				)
				( attribute "XY" "(1600,1650)"
					( Origin gFrontEnd )
				)
				( attribute "CHIPS_PART_NAME" "SCONN288_H44441003"
					( Origin gPackager )
				)
				( attribute "CDS_PART_NAME" "SCONN288_H44441003_PIP-SCONN,HA"
					( Origin gPackager )
				)
				( objectStatus "J6T1" )
				( pin "\12v\(0)"
					( attribute "PN" "145"
						( Origin gPackager )
					)
					( objectStatus "J6T1.145" )
				)
				( pin "\12v\(1)"
					( attribute "PN" "1"
						( Origin gPackager )
					)
					( objectStatus "J6T1.1" )
				)
				( pin "vdd(0)"
					( attribute "PN" "236"
						( Origin gPackager )
					)
					( objectStatus "J6T1.236" )
				)
				( pin "vdd(1)"
					( attribute "PN" "233"
						( Origin gPackager )
					)
					( objectStatus "J6T1.233" )
				)
				( pin "vdd(2)"
					( attribute "PN" "231"
						( Origin gPackager )
					)
					( objectStatus "J6T1.231" )
				)
				( pin "vdd(3)"
					( attribute "PN" "229"
						( Origin gPackager )
					)
					( objectStatus "J6T1.229" )
				)
				( pin "vdd(4)"
					( attribute "PN" "226"
						( Origin gPackager )
					)
					( objectStatus "J6T1.226" )
				)
				( pin "vdd(5)"
					( attribute "PN" "223"
						( Origin gPackager )
					)
					( objectStatus "J6T1.223" )
				)
				( pin "vdd(6)"
					( attribute "PN" "220"
						( Origin gPackager )
					)
					( objectStatus "J6T1.220" )
				)
				( pin "vdd(7)"
					( attribute "PN" "217"
						( Origin gPackager )
					)
					( objectStatus "J6T1.217" )
				)
				( pin "vdd(8)"
					( attribute "PN" "215"
						( Origin gPackager )
					)
					( objectStatus "J6T1.215" )
				)
				( pin "vdd(9)"
					( attribute "PN" "212"
						( Origin gPackager )
					)
					( objectStatus "J6T1.212" )
				)
				( pin "vdd(10)"
					( attribute "PN" "209"
						( Origin gPackager )
					)
					( objectStatus "J6T1.209" )
				)
				( pin "vdd(11)"
					( attribute "PN" "206"
						( Origin gPackager )
					)
					( objectStatus "J6T1.206" )
				)
				( pin "vdd(12)"
					( attribute "PN" "204"
						( Origin gPackager )
					)
					( objectStatus "J6T1.204" )
				)
				( pin "vdd(13)"
					( attribute "PN" "92"
						( Origin gPackager )
					)
					( objectStatus "J6T1.92" )
				)
				( pin "vdd(14)"
					( attribute "PN" "90"
						( Origin gPackager )
					)
					( objectStatus "J6T1.90" )
				)
				( pin "vdd(15)"
					( attribute "PN" "88"
						( Origin gPackager )
					)
					( objectStatus "J6T1.88" )
				)
				( pin "vdd(16)"
					( attribute "PN" "85"
						( Origin gPackager )
					)
					( objectStatus "J6T1.85" )
				)
				( pin "vdd(17)"
					( attribute "PN" "83"
						( Origin gPackager )
					)
					( objectStatus "J6T1.83" )
				)
				( pin "vdd(18)"
					( attribute "PN" "80"
						( Origin gPackager )
					)
					( objectStatus "J6T1.80" )
				)
				( pin "vdd(19)"
					( attribute "PN" "76"
						( Origin gPackager )
					)
					( objectStatus "J6T1.76" )
				)
				( pin "vdd(20)"
					( attribute "PN" "73"
						( Origin gPackager )
					)
					( objectStatus "J6T1.73" )
				)
				( pin "vdd(21)"
					( attribute "PN" "70"
						( Origin gPackager )
					)
					( objectStatus "J6T1.70" )
				)
				( pin "vdd(22)"
					( attribute "PN" "67"
						( Origin gPackager )
					)
					( objectStatus "J6T1.67" )
				)
				( pin "vdd(23)"
					( attribute "PN" "64"
						( Origin gPackager )
					)
					( objectStatus "J6T1.64" )
				)
				( pin "vdd(24)"
					( attribute "PN" "61"
						( Origin gPackager )
					)
					( objectStatus "J6T1.61" )
				)
				( pin "vdd(25)"
					( attribute "PN" "59"
						( Origin gPackager )
					)
					( objectStatus "J6T1.59" )
				)
				( pin "vpp(0)"
					( attribute "PN" "287"
						( Origin gPackager )
					)
					( objectStatus "J6T1.287" )
				)
				( pin "vpp(1)"
					( attribute "PN" "286"
						( Origin gPackager )
					)
					( objectStatus "J6T1.286" )
				)
				( pin "vpp(2)"
					( attribute "PN" "288"
						( Origin gPackager )
					)
					( objectStatus "J6T1.288" )
				)
				( pin "vpp(3)"
					( attribute "PN" "143"
						( Origin gPackager )
					)
					( objectStatus "J6T1.143" )
				)
				( pin "vpp(4)"
					( attribute "PN" "142"
						( Origin gPackager )
					)
					( objectStatus "J6T1.142" )
				)
				( pin "vtt(0)"
					( attribute "PN" "221"
						( Origin gPackager )
					)
					( objectStatus "J6T1.221" )
				)
				( pin "vtt(1)"
					( attribute "PN" "77"
						( Origin gPackager )
					)
					( objectStatus "J6T1.77" )
				)
			)
			( gate "@baseboard_fab2_lib.baseboard_fab2(sch_1):page44_i120"
				( attribute "BOM_COST" "MEM"
					( Origin gFrontEnd )
				)
				( attribute "CDS_LIB" "mstr_sconn"
					( Origin gPackager )
				)
				( attribute "CDS_LOCATION" "J6T1"
					( Origin gPackager )
				)
				( attribute "CDS_SEC" "2"
					( Origin gPackager )
				)
				( attribute "LOCATION" "J6T1"
					( Origin gFrontEnd )
				)
				( attribute "MATERIAL" "SCONN"
					( Origin gFrontEnd )
				)
				( attribute "PACK_TYPE" "PIP"
					( Origin gFrontEnd )
				)
				( attribute "PART_NUMBER" "H44441-003"
					( Origin gFrontEnd )
				)
				( attribute "PHYS_PAGE" "44"
					( Origin gFrontEnd )
				)
				( attribute "ROOM" "DDR4_CH_A"
					( Origin gFrontEnd )
				)
				( attribute "ROT" "0"
					( Origin gFrontEnd )
				)
				( attribute "SEC" "2"
					( Origin gFrontEnd )
				)
				( attribute "SEC_TYPE" "PIP"
					( Origin gFrontEnd )
				)
				( attribute "VER" "2"
					( Origin gFrontEnd )
				)
				( attribute "XY" "(1650,4000)"
					( Origin gFrontEnd )
				)
				( attribute "CHIPS_PART_NAME" "SCONN288_H44441003"
					( Origin gPackager )
				)
				( attribute "CDS_PART_NAME" "SCONN288_H44441003_PIP-SCONN,HA"
					( Origin gPackager )
				)
				( objectStatus "J6T1" )
				( pin "dqs0n"
					( attribute "PN" "152"
						( Origin gPackager )
					)
					( objectStatus "J6T1.152" )
				)
				( pin "dqs0p"
					( attribute "PN" "153"
						( Origin gPackager )
					)
					( objectStatus "J6T1.153" )
				)
				( pin "dqs1n"
					( attribute "PN" "163"
						( Origin gPackager )
					)
					( objectStatus "J6T1.163" )
				)
				( pin "dqs1p"
					( attribute "PN" "164"
						( Origin gPackager )
					)
					( objectStatus "J6T1.164" )
				)
				( pin "dqs2n"
					( attribute "PN" "174"
						( Origin gPackager )
					)
					( objectStatus "J6T1.174" )
				)
				( pin "dqs2p"
					( attribute "PN" "175"
						( Origin gPackager )
					)
					( objectStatus "J6T1.175" )
				)
				( pin "dqs3n"
					( attribute "PN" "185"
						( Origin gPackager )
					)
					( objectStatus "J6T1.185" )
				)
				( pin "dqs3p"
					( attribute "PN" "186"
						( Origin gPackager )
					)
					( objectStatus "J6T1.186" )
				)
				( pin "dqs4n"
					( attribute "PN" "244"
						( Origin gPackager )
					)
					( objectStatus "J6T1.244" )
				)
				( pin "dqs4p"
					( attribute "PN" "245"
						( Origin gPackager )
					)
					( objectStatus "J6T1.245" )
				)
				( pin "dqs5n"
					( attribute "PN" "255"
						( Origin gPackager )
					)
					( objectStatus "J6T1.255" )
				)
				( pin "dqs5p"
					( attribute "PN" "256"
						( Origin gPackager )
					)
					( objectStatus "J6T1.256" )
				)
				( pin "dqs6n"
					( attribute "PN" "266"
						( Origin gPackager )
					)
					( objectStatus "J6T1.266" )
				)
				( pin "dqs6p"
					( attribute "PN" "267"
						( Origin gPackager )
					)
					( objectStatus "J6T1.267" )
				)
				( pin "dqs7n"
					( attribute "PN" "277"
						( Origin gPackager )
					)
					( objectStatus "J6T1.277" )
				)
				( pin "dqs7p"
					( attribute "PN" "278"
						( Origin gPackager )
					)
					( objectStatus "J6T1.278" )
				)
				( pin "dqs8n"
					( attribute "PN" "196"
						( Origin gPackager )
					)
					( objectStatus "J6T1.196" )
				)
				( pin "dqs8p"
					( attribute "PN" "197"
						( Origin gPackager )
					)
					( objectStatus "J6T1.197" )
				)
				( pin "dqs9n"
					( attribute "PN" "8"
						( Origin gPackager )
					)
					( objectStatus "J6T1.8" )
				)
				( pin "dqs9p"
					( attribute "PN" "7"
						( Origin gPackager )
					)
					( objectStatus "J6T1.7" )
				)
				( pin "dqs10n"
					( attribute "PN" "19"
						( Origin gPackager )
					)
					( objectStatus "J6T1.19" )
				)
				( pin "dqs10p"
					( attribute "PN" "18"
						( Origin gPackager )
					)
					( objectStatus "J6T1.18" )
				)
				( pin "dqs11n"
					( attribute "PN" "30"
						( Origin gPackager )
					)
					( objectStatus "J6T1.30" )
				)
				( pin "dqs11p"
					( attribute "PN" "29"
						( Origin gPackager )
					)
					( objectStatus "J6T1.29" )
				)
				( pin "dqs12n"
					( attribute "PN" "41"
						( Origin gPackager )
					)
					( objectStatus "J6T1.41" )
				)
				( pin "dqs12p"
					( attribute "PN" "40"
						( Origin gPackager )
					)
					( objectStatus "J6T1.40" )
				)
				( pin "dqs13n"
					( attribute "PN" "100"
						( Origin gPackager )
					)
					( objectStatus "J6T1.100" )
				)
				( pin "dqs13p"
					( attribute "PN" "99"
						( Origin gPackager )
					)
					( objectStatus "J6T1.99" )
				)
				( pin "dqs14n"
					( attribute "PN" "111"
						( Origin gPackager )
					)
					( objectStatus "J6T1.111" )
				)
				( pin "dqs14p"
					( attribute "PN" "110"
						( Origin gPackager )
					)
					( objectStatus "J6T1.110" )
				)
				( pin "dqs15n"
					( attribute "PN" "122"
						( Origin gPackager )
					)
					( objectStatus "J6T1.122" )
				)
				( pin "dqs15p"
					( attribute "PN" "121"
						( Origin gPackager )
					)
					( objectStatus "J6T1.121" )
				)
				( pin "dqs16n"
					( attribute "PN" "133"
						( Origin gPackager )
					)
					( objectStatus "J6T1.133" )
				)
				( pin "dqs16p"
					( attribute "PN" "132"
						( Origin gPackager )
					)
					( objectStatus "J6T1.132" )
				)
				( pin "dqs17n"
					( attribute "PN" "52"
						( Origin gPackager )
					)
					( objectStatus "J6T1.52" )
				)
				( pin "dqs17p"
					( attribute "PN" "51"
						( Origin gPackager )
					)
					( objectStatus "J6T1.51" )
				)
			)
			( gate "@baseboard_fab2_lib.baseboard_fab2(sch_1):page44_i139"
				( attribute "BOM_COST" "MEM"
					( Origin gFrontEnd )
				)
				( attribute "CDS_LIB" "mstr_sconn"
					( Origin gPackager )
				)
				( attribute "CDS_LOCATION" "J6T1"
					( Origin gPackager )
				)
				( attribute "CDS_SEC" "3"
					( Origin gPackager )
				)
				( attribute "LOCATION" "J6T1"
					( Origin gFrontEnd )
				)
				( attribute "MATERIAL" "SCONN"
					( Origin gFrontEnd )
				)
				( attribute "PACK_TYPE" "PIP"
					( Origin gFrontEnd )
				)
				( attribute "PART_NUMBER" "H44441-003"
					( Origin gFrontEnd )
				)
				( attribute "PHYS_PAGE" "44"
					( Origin gFrontEnd )
				)
				( attribute "ROOM" "DDR4_CH_A"
					( Origin gFrontEnd )
				)
				( attribute "ROT" "0"
					( Origin gFrontEnd )
				)
				( attribute "SEC" "3"
					( Origin gFrontEnd )
				)
				( attribute "SEC_TYPE" "PIP"
					( Origin gFrontEnd )
				)
				( attribute "VER" "3"
					( Origin gFrontEnd )
				)
				( attribute "XY" "(3450,2400)"
					( Origin gFrontEnd )
				)
				( attribute "CHIPS_PART_NAME" "SCONN288_H44441003"
					( Origin gPackager )
				)
				( attribute "CDS_PART_NAME" "SCONN288_H44441003_PIP-SCONN,HA"
					( Origin gPackager )
				)
				( objectStatus "J6T1" )
				( pin "vss(0)"
					( attribute "PN" "283"
						( Origin gPackager )
					)
					( objectStatus "J6T1.283" )
				)
				( pin "vss(1)"
					( attribute "PN" "281"
						( Origin gPackager )
					)
					( objectStatus "J6T1.281" )
				)
				( pin "vss(2)"
					( attribute "PN" "279"
						( Origin gPackager )
					)
					( objectStatus "J6T1.279" )
				)
				( pin "vss(3)"
					( attribute "PN" "276"
						( Origin gPackager )
					)
					( objectStatus "J6T1.276" )
				)
				( pin "vss(4)"
					( attribute "PN" "274"
						( Origin gPackager )
					)
					( objectStatus "J6T1.274" )
				)
				( pin "vss(5)"
					( attribute "PN" "272"
						( Origin gPackager )
					)
					( objectStatus "J6T1.272" )
				)
				( pin "vss(6)"
					( attribute "PN" "270"
						( Origin gPackager )
					)
					( objectStatus "J6T1.270" )
				)
				( pin "vss(7)"
					( attribute "PN" "268"
						( Origin gPackager )
					)
					( objectStatus "J6T1.268" )
				)
				( pin "vss(8)"
					( attribute "PN" "265"
						( Origin gPackager )
					)
					( objectStatus "J6T1.265" )
				)
				( pin "vss(9)"
					( attribute "PN" "263"
						( Origin gPackager )
					)
					( objectStatus "J6T1.263" )
				)
				( pin "vss(10)"
					( attribute "PN" "261"
						( Origin gPackager )
					)
					( objectStatus "J6T1.261" )
				)
				( pin "vss(11)"
					( attribute "PN" "259"
						( Origin gPackager )
					)
					( objectStatus "J6T1.259" )
				)
				( pin "vss(12)"
					( attribute "PN" "257"
						( Origin gPackager )
					)
					( objectStatus "J6T1.257" )
				)
				( pin "vss(13)"
					( attribute "PN" "254"
						( Origin gPackager )
					)
					( objectStatus "J6T1.254" )
				)
				( pin "vss(14)"
					( attribute "PN" "252"
						( Origin gPackager )
					)
					( objectStatus "J6T1.252" )
				)
				( pin "vss(15)"
					( attribute "PN" "250"
						( Origin gPackager )
					)
					( objectStatus "J6T1.250" )
				)
				( pin "vss(16)"
					( attribute "PN" "248"
						( Origin gPackager )
					)
					( objectStatus "J6T1.248" )
				)
				( pin "vss(17)"
					( attribute "PN" "246"
						( Origin gPackager )
					)
					( objectStatus "J6T1.246" )
				)
				( pin "vss(18)"
					( attribute "PN" "243"
						( Origin gPackager )
					)
					( objectStatus "J6T1.243" )
				)
				( pin "vss(19)"
					( attribute "PN" "241"
						( Origin gPackager )
					)
					( objectStatus "J6T1.241" )
				)
				( pin "vss(20)"
					( attribute "PN" "239"
						( Origin gPackager )
					)
					( objectStatus "J6T1.239" )
				)
				( pin "vss(21)"
					( attribute "PN" "202"
						( Origin gPackager )
					)
					( objectStatus "J6T1.202" )
				)
				( pin "vss(22)"
					( attribute "PN" "200"
						( Origin gPackager )
					)
					( objectStatus "J6T1.200" )
				)
				( pin "vss(23)"
					( attribute "PN" "198"
						( Origin gPackager )
					)
					( objectStatus "J6T1.198" )
				)
				( pin "vss(24)"
					( attribute "PN" "195"
						( Origin gPackager )
					)
					( objectStatus "J6T1.195" )
				)
				( pin "vss(25)"
					( attribute "PN" "193"
						( Origin gPackager )
					)
					( objectStatus "J6T1.193" )
				)
				( pin "vss(26)"
					( attribute "PN" "191"
						( Origin gPackager )
					)
					( objectStatus "J6T1.191" )
				)
				( pin "vss(27)"
					( attribute "PN" "189"
						( Origin gPackager )
					)
					( objectStatus "J6T1.189" )
				)
				( pin "vss(28)"
					( attribute "PN" "187"
						( Origin gPackager )
					)
					( objectStatus "J6T1.187" )
				)
				( pin "vss(29)"
					( attribute "PN" "184"
						( Origin gPackager )
					)
					( objectStatus "J6T1.184" )
				)
				( pin "vss(30)"
					( attribute "PN" "182"
						( Origin gPackager )
					)
					( objectStatus "J6T1.182" )
				)
				( pin "vss(31)"
					( attribute "PN" "180"
						( Origin gPackager )
					)
					( objectStatus "J6T1.180" )
				)
				( pin "vss(32)"
					( attribute "PN" "178"
						( Origin gPackager )
					)
					( objectStatus "J6T1.178" )
				)
				( pin "vss(33)"
					( attribute "PN" "176"
						( Origin gPackager )
					)
					( objectStatus "J6T1.176" )
				)
				( pin "vss(34)"
					( attribute "PN" "173"
						( Origin gPackager )
					)
					( objectStatus "J6T1.173" )
				)
				( pin "vss(35)"
					( attribute "PN" "171"
						( Origin gPackager )
					)
					( objectStatus "J6T1.171" )
				)
				( pin "vss(36)"
					( attribute "PN" "169"
						( Origin gPackager )
					)
					( objectStatus "J6T1.169" )
				)
				( pin "vss(37)"
					( attribute "PN" "167"
						( Origin gPackager )
					)
					( objectStatus "J6T1.167" )
				)
				( pin "vss(38)"
					( attribute "PN" "165"
						( Origin gPackager )
					)
					( objectStatus "J6T1.165" )
				)
				( pin "vss(39)"
					( attribute "PN" "162"
						( Origin gPackager )
					)
					( objectStatus "J6T1.162" )
				)
				( pin "vss(40)"
					( attribute "PN" "160"
						( Origin gPackager )
					)
					( objectStatus "J6T1.160" )
				)
				( pin "vss(41)"
					( attribute "PN" "158"
						( Origin gPackager )
					)
					( objectStatus "J6T1.158" )
				)
				( pin "vss(42)"
					( attribute "PN" "156"
						( Origin gPackager )
					)
					( objectStatus "J6T1.156" )
				)
				( pin "vss(43)"
					( attribute "PN" "154"
						( Origin gPackager )
					)
					( objectStatus "J6T1.154" )
				)
				( pin "vss(44)"
					( attribute "PN" "151"
						( Origin gPackager )
					)
					( objectStatus "J6T1.151" )
				)
				( pin "vss(45)"
					( attribute "PN" "149"
						( Origin gPackager )
					)
					( objectStatus "J6T1.149" )
				)
				( pin "vss(46)"
					( attribute "PN" "147"
						( Origin gPackager )
					)
					( objectStatus "J6T1.147" )
				)
				( pin "vss(47)"
					( attribute "PN" "138"
						( Origin gPackager )
					)
					( objectStatus "J6T1.138" )
				)
				( pin "vss(48)"
					( attribute "PN" "136"
						( Origin gPackager )
					)
					( objectStatus "J6T1.136" )
				)
				( pin "vss(49)"
					( attribute "PN" "134"
						( Origin gPackager )
					)
					( objectStatus "J6T1.134" )
				)
				( pin "vss(50)"
					( attribute "PN" "131"
						( Origin gPackager )
					)
					( objectStatus "J6T1.131" )
				)
				( pin "vss(51)"
					( attribute "PN" "129"
						( Origin gPackager )
					)
					( objectStatus "J6T1.129" )
				)
				( pin "vss(52)"
					( attribute "PN" "127"
						( Origin gPackager )
					)
					( objectStatus "J6T1.127" )
				)
				( pin "vss(53)"
					( attribute "PN" "125"
						( Origin gPackager )
					)
					( objectStatus "J6T1.125" )
				)
				( pin "vss(54)"
					( attribute "PN" "123"
						( Origin gPackager )
					)
					( objectStatus "J6T1.123" )
				)
				( pin "vss(55)"
					( attribute "PN" "120"
						( Origin gPackager )
					)
					( objectStatus "J6T1.120" )
				)
				( pin "vss(56)"
					( attribute "PN" "118"
						( Origin gPackager )
					)
					( objectStatus "J6T1.118" )
				)
				( pin "vss(57)"
					( attribute "PN" "116"
						( Origin gPackager )
					)
					( objectStatus "J6T1.116" )
				)
				( pin "vss(58)"
					( attribute "PN" "114"
						( Origin gPackager )
					)
					( objectStatus "J6T1.114" )
				)
				( pin "vss(59)"
					( attribute "PN" "112"
						( Origin gPackager )
					)
					( objectStatus "J6T1.112" )
				)
				( pin "vss(60)"
					( attribute "PN" "109"
						( Origin gPackager )
					)
					( objectStatus "J6T1.109" )
				)
				( pin "vss(61)"
					( attribute "PN" "107"
						( Origin gPackager )
					)
					( objectStatus "J6T1.107" )
				)
				( pin "vss(62)"
					( attribute "PN" "105"
						( Origin gPackager )
					)
					( objectStatus "J6T1.105" )
				)
				( pin "vss(63)"
					( attribute "PN" "103"
						( Origin gPackager )
					)
					( objectStatus "J6T1.103" )
				)
				( pin "vss(64)"
					( attribute "PN" "101"
						( Origin gPackager )
					)
					( objectStatus "J6T1.101" )
				)
				( pin "vss(65)"
					( attribute "PN" "98"
						( Origin gPackager )
					)
					( objectStatus "J6T1.98" )
				)
				( pin "vss(66)"
					( attribute "PN" "96"
						( Origin gPackager )
					)
					( objectStatus "J6T1.96" )
				)
				( pin "vss(67)"
					( attribute "PN" "94"
						( Origin gPackager )
					)
					( objectStatus "J6T1.94" )
				)
				( pin "vss(68)"
					( attribute "PN" "57"
						( Origin gPackager )
					)
					( objectStatus "J6T1.57" )
				)
				( pin "vss(69)"
					( attribute "PN" "55"
						( Origin gPackager )
					)
					( objectStatus "J6T1.55" )
				)
				( pin "vss(70)"
					( attribute "PN" "53"
						( Origin gPackager )
					)
					( objectStatus "J6T1.53" )
				)
				( pin "vss(71)"
					( attribute "PN" "50"
						( Origin gPackager )
					)
					( objectStatus "J6T1.50" )
				)
				( pin "vss(72)"
					( attribute "PN" "48"
						( Origin gPackager )
					)
					( objectStatus "J6T1.48" )
				)
				( pin "vss(73)"
					( attribute "PN" "46"
						( Origin gPackager )
					)
					( objectStatus "J6T1.46" )
				)
				( pin "vss(74)"
					( attribute "PN" "44"
						( Origin gPackager )
					)
					( objectStatus "J6T1.44" )
				)
				( pin "vss(75)"
					( attribute "PN" "42"
						( Origin gPackager )
					)
					( objectStatus "J6T1.42" )
				)
				( pin "vss(76)"
					( attribute "PN" "39"
						( Origin gPackager )
					)
					( objectStatus "J6T1.39" )
				)
				( pin "vss(77)"
					( attribute "PN" "37"
						( Origin gPackager )
					)
					( objectStatus "J6T1.37" )
				)
				( pin "vss(78)"
					( attribute "PN" "35"
						( Origin gPackager )
					)
					( objectStatus "J6T1.35" )
				)
				( pin "vss(79)"
					( attribute "PN" "33"
						( Origin gPackager )
					)
					( objectStatus "J6T1.33" )
				)
				( pin "vss(80)"
					( attribute "PN" "31"
						( Origin gPackager )
					)
					( objectStatus "J6T1.31" )
				)
				( pin "vss(81)"
					( attribute "PN" "28"
						( Origin gPackager )
					)
					( objectStatus "J6T1.28" )
				)
				( pin "vss(82)"
					( attribute "PN" "26"
						( Origin gPackager )
					)
					( objectStatus "J6T1.26" )
				)
				( pin "vss(83)"
					( attribute "PN" "24"
						( Origin gPackager )
					)
					( objectStatus "J6T1.24" )
				)
				( pin "vss(84)"
					( attribute "PN" "22"
						( Origin gPackager )
					)
					( objectStatus "J6T1.22" )
				)
				( pin "vss(85)"
					( attribute "PN" "20"
						( Origin gPackager )
					)
					( objectStatus "J6T1.20" )
				)
				( pin "vss(86)"
					( attribute "PN" "17"
						( Origin gPackager )
					)
					( objectStatus "J6T1.17" )
				)
				( pin "vss(87)"
					( attribute "PN" "15"
						( Origin gPackager )
					)
					( objectStatus "J6T1.15" )
				)
				( pin "vss(88)"
					( attribute "PN" "13"
						( Origin gPackager )
					)
					( objectStatus "J6T1.13" )
				)
				( pin "vss(89)"
					( attribute "PN" "11"
						( Origin gPackager )
					)
					( objectStatus "J6T1.11" )
				)
				( pin "vss(90)"
					( attribute "PN" "9"
						( Origin gPackager )
					)
					( objectStatus "J6T1.9" )
				)
				( pin "vss(91)"
					( attribute "PN" "6"
						( Origin gPackager )
					)
					( objectStatus "J6T1.6" )
				)
				( pin "vss(92)"
					( attribute "PN" "4"
						( Origin gPackager )
					)
					( objectStatus "J6T1.4" )
				)
				( pin "vss(93)"
					( attribute "PN" "2"
						( Origin gPackager )
					)
					( objectStatus "J6T1.2" )
				)
			)
			( gate "@baseboard_fab2_lib.baseboard_fab2(sch_1):page45_i43"
				( attribute "BOM_COST" "MEM"
					( Origin gFrontEnd )
				)
				( attribute "CDS_LIB" "mstr_sconn"
					( Origin gPackager )
				)
				( attribute "CDS_LOCATION" "J4G2"
					( Origin gPackager )
				)
				( attribute "CDS_SEC" "3"
					( Origin gPackager )
				)
				( attribute "LOCATION" "J4G2"
					( Origin gFrontEnd )
				)
				( attribute "MATERIAL" "SCONN"
					( Origin gFrontEnd )
				)
				( attribute "PACK_TYPE" "PIP"
					( Origin gFrontEnd )
				)
				( attribute "PART_NUMBER" "H44441-004"
					( Origin gFrontEnd )
				)
				( attribute "PHYS_PAGE" "45"
					( Origin gFrontEnd )
				)
				( attribute "ROOM" "DDR4_CH_B"
					( Origin gFrontEnd )
				)
				( attribute "ROT" "0"
					( Origin gFrontEnd )
				)
				( attribute "SEC" "3"
					( Origin gFrontEnd )
				)
				( attribute "SEC_TYPE" "PIP"
					( Origin gFrontEnd )
				)
				( attribute "VER" "3"
					( Origin gFrontEnd )
				)
				( attribute "XY" "(1800,2600)"
					( Origin gFrontEnd )
				)
				( attribute "CHIPS_PART_NAME" "SCONN288_H44441004"
					( Origin gPackager )
				)
				( attribute "CDS_PART_NAME" "SCONN288_H44441004_PIP-SCONN,HA"
					( Origin gPackager )
				)
				( objectStatus "J4G2" )
				( pin "vss(0)"
					( attribute "PN" "283"
						( Origin gPackager )
					)
					( objectStatus "J4G2.283" )
				)
				( pin "vss(1)"
					( attribute "PN" "281"
						( Origin gPackager )
					)
					( objectStatus "J4G2.281" )
				)
				( pin "vss(2)"
					( attribute "PN" "279"
						( Origin gPackager )
					)
					( objectStatus "J4G2.279" )
				)
				( pin "vss(3)"
					( attribute "PN" "276"
						( Origin gPackager )
					)
					( objectStatus "J4G2.276" )
				)
				( pin "vss(4)"
					( attribute "PN" "274"
						( Origin gPackager )
					)
					( objectStatus "J4G2.274" )
				)
				( pin "vss(5)"
					( attribute "PN" "272"
						( Origin gPackager )
					)
					( objectStatus "J4G2.272" )
				)
				( pin "vss(6)"
					( attribute "PN" "270"
						( Origin gPackager )
					)
					( objectStatus "J4G2.270" )
				)
				( pin "vss(7)"
					( attribute "PN" "268"
						( Origin gPackager )
					)
					( objectStatus "J4G2.268" )
				)
				( pin "vss(8)"
					( attribute "PN" "265"
						( Origin gPackager )
					)
					( objectStatus "J4G2.265" )
				)
				( pin "vss(9)"
					( attribute "PN" "263"
						( Origin gPackager )
					)
					( objectStatus "J4G2.263" )
				)
				( pin "vss(10)"
					( attribute "PN" "261"
						( Origin gPackager )
					)
					( objectStatus "J4G2.261" )
				)
				( pin "vss(11)"
					( attribute "PN" "259"
						( Origin gPackager )
					)
					( objectStatus "J4G2.259" )
				)
				( pin "vss(12)"
					( attribute "PN" "257"
						( Origin gPackager )
					)
					( objectStatus "J4G2.257" )
				)
				( pin "vss(13)"
					( attribute "PN" "254"
						( Origin gPackager )
					)
					( objectStatus "J4G2.254" )
				)
				( pin "vss(14)"
					( attribute "PN" "252"
						( Origin gPackager )
					)
					( objectStatus "J4G2.252" )
				)
				( pin "vss(15)"
					( attribute "PN" "250"
						( Origin gPackager )
					)
					( objectStatus "J4G2.250" )
				)
				( pin "vss(16)"
					( attribute "PN" "248"
						( Origin gPackager )
					)
					( objectStatus "J4G2.248" )
				)
				( pin "vss(17)"
					( attribute "PN" "246"
						( Origin gPackager )
					)
					( objectStatus "J4G2.246" )
				)
				( pin "vss(18)"
					( attribute "PN" "243"
						( Origin gPackager )
					)
					( objectStatus "J4G2.243" )
				)
				( pin "vss(19)"
					( attribute "PN" "241"
						( Origin gPackager )
					)
					( objectStatus "J4G2.241" )
				)
				( pin "vss(20)"
					( attribute "PN" "239"
						( Origin gPackager )
					)
					( objectStatus "J4G2.239" )
				)
				( pin "vss(21)"
					( attribute "PN" "202"
						( Origin gPackager )
					)
					( objectStatus "J4G2.202" )
				)
				( pin "vss(22)"
					( attribute "PN" "200"
						( Origin gPackager )
					)
					( objectStatus "J4G2.200" )
				)
				( pin "vss(23)"
					( attribute "PN" "198"
						( Origin gPackager )
					)
					( objectStatus "J4G2.198" )
				)
				( pin "vss(24)"
					( attribute "PN" "195"
						( Origin gPackager )
					)
					( objectStatus "J4G2.195" )
				)
				( pin "vss(25)"
					( attribute "PN" "193"
						( Origin gPackager )
					)
					( objectStatus "J4G2.193" )
				)
				( pin "vss(26)"
					( attribute "PN" "191"
						( Origin gPackager )
					)
					( objectStatus "J4G2.191" )
				)
				( pin "vss(27)"
					( attribute "PN" "189"
						( Origin gPackager )
					)
					( objectStatus "J4G2.189" )
				)
				( pin "vss(28)"
					( attribute "PN" "187"
						( Origin gPackager )
					)
					( objectStatus "J4G2.187" )
				)
				( pin "vss(29)"
					( attribute "PN" "184"
						( Origin gPackager )
					)
					( objectStatus "J4G2.184" )
				)
				( pin "vss(30)"
					( attribute "PN" "182"
						( Origin gPackager )
					)
					( objectStatus "J4G2.182" )
				)
				( pin "vss(31)"
					( attribute "PN" "180"
						( Origin gPackager )
					)
					( objectStatus "J4G2.180" )
				)
				( pin "vss(32)"
					( attribute "PN" "178"
						( Origin gPackager )
					)
					( objectStatus "J4G2.178" )
				)
				( pin "vss(33)"
					( attribute "PN" "176"
						( Origin gPackager )
					)
					( objectStatus "J4G2.176" )
				)
				( pin "vss(34)"
					( attribute "PN" "173"
						( Origin gPackager )
					)
					( objectStatus "J4G2.173" )
				)
				( pin "vss(35)"
					( attribute "PN" "171"
						( Origin gPackager )
					)
					( objectStatus "J4G2.171" )
				)
				( pin "vss(36)"
					( attribute "PN" "169"
						( Origin gPackager )
					)
					( objectStatus "J4G2.169" )
				)
				( pin "vss(37)"
					( attribute "PN" "167"
						( Origin gPackager )
					)
					( objectStatus "J4G2.167" )
				)
				( pin "vss(38)"
					( attribute "PN" "165"
						( Origin gPackager )
					)
					( objectStatus "J4G2.165" )
				)
				( pin "vss(39)"
					( attribute "PN" "162"
						( Origin gPackager )
					)
					( objectStatus "J4G2.162" )
				)
				( pin "vss(40)"
					( attribute "PN" "160"
						( Origin gPackager )
					)
					( objectStatus "J4G2.160" )
				)
				( pin "vss(41)"
					( attribute "PN" "158"
						( Origin gPackager )
					)
					( objectStatus "J4G2.158" )
				)
				( pin "vss(42)"
					( attribute "PN" "156"
						( Origin gPackager )
					)
					( objectStatus "J4G2.156" )
				)
				( pin "vss(43)"
					( attribute "PN" "154"
						( Origin gPackager )
					)
					( objectStatus "J4G2.154" )
				)
				( pin "vss(44)"
					( attribute "PN" "151"
						( Origin gPackager )
					)
					( objectStatus "J4G2.151" )
				)
				( pin "vss(45)"
					( attribute "PN" "149"
						( Origin gPackager )
					)
					( objectStatus "J4G2.149" )
				)
				( pin "vss(46)"
					( attribute "PN" "147"
						( Origin gPackager )
					)
					( objectStatus "J4G2.147" )
				)
				( pin "vss(47)"
					( attribute "PN" "138"
						( Origin gPackager )
					)
					( objectStatus "J4G2.138" )
				)
				( pin "vss(48)"
					( attribute "PN" "136"
						( Origin gPackager )
					)
					( objectStatus "J4G2.136" )
				)
				( pin "vss(49)"
					( attribute "PN" "134"
						( Origin gPackager )
					)
					( objectStatus "J4G2.134" )
				)
				( pin "vss(50)"
					( attribute "PN" "131"
						( Origin gPackager )
					)
					( objectStatus "J4G2.131" )
				)
				( pin "vss(51)"
					( attribute "PN" "129"
						( Origin gPackager )
					)
					( objectStatus "J4G2.129" )
				)
				( pin "vss(52)"
					( attribute "PN" "127"
						( Origin gPackager )
					)
					( objectStatus "J4G2.127" )
				)
				( pin "vss(53)"
					( attribute "PN" "125"
						( Origin gPackager )
					)
					( objectStatus "J4G2.125" )
				)
				( pin "vss(54)"
					( attribute "PN" "123"
						( Origin gPackager )
					)
					( objectStatus "J4G2.123" )
				)
				( pin "vss(55)"
					( attribute "PN" "120"
						( Origin gPackager )
					)
					( objectStatus "J4G2.120" )
				)
				( pin "vss(56)"
					( attribute "PN" "118"
						( Origin gPackager )
					)
					( objectStatus "J4G2.118" )
				)
				( pin "vss(57)"
					( attribute "PN" "116"
						( Origin gPackager )
					)
					( objectStatus "J4G2.116" )
				)
				( pin "vss(58)"
					( attribute "PN" "114"
						( Origin gPackager )
					)
					( objectStatus "J4G2.114" )
				)
				( pin "vss(59)"
					( attribute "PN" "112"
						( Origin gPackager )
					)
					( objectStatus "J4G2.112" )
				)
				( pin "vss(60)"
					( attribute "PN" "109"
						( Origin gPackager )
					)
					( objectStatus "J4G2.109" )
				)
				( pin "vss(61)"
					( attribute "PN" "107"
						( Origin gPackager )
					)
					( objectStatus "J4G2.107" )
				)
				( pin "vss(62)"
					( attribute "PN" "105"
						( Origin gPackager )
					)
					( objectStatus "J4G2.105" )
				)
				( pin "vss(63)"
					( attribute "PN" "103"
						( Origin gPackager )
					)
					( objectStatus "J4G2.103" )
				)
				( pin "vss(64)"
					( attribute "PN" "101"
						( Origin gPackager )
					)
					( objectStatus "J4G2.101" )
				)
				( pin "vss(65)"
					( attribute "PN" "98"
						( Origin gPackager )
					)
					( objectStatus "J4G2.98" )
				)
				( pin "vss(66)"
					( attribute "PN" "96"
						( Origin gPackager )
					)
					( objectStatus "J4G2.96" )
				)
				( pin "vss(67)"
					( attribute "PN" "94"
						( Origin gPackager )
					)
					( objectStatus "J4G2.94" )
				)
				( pin "vss(68)"
					( attribute "PN" "57"
						( Origin gPackager )
					)
					( objectStatus "J4G2.57" )
				)
				( pin "vss(69)"
					( attribute "PN" "55"
						( Origin gPackager )
					)
					( objectStatus "J4G2.55" )
				)
				( pin "vss(70)"
					( attribute "PN" "53"
						( Origin gPackager )
					)
					( objectStatus "J4G2.53" )
				)
				( pin "vss(71)"
					( attribute "PN" "50"
						( Origin gPackager )
					)
					( objectStatus "J4G2.50" )
				)
				( pin "vss(72)"
					( attribute "PN" "48"
						( Origin gPackager )
					)
					( objectStatus "J4G2.48" )
				)
				( pin "vss(73)"
					( attribute "PN" "46"
						( Origin gPackager )
					)
					( objectStatus "J4G2.46" )
				)
				( pin "vss(74)"
					( attribute "PN" "44"
						( Origin gPackager )
					)
					( objectStatus "J4G2.44" )
				)
				( pin "vss(75)"
					( attribute "PN" "42"
						( Origin gPackager )
					)
					( objectStatus "J4G2.42" )
				)
				( pin "vss(76)"
					( attribute "PN" "39"
						( Origin gPackager )
					)
					( objectStatus "J4G2.39" )
				)
				( pin "vss(77)"
					( attribute "PN" "37"
						( Origin gPackager )
					)
					( objectStatus "J4G2.37" )
				)
				( pin "vss(78)"
					( attribute "PN" "35"
						( Origin gPackager )
					)
					( objectStatus "J4G2.35" )
				)
				( pin "vss(79)"
					( attribute "PN" "33"
						( Origin gPackager )
					)
					( objectStatus "J4G2.33" )
				)
				( pin "vss(80)"
					( attribute "PN" "31"
						( Origin gPackager )
					)
					( objectStatus "J4G2.31" )
				)
				( pin "vss(81)"
					( attribute "PN" "28"
						( Origin gPackager )
					)
					( objectStatus "J4G2.28" )
				)
				( pin "vss(82)"
					( attribute "PN" "26"
						( Origin gPackager )
					)
					( objectStatus "J4G2.26" )
				)
				( pin "vss(83)"
					( attribute "PN" "24"
						( Origin gPackager )
					)
					( objectStatus "J4G2.24" )
				)
				( pin "vss(84)"
					( attribute "PN" "22"
						( Origin gPackager )
					)
					( objectStatus "J4G2.22" )
				)
				( pin "vss(85)"
					( attribute "PN" "20"
						( Origin gPackager )
					)
					( objectStatus "J4G2.20" )
				)
				( pin "vss(86)"
					( attribute "PN" "17"
						( Origin gPackager )
					)
					( objectStatus "J4G2.17" )
				)
				( pin "vss(87)"
					( attribute "PN" "15"
						( Origin gPackager )
					)
					( objectStatus "J4G2.15" )
				)
				( pin "vss(88)"
					( attribute "PN" "13"
						( Origin gPackager )
					)
					( objectStatus "J4G2.13" )
				)
				( pin "vss(89)"
					( attribute "PN" "11"
						( Origin gPackager )
					)
					( objectStatus "J4G2.11" )
				)
				( pin "vss(90)"
					( attribute "PN" "9"
						( Origin gPackager )
					)
					( objectStatus "J4G2.9" )
				)
				( pin "vss(91)"
					( attribute "PN" "6"
						( Origin gPackager )
					)
					( objectStatus "J4G2.6" )
				)
				( pin "vss(92)"
					( attribute "PN" "4"
						( Origin gPackager )
					)
					( objectStatus "J4G2.4" )
				)
				( pin "vss(93)"
					( attribute "PN" "2"
						( Origin gPackager )
					)
					( objectStatus "J4G2.2" )
				)
			)
			( gate "@baseboard_fab2_lib.baseboard_fab2(sch_1):page45_i61"
				( attribute "BOM_COST" "MEM"
					( Origin gFrontEnd )
				)
				( attribute "CDS_LIB" "mstr_sconn"
					( Origin gPackager )
				)
				( attribute "CDS_LOCATION" "J4G2"
					( Origin gPackager )
				)
				( attribute "CDS_SEC" "2"
					( Origin gPackager )
				)
				( attribute "LOCATION" "J4G2"
					( Origin gFrontEnd )
				)
				( attribute "MATERIAL" "SCONN"
					( Origin gFrontEnd )
				)
				( attribute "PACK_TYPE" "PIP"
					( Origin gFrontEnd )
				)
				( attribute "PART_NUMBER" "H44441-004"
					( Origin gFrontEnd )
				)
				( attribute "PHYS_PAGE" "45"
					( Origin gFrontEnd )
				)
				( attribute "ROOM" "DDR4_CH_B"
					( Origin gFrontEnd )
				)
				( attribute "ROT" "0"
					( Origin gFrontEnd )
				)
				( attribute "SEC" "2"
					( Origin gFrontEnd )
				)
				( attribute "SEC_TYPE" "PIP"
					( Origin gFrontEnd )
				)
				( attribute "VER" "2"
					( Origin gFrontEnd )
				)
				( attribute "XY" "(0,4300)"
					( Origin gFrontEnd )
				)
				( attribute "CHIPS_PART_NAME" "SCONN288_H44441004"
					( Origin gPackager )
				)
				( attribute "CDS_PART_NAME" "SCONN288_H44441004_PIP-SCONN,HA"
					( Origin gPackager )
				)
				( objectStatus "J4G2" )
				( pin "dqs0n"
					( attribute "PN" "152"
						( Origin gPackager )
					)
					( objectStatus "J4G2.152" )
				)
				( pin "dqs0p"
					( attribute "PN" "153"
						( Origin gPackager )
					)
					( objectStatus "J4G2.153" )
				)
				( pin "dqs1n"
					( attribute "PN" "163"
						( Origin gPackager )
					)
					( objectStatus "J4G2.163" )
				)
				( pin "dqs1p"
					( attribute "PN" "164"
						( Origin gPackager )
					)
					( objectStatus "J4G2.164" )
				)
				( pin "dqs2n"
					( attribute "PN" "174"
						( Origin gPackager )
					)
					( objectStatus "J4G2.174" )
				)
				( pin "dqs2p"
					( attribute "PN" "175"
						( Origin gPackager )
					)
					( objectStatus "J4G2.175" )
				)
				( pin "dqs3n"
					( attribute "PN" "185"
						( Origin gPackager )
					)
					( objectStatus "J4G2.185" )
				)
				( pin "dqs3p"
					( attribute "PN" "186"
						( Origin gPackager )
					)
					( objectStatus "J4G2.186" )
				)
				( pin "dqs4n"
					( attribute "PN" "244"
						( Origin gPackager )
					)
					( objectStatus "J4G2.244" )
				)
				( pin "dqs4p"
					( attribute "PN" "245"
						( Origin gPackager )
					)
					( objectStatus "J4G2.245" )
				)
				( pin "dqs5n"
					( attribute "PN" "255"
						( Origin gPackager )
					)
					( objectStatus "J4G2.255" )
				)
				( pin "dqs5p"
					( attribute "PN" "256"
						( Origin gPackager )
					)
					( objectStatus "J4G2.256" )
				)
				( pin "dqs6n"
					( attribute "PN" "266"
						( Origin gPackager )
					)
					( objectStatus "J4G2.266" )
				)
				( pin "dqs6p"
					( attribute "PN" "267"
						( Origin gPackager )
					)
					( objectStatus "J4G2.267" )
				)
				( pin "dqs7n"
					( attribute "PN" "277"
						( Origin gPackager )
					)
					( objectStatus "J4G2.277" )
				)
				( pin "dqs7p"
					( attribute "PN" "278"
						( Origin gPackager )
					)
					( objectStatus "J4G2.278" )
				)
				( pin "dqs8n"
					( attribute "PN" "196"
						( Origin gPackager )
					)
					( objectStatus "J4G2.196" )
				)
				( pin "dqs8p"
					( attribute "PN" "197"
						( Origin gPackager )
					)
					( objectStatus "J4G2.197" )
				)
				( pin "dqs9n"
					( attribute "PN" "8"
						( Origin gPackager )
					)
					( objectStatus "J4G2.8" )
				)
				( pin "dqs9p"
					( attribute "PN" "7"
						( Origin gPackager )
					)
					( objectStatus "J4G2.7" )
				)
				( pin "dqs10n"
					( attribute "PN" "19"
						( Origin gPackager )
					)
					( objectStatus "J4G2.19" )
				)
				( pin "dqs10p"
					( attribute "PN" "18"
						( Origin gPackager )
					)
					( objectStatus "J4G2.18" )
				)
				( pin "dqs11n"
					( attribute "PN" "30"
						( Origin gPackager )
					)
					( objectStatus "J4G2.30" )
				)
				( pin "dqs11p"
					( attribute "PN" "29"
						( Origin gPackager )
					)
					( objectStatus "J4G2.29" )
				)
				( pin "dqs12n"
					( attribute "PN" "41"
						( Origin gPackager )
					)
					( objectStatus "J4G2.41" )
				)
				( pin "dqs12p"
					( attribute "PN" "40"
						( Origin gPackager )
					)
					( objectStatus "J4G2.40" )
				)
				( pin "dqs13n"
					( attribute "PN" "100"
						( Origin gPackager )
					)
					( objectStatus "J4G2.100" )
				)
				( pin "dqs13p"
					( attribute "PN" "99"
						( Origin gPackager )
					)
					( objectStatus "J4G2.99" )
				)
				( pin "dqs14n"
					( attribute "PN" "111"
						( Origin gPackager )
					)
					( objectStatus "J4G2.111" )
				)
				( pin "dqs14p"
					( attribute "PN" "110"
						( Origin gPackager )
					)
					( objectStatus "J4G2.110" )
				)
				( pin "dqs15n"
					( attribute "PN" "122"
						( Origin gPackager )
					)
					( objectStatus "J4G2.122" )
				)
				( pin "dqs15p"
					( attribute "PN" "121"
						( Origin gPackager )
					)
					( objectStatus "J4G2.121" )
				)
				( pin "dqs16n"
					( attribute "PN" "133"
						( Origin gPackager )
					)
					( objectStatus "J4G2.133" )
				)
				( pin "dqs16p"
					( attribute "PN" "132"
						( Origin gPackager )
					)
					( objectStatus "J4G2.132" )
				)
				( pin "dqs17n"
					( attribute "PN" "52"
						( Origin gPackager )
					)
					( objectStatus "J4G2.52" )
				)
				( pin "dqs17p"
					( attribute "PN" "51"
						( Origin gPackager )
					)
					( objectStatus "J4G2.51" )
				)
			)
			( gate "@baseboard_fab2_lib.baseboard_fab2(sch_1):page45_i111"
				( attribute "BOM_COST" "MEM"
					( Origin gFrontEnd )
				)
				( attribute "CDS_LIB" "mstr_sconn"
					( Origin gPackager )
				)
				( attribute "CDS_LOCATION" "J4G2"
					( Origin gPackager )
				)
				( attribute "CDS_SEC" "1"
					( Origin gPackager )
				)
				( attribute "LOCATION" "J4G2"
					( Origin gFrontEnd )
				)
				( attribute "MATERIAL" "SCONN"
					( Origin gFrontEnd )
				)
				( attribute "PACK_TYPE" "PIP"
					( Origin gFrontEnd )
				)
				( attribute "PART_NUMBER" "H44441-004"
					( Origin gFrontEnd )
				)
				( attribute "PHYS_PAGE" "45"
					( Origin gFrontEnd )
				)
				( attribute "ROOM" "DDR4_CH_B"
					( Origin gFrontEnd )
				)
				( attribute "ROT" "0"
					( Origin gFrontEnd )
				)
				( attribute "SEC" "1"
					( Origin gFrontEnd )
				)
				( attribute "SEC_TYPE" "PIP"
					( Origin gFrontEnd )
				)
				( attribute "VER" "1"
					( Origin gFrontEnd )
				)
				( attribute "XY" "(-2450,2950)"
					( Origin gFrontEnd )
				)
				( attribute "CHIPS_PART_NAME" "SCONN288_H44441004"
					( Origin gPackager )
				)
				( attribute "CDS_PART_NAME" "SCONN288_H44441004_PIP-SCONN,HA"
					( Origin gPackager )
				)
				( objectStatus "J4G2" )
				( pin "a0"
					( attribute "PN" "79"
						( Origin gPackager )
					)
					( objectStatus "J4G2.79" )
				)
				( pin "a1"
					( attribute "PN" "72"
						( Origin gPackager )
					)
					( objectStatus "J4G2.72" )
				)
				( pin "a2"
					( attribute "PN" "216"
						( Origin gPackager )
					)
					( objectStatus "J4G2.216" )
				)
				( pin "a3"
					( attribute "PN" "71"
						( Origin gPackager )
					)
					( objectStatus "J4G2.71" )
				)
				( pin "a4"
					( attribute "PN" "214"
						( Origin gPackager )
					)
					( objectStatus "J4G2.214" )
				)
				( pin "a5"
					( attribute "PN" "213"
						( Origin gPackager )
					)
					( objectStatus "J4G2.213" )
				)
				( pin "a6"
					( attribute "PN" "69"
						( Origin gPackager )
					)
					( objectStatus "J4G2.69" )
				)
				( pin "a7"
					( attribute "PN" "211"
						( Origin gPackager )
					)
					( objectStatus "J4G2.211" )
				)
				( pin "a8"
					( attribute "PN" "68"
						( Origin gPackager )
					)
					( objectStatus "J4G2.68" )
				)
				( pin "a9"
					( attribute "PN" "66"
						( Origin gPackager )
					)
					( objectStatus "J4G2.66" )
				)
				( pin "a10"
					( attribute "PN" "225"
						( Origin gPackager )
					)
					( objectStatus "J4G2.225" )
				)
				( pin "a11"
					( attribute "PN" "210"
						( Origin gPackager )
					)
					( objectStatus "J4G2.210" )
				)
				( pin "a12"
					( attribute "PN" "65"
						( Origin gPackager )
					)
					( objectStatus "J4G2.65" )
				)
				( pin "a13"
					( attribute "PN" "232"
						( Origin gPackager )
					)
					( objectStatus "J4G2.232" )
				)
				( pin "a14_we_n"
					( attribute "PN" "228"
						( Origin gPackager )
					)
					( objectStatus "J4G2.228" )
				)
				( pin "a15_cas_n"
					( attribute "PN" "86"
						( Origin gPackager )
					)
					( objectStatus "J4G2.86" )
				)
				( pin "a16_ras_n"
					( attribute "PN" "82"
						( Origin gPackager )
					)
					( objectStatus "J4G2.82" )
				)
				( pin "a17"
					( attribute "PN" "234"
						( Origin gPackager )
					)
					( objectStatus "J4G2.234" )
				)
				( pin "act_n"
					( attribute "PN" "62"
						( Origin gPackager )
					)
					( objectStatus "J4G2.62" )
				)
				( pin "alert_n"
					( attribute "PN" "208"
						( Origin gPackager )
					)
					( objectStatus "J4G2.208" )
				)
				( pin "ba(0)"
					( attribute "PN" "81"
						( Origin gPackager )
					)
					( objectStatus "J4G2.81" )
				)
				( pin "ba(1)"
					( attribute "PN" "224"
						( Origin gPackager )
					)
					( objectStatus "J4G2.224" )
				)
				( pin "bg(0)"
					( attribute "PN" "63"
						( Origin gPackager )
					)
					( objectStatus "J4G2.63" )
				)
				( pin "bg(1)"
					( attribute "PN" "207"
						( Origin gPackager )
					)
					( objectStatus "J4G2.207" )
				)
				( pin "c(2)"
					( attribute "PN" "235"
						( Origin gPackager )
					)
					( objectStatus "J4G2.235" )
				)
				( pin "cb(0)"
					( attribute "PN" "49"
						( Origin gPackager )
					)
					( objectStatus "J4G2.49" )
				)
				( pin "cb(1)"
					( attribute "PN" "194"
						( Origin gPackager )
					)
					( objectStatus "J4G2.194" )
				)
				( pin "cb(2)"
					( attribute "PN" "56"
						( Origin gPackager )
					)
					( objectStatus "J4G2.56" )
				)
				( pin "cb(3)"
					( attribute "PN" "201"
						( Origin gPackager )
					)
					( objectStatus "J4G2.201" )
				)
				( pin "cb(4)"
					( attribute "PN" "47"
						( Origin gPackager )
					)
					( objectStatus "J4G2.47" )
				)
				( pin "cb(5)"
					( attribute "PN" "192"
						( Origin gPackager )
					)
					( objectStatus "J4G2.192" )
				)
				( pin "cb(6)"
					( attribute "PN" "54"
						( Origin gPackager )
					)
					( objectStatus "J4G2.54" )
				)
				( pin "cb(7)"
					( attribute "PN" "199"
						( Origin gPackager )
					)
					( objectStatus "J4G2.199" )
				)
				( pin "ck0n"
					( attribute "PN" "75"
						( Origin gPackager )
					)
					( objectStatus "J4G2.75" )
				)
				( pin "ck0p"
					( attribute "PN" "74"
						( Origin gPackager )
					)
					( objectStatus "J4G2.74" )
				)
				( pin "ck1n"
					( attribute "PN" "219"
						( Origin gPackager )
					)
					( objectStatus "J4G2.219" )
				)
				( pin "ck1p"
					( attribute "PN" "218"
						( Origin gPackager )
					)
					( objectStatus "J4G2.218" )
				)
				( pin "cke(0)"
					( attribute "PN" "60"
						( Origin gPackager )
					)
					( objectStatus "J4G2.60" )
				)
				( pin "cke(1)"
					( attribute "PN" "203"
						( Origin gPackager )
					)
					( objectStatus "J4G2.203" )
				)
				( pin "dq(0)"
					( attribute "PN" "5"
						( Origin gPackager )
					)
					( objectStatus "J4G2.5" )
				)
				( pin "dq(1)"
					( attribute "PN" "150"
						( Origin gPackager )
					)
					( objectStatus "J4G2.150" )
				)
				( pin "dq(2)"
					( attribute "PN" "12"
						( Origin gPackager )
					)
					( objectStatus "J4G2.12" )
				)
				( pin "dq(3)"
					( attribute "PN" "157"
						( Origin gPackager )
					)
					( objectStatus "J4G2.157" )
				)
				( pin "dq(4)"
					( attribute "PN" "3"
						( Origin gPackager )
					)
					( objectStatus "J4G2.3" )
				)
				( pin "dq(5)"
					( attribute "PN" "148"
						( Origin gPackager )
					)
					( objectStatus "J4G2.148" )
				)
				( pin "dq(6)"
					( attribute "PN" "10"
						( Origin gPackager )
					)
					( objectStatus "J4G2.10" )
				)
				( pin "dq(7)"
					( attribute "PN" "155"
						( Origin gPackager )
					)
					( objectStatus "J4G2.155" )
				)
				( pin "dq(8)"
					( attribute "PN" "16"
						( Origin gPackager )
					)
					( objectStatus "J4G2.16" )
				)
				( pin "dq(9)"
					( attribute "PN" "161"
						( Origin gPackager )
					)
					( objectStatus "J4G2.161" )
				)
				( pin "dq(10)"
					( attribute "PN" "23"
						( Origin gPackager )
					)
					( objectStatus "J4G2.23" )
				)
				( pin "dq(11)"
					( attribute "PN" "168"
						( Origin gPackager )
					)
					( objectStatus "J4G2.168" )
				)
				( pin "dq(12)"
					( attribute "PN" "14"
						( Origin gPackager )
					)
					( objectStatus "J4G2.14" )
				)
				( pin "dq(13)"
					( attribute "PN" "159"
						( Origin gPackager )
					)
					( objectStatus "J4G2.159" )
				)
				( pin "dq(14)"
					( attribute "PN" "21"
						( Origin gPackager )
					)
					( objectStatus "J4G2.21" )
				)
				( pin "dq(15)"
					( attribute "PN" "166"
						( Origin gPackager )
					)
					( objectStatus "J4G2.166" )
				)
				( pin "dq(16)"
					( attribute "PN" "27"
						( Origin gPackager )
					)
					( objectStatus "J4G2.27" )
				)
				( pin "dq(17)"
					( attribute "PN" "172"
						( Origin gPackager )
					)
					( objectStatus "J4G2.172" )
				)
				( pin "dq(18)"
					( attribute "PN" "34"
						( Origin gPackager )
					)
					( objectStatus "J4G2.34" )
				)
				( pin "dq(19)"
					( attribute "PN" "179"
						( Origin gPackager )
					)
					( objectStatus "J4G2.179" )
				)
				( pin "dq(20)"
					( attribute "PN" "25"
						( Origin gPackager )
					)
					( objectStatus "J4G2.25" )
				)
				( pin "dq(21)"
					( attribute "PN" "170"
						( Origin gPackager )
					)
					( objectStatus "J4G2.170" )
				)
				( pin "dq(22)"
					( attribute "PN" "32"
						( Origin gPackager )
					)
					( objectStatus "J4G2.32" )
				)
				( pin "dq(23)"
					( attribute "PN" "177"
						( Origin gPackager )
					)
					( objectStatus "J4G2.177" )
				)
				( pin "dq(24)"
					( attribute "PN" "38"
						( Origin gPackager )
					)
					( objectStatus "J4G2.38" )
				)
				( pin "dq(25)"
					( attribute "PN" "183"
						( Origin gPackager )
					)
					( objectStatus "J4G2.183" )
				)
				( pin "dq(26)"
					( attribute "PN" "45"
						( Origin gPackager )
					)
					( objectStatus "J4G2.45" )
				)
				( pin "dq(27)"
					( attribute "PN" "190"
						( Origin gPackager )
					)
					( objectStatus "J4G2.190" )
				)
				( pin "dq(28)"
					( attribute "PN" "36"
						( Origin gPackager )
					)
					( objectStatus "J4G2.36" )
				)
				( pin "dq(29)"
					( attribute "PN" "181"
						( Origin gPackager )
					)
					( objectStatus "J4G2.181" )
				)
				( pin "dq(30)"
					( attribute "PN" "43"
						( Origin gPackager )
					)
					( objectStatus "J4G2.43" )
				)
				( pin "dq(31)"
					( attribute "PN" "188"
						( Origin gPackager )
					)
					( objectStatus "J4G2.188" )
				)
				( pin "dq(32)"
					( attribute "PN" "97"
						( Origin gPackager )
					)
					( objectStatus "J4G2.97" )
				)
				( pin "dq(33)"
					( attribute "PN" "242"
						( Origin gPackager )
					)
					( objectStatus "J4G2.242" )
				)
				( pin "dq(34)"
					( attribute "PN" "104"
						( Origin gPackager )
					)
					( objectStatus "J4G2.104" )
				)
				( pin "dq(35)"
					( attribute "PN" "249"
						( Origin gPackager )
					)
					( objectStatus "J4G2.249" )
				)
				( pin "dq(36)"
					( attribute "PN" "95"
						( Origin gPackager )
					)
					( objectStatus "J4G2.95" )
				)
				( pin "dq(37)"
					( attribute "PN" "240"
						( Origin gPackager )
					)
					( objectStatus "J4G2.240" )
				)
				( pin "dq(38)"
					( attribute "PN" "102"
						( Origin gPackager )
					)
					( objectStatus "J4G2.102" )
				)
				( pin "dq(39)"
					( attribute "PN" "247"
						( Origin gPackager )
					)
					( objectStatus "J4G2.247" )
				)
				( pin "dq(40)"
					( attribute "PN" "108"
						( Origin gPackager )
					)
					( objectStatus "J4G2.108" )
				)
				( pin "dq(41)"
					( attribute "PN" "253"
						( Origin gPackager )
					)
					( objectStatus "J4G2.253" )
				)
				( pin "dq(42)"
					( attribute "PN" "115"
						( Origin gPackager )
					)
					( objectStatus "J4G2.115" )
				)
				( pin "dq(43)"
					( attribute "PN" "260"
						( Origin gPackager )
					)
					( objectStatus "J4G2.260" )
				)
				( pin "dq(44)"
					( attribute "PN" "106"
						( Origin gPackager )
					)
					( objectStatus "J4G2.106" )
				)
				( pin "dq(45)"
					( attribute "PN" "251"
						( Origin gPackager )
					)
					( objectStatus "J4G2.251" )
				)
				( pin "dq(46)"
					( attribute "PN" "113"
						( Origin gPackager )
					)
					( objectStatus "J4G2.113" )
				)
				( pin "dq(47)"
					( attribute "PN" "258"
						( Origin gPackager )
					)
					( objectStatus "J4G2.258" )
				)
				( pin "dq(48)"
					( attribute "PN" "119"
						( Origin gPackager )
					)
					( objectStatus "J4G2.119" )
				)
				( pin "dq(49)"
					( attribute "PN" "264"
						( Origin gPackager )
					)
					( objectStatus "J4G2.264" )
				)
				( pin "dq(50)"
					( attribute "PN" "126"
						( Origin gPackager )
					)
					( objectStatus "J4G2.126" )
				)
				( pin "dq(51)"
					( attribute "PN" "271"
						( Origin gPackager )
					)
					( objectStatus "J4G2.271" )
				)
				( pin "dq(52)"
					( attribute "PN" "117"
						( Origin gPackager )
					)
					( objectStatus "J4G2.117" )
				)
				( pin "dq(53)"
					( attribute "PN" "262"
						( Origin gPackager )
					)
					( objectStatus "J4G2.262" )
				)
				( pin "dq(54)"
					( attribute "PN" "124"
						( Origin gPackager )
					)
					( objectStatus "J4G2.124" )
				)
				( pin "dq(55)"
					( attribute "PN" "269"
						( Origin gPackager )
					)
					( objectStatus "J4G2.269" )
				)
				( pin "dq(56)"
					( attribute "PN" "130"
						( Origin gPackager )
					)
					( objectStatus "J4G2.130" )
				)
				( pin "dq(57)"
					( attribute "PN" "275"
						( Origin gPackager )
					)
					( objectStatus "J4G2.275" )
				)
				( pin "dq(58)"
					( attribute "PN" "137"
						( Origin gPackager )
					)
					( objectStatus "J4G2.137" )
				)
				( pin "dq(59)"
					( attribute "PN" "282"
						( Origin gPackager )
					)
					( objectStatus "J4G2.282" )
				)
				( pin "dq(60)"
					( attribute "PN" "128"
						( Origin gPackager )
					)
					( objectStatus "J4G2.128" )
				)
				( pin "dq(61)"
					( attribute "PN" "273"
						( Origin gPackager )
					)
					( objectStatus "J4G2.273" )
				)
				( pin "dq(62)"
					( attribute "PN" "135"
						( Origin gPackager )
					)
					( objectStatus "J4G2.135" )
				)
				( pin "dq(63)"
					( attribute "PN" "280"
						( Origin gPackager )
					)
					( objectStatus "J4G2.280" )
				)
				( pin "event_n"
					( attribute "PN" "78"
						( Origin gPackager )
					)
					( objectStatus "J4G2.78" )
				)
				( pin "odt(0)"
					( attribute "PN" "87"
						( Origin gPackager )
					)
					( objectStatus "J4G2.87" )
				)
				( pin "odt(1)"
					( attribute "PN" "91"
						( Origin gPackager )
					)
					( objectStatus "J4G2.91" )
				)
				( pin "par"
					( attribute "PN" "222"
						( Origin gPackager )
					)
					( objectStatus "J4G2.222" )
				)
				( pin "reset_n"
					( attribute "PN" "58"
						( Origin gPackager )
					)
					( objectStatus "J4G2.58" )
				)
				( pin "rfu(0)"
					( attribute "PN" "205"
						( Origin gPackager )
					)
					( objectStatus "J4G2.205" )
				)
				( pin "rfu(1)"
					( attribute "PN" "227"
						( Origin gPackager )
					)
					( objectStatus "J4G2.227" )
				)
				( pin "rfu(2)"
					( attribute "PN" "144"
						( Origin gPackager )
					)
					( objectStatus "J4G2.144" )
				)
				( pin "s0_n"
					( attribute "PN" "84"
						( Origin gPackager )
					)
					( objectStatus "J4G2.84" )
				)
				( pin "s1_n"
					( attribute "PN" "89"
						( Origin gPackager )
					)
					( objectStatus "J4G2.89" )
				)
				( pin "s2_n_c(0)"
					( attribute "PN" "93"
						( Origin gPackager )
					)
					( objectStatus "J4G2.93" )
				)
				( pin "s3_n_c(1)"
					( attribute "PN" "237"
						( Origin gPackager )
					)
					( objectStatus "J4G2.237" )
				)
				( pin "sa(0)"
					( attribute "PN" "139"
						( Origin gPackager )
					)
					( objectStatus "J4G2.139" )
				)
				( pin "sa(1)"
					( attribute "PN" "140"
						( Origin gPackager )
					)
					( objectStatus "J4G2.140" )
				)
				( pin "sa(2)"
					( attribute "PN" "238"
						( Origin gPackager )
					)
					( objectStatus "J4G2.238" )
				)
				( pin "save_n_nc"
					( attribute "PN" "230"
						( Origin gPackager )
					)
					( objectStatus "J4G2.230" )
				)
				( pin "scl"
					( attribute "PN" "141"
						( Origin gPackager )
					)
					( objectStatus "J4G2.141" )
				)
				( pin "sda"
					( attribute "PN" "285"
						( Origin gPackager )
					)
					( objectStatus "J4G2.285" )
				)
				( pin "vddspd"
					( attribute "PN" "284"
						( Origin gPackager )
					)
					( objectStatus "J4G2.284" )
				)
				( pin "vrefca"
					( attribute "PN" "146"
						( Origin gPackager )
					)
					( objectStatus "J4G2.146" )
				)
			)
			( gate "@baseboard_fab2_lib.baseboard_fab2(sch_1):page45_i169"
				( attribute "BOM_COST" "MEM"
					( Origin gFrontEnd )
				)
				( attribute "CDS_LIB" "mstr_sconn"
					( Origin gPackager )
				)
				( attribute "CDS_LOCATION" "J4G2"
					( Origin gPackager )
				)
				( attribute "CDS_SEC" "4"
					( Origin gPackager )
				)
				( attribute "LOCATION" "J4G2"
					( Origin gFrontEnd )
				)
				( attribute "MATERIAL" "SCONN"
					( Origin gFrontEnd )
				)
				( attribute "PACK_TYPE" "PIP"
					( Origin gFrontEnd )
				)
				( attribute "PART_NUMBER" "H44441-004"
					( Origin gFrontEnd )
				)
				( attribute "PHYS_PAGE" "45"
					( Origin gFrontEnd )
				)
				( attribute "ROOM" "DDR4_CH_B"
					( Origin gFrontEnd )
				)
				( attribute "ROT" "0"
					( Origin gFrontEnd )
				)
				( attribute "SEC" "4"
					( Origin gFrontEnd )
				)
				( attribute "SEC_TYPE" "PIP"
					( Origin gFrontEnd )
				)
				( attribute "VER" "4"
					( Origin gFrontEnd )
				)
				( attribute "XY" "(50,2000)"
					( Origin gFrontEnd )
				)
				( attribute "CHIPS_PART_NAME" "SCONN288_H44441004"
					( Origin gPackager )
				)
				( attribute "CDS_PART_NAME" "SCONN288_H44441004_PIP-SCONN,HA"
					( Origin gPackager )
				)
				( objectStatus "J4G2" )
				( pin "\12v\(0)"
					( attribute "PN" "145"
						( Origin gPackager )
					)
					( objectStatus "J4G2.145" )
				)
				( pin "\12v\(1)"
					( attribute "PN" "1"
						( Origin gPackager )
					)
					( objectStatus "J4G2.1" )
				)
				( pin "vdd(0)"
					( attribute "PN" "236"
						( Origin gPackager )
					)
					( objectStatus "J4G2.236" )
				)
				( pin "vdd(1)"
					( attribute "PN" "233"
						( Origin gPackager )
					)
					( objectStatus "J4G2.233" )
				)
				( pin "vdd(2)"
					( attribute "PN" "231"
						( Origin gPackager )
					)
					( objectStatus "J4G2.231" )
				)
				( pin "vdd(3)"
					( attribute "PN" "229"
						( Origin gPackager )
					)
					( objectStatus "J4G2.229" )
				)
				( pin "vdd(4)"
					( attribute "PN" "226"
						( Origin gPackager )
					)
					( objectStatus "J4G2.226" )
				)
				( pin "vdd(5)"
					( attribute "PN" "223"
						( Origin gPackager )
					)
					( objectStatus "J4G2.223" )
				)
				( pin "vdd(6)"
					( attribute "PN" "220"
						( Origin gPackager )
					)
					( objectStatus "J4G2.220" )
				)
				( pin "vdd(7)"
					( attribute "PN" "217"
						( Origin gPackager )
					)
					( objectStatus "J4G2.217" )
				)
				( pin "vdd(8)"
					( attribute "PN" "215"
						( Origin gPackager )
					)
					( objectStatus "J4G2.215" )
				)
				( pin "vdd(9)"
					( attribute "PN" "212"
						( Origin gPackager )
					)
					( objectStatus "J4G2.212" )
				)
				( pin "vdd(10)"
					( attribute "PN" "209"
						( Origin gPackager )
					)
					( objectStatus "J4G2.209" )
				)
				( pin "vdd(11)"
					( attribute "PN" "206"
						( Origin gPackager )
					)
					( objectStatus "J4G2.206" )
				)
				( pin "vdd(12)"
					( attribute "PN" "204"
						( Origin gPackager )
					)
					( objectStatus "J4G2.204" )
				)
				( pin "vdd(13)"
					( attribute "PN" "92"
						( Origin gPackager )
					)
					( objectStatus "J4G2.92" )
				)
				( pin "vdd(14)"
					( attribute "PN" "90"
						( Origin gPackager )
					)
					( objectStatus "J4G2.90" )
				)
				( pin "vdd(15)"
					( attribute "PN" "88"
						( Origin gPackager )
					)
					( objectStatus "J4G2.88" )
				)
				( pin "vdd(16)"
					( attribute "PN" "85"
						( Origin gPackager )
					)
					( objectStatus "J4G2.85" )
				)
				( pin "vdd(17)"
					( attribute "PN" "83"
						( Origin gPackager )
					)
					( objectStatus "J4G2.83" )
				)
				( pin "vdd(18)"
					( attribute "PN" "80"
						( Origin gPackager )
					)
					( objectStatus "J4G2.80" )
				)
				( pin "vdd(19)"
					( attribute "PN" "76"
						( Origin gPackager )
					)
					( objectStatus "J4G2.76" )
				)
				( pin "vdd(20)"
					( attribute "PN" "73"
						( Origin gPackager )
					)
					( objectStatus "J4G2.73" )
				)
				( pin "vdd(21)"
					( attribute "PN" "70"
						( Origin gPackager )
					)
					( objectStatus "J4G2.70" )
				)
				( pin "vdd(22)"
					( attribute "PN" "67"
						( Origin gPackager )
					)
					( objectStatus "J4G2.67" )
				)
				( pin "vdd(23)"
					( attribute "PN" "64"
						( Origin gPackager )
					)
					( objectStatus "J4G2.64" )
				)
				( pin "vdd(24)"
					( attribute "PN" "61"
						( Origin gPackager )
					)
					( objectStatus "J4G2.61" )
				)
				( pin "vdd(25)"
					( attribute "PN" "59"
						( Origin gPackager )
					)
					( objectStatus "J4G2.59" )
				)
				( pin "vpp(0)"
					( attribute "PN" "287"
						( Origin gPackager )
					)
					( objectStatus "J4G2.287" )
				)
				( pin "vpp(1)"
					( attribute "PN" "286"
						( Origin gPackager )
					)
					( objectStatus "J4G2.286" )
				)
				( pin "vpp(2)"
					( attribute "PN" "288"
						( Origin gPackager )
					)
					( objectStatus "J4G2.288" )
				)
				( pin "vpp(3)"
					( attribute "PN" "143"
						( Origin gPackager )
					)
					( objectStatus "J4G2.143" )
				)
				( pin "vpp(4)"
					( attribute "PN" "142"
						( Origin gPackager )
					)
					( objectStatus "J4G2.142" )
				)
				( pin "vtt(0)"
					( attribute "PN" "221"
						( Origin gPackager )
					)
					( objectStatus "J4G2.221" )
				)
				( pin "vtt(1)"
					( attribute "PN" "77"
						( Origin gPackager )
					)
					( objectStatus "J4G2.77" )
				)
			)
			( gate "@baseboard_fab2_lib.baseboard_fab2(sch_1):page45_i179"
				( attribute "BOM_COST" "MEM"
					( Origin gFrontEnd )
				)
				( attribute "CDS_LIB" "dev_discrete"
					( Origin gPackager )
				)
				( attribute "CDS_LOCATION" "C4G3"
					( Origin gPackager )
				)
				( attribute "CDS_SEC" "1"
					( Origin gPackager )
				)
				( attribute "LOCATION" "C4G3"
					( Origin gFrontEnd )
				)
				( attribute "MATERIAL" "X7R"
					( Origin gFrontEnd )
				)
				( attribute "PACK_TYPE" "0402V"
					( Origin gFrontEnd )
				)
				( attribute "PART_NUMBER" "A36096-045"
					( Origin gFrontEnd )
				)
				( attribute "PHYS_PAGE" "45"
					( Origin gFrontEnd )
				)
				( attribute "ROOM" "DDR4_CH_A"
					( Origin gFrontEnd )
				)
				( attribute "ROT" "2"
					( Origin gFrontEnd )
				)
				( attribute "SEC" "1"
					( Origin gPackager )
				)
				( attribute "TOLERANCE" "10%"
					( Origin gFrontEnd )
				)
				( attribute "VALUE" "0.01UF"
					( Origin gFrontEnd )
				)
				( attribute "VER" "1"
					( Origin gFrontEnd )
				)
				( attribute "VOLTAGE" "25V"
					( Units "uVoltage" "V" 1.000000)
					( Origin gFrontEnd )
				)
				( attribute "XY" "(-4600,1250)"
					( Origin gFrontEnd )
				)
				( attribute "CHIPS_PART_NAME" "CAP_A"
					( Origin gPackager )
				)
				( attribute "CDS_PART_NAME" "CAP_A_0402V-0.01UF,25V,10%,X7RA"
					( Origin gPackager )
				)
				( objectStatus "C4G3" )
				( pin "a"
					( attribute "PN" "1"
						( Origin gPackager )
					)
					( objectStatus "C4G3.1" )
				)
				( pin "b"
					( attribute "PN" "2"
						( Origin gPackager )
					)
					( objectStatus "C4G3.2" )
				)
			)
			( gate "@baseboard_fab2_lib.baseboard_fab2(sch_1):page46_i5"
				( attribute "BOM_COST" "MEM"
					( Origin gFrontEnd )
				)
				( attribute "CDS_LIB" "dev_discrete"
					( Origin gPackager )
				)
				( attribute "CDS_LOCATION" "C6U9"
					( Origin gPackager )
				)
				( attribute "CDS_SEC" "1"
					( Origin gPackager )
				)
				( attribute "LOCATION" "C6U9"
					( Origin gFrontEnd )
				)
				( attribute "MATERIAL" "X7R"
					( Origin gFrontEnd )
				)
				( attribute "PACK_TYPE" "0402V"
					( Origin gFrontEnd )
				)
				( attribute "PART_NUMBER" "A36096-045"
					( Origin gFrontEnd )
				)
				( attribute "PHYS_PAGE" "46"
					( Origin gFrontEnd )
				)
				( attribute "ROOM" "DDR4_CH_A"
					( Origin gFrontEnd )
				)
				( attribute "ROT" "2"
					( Origin gFrontEnd )
				)
				( attribute "SEC" "1"
					( Origin gFrontEnd )
				)
				( attribute "SEC_TYPE" "0402V"
					( Origin gFrontEnd )
				)
				( attribute "TOLERANCE" "10%"
					( Origin gFrontEnd )
				)
				( attribute "VALUE" "0.01UF"
					( Origin gFrontEnd )
				)
				( attribute "VER" "1"
					( Origin gFrontEnd )
				)
				( attribute "VOLTAGE" "25V"
					( Units "uVoltage" "V" 1.000000)
					( Origin gFrontEnd )
				)
				( attribute "XY" "(-2975,900)"
					( Origin gFrontEnd )
				)
				( attribute "CHIPS_PART_NAME" "CAP_A"
					( Origin gPackager )
				)
				( attribute "CDS_PART_NAME" "CAP_A_0402V-0.01UF,25V,10%,X7RA"
					( Origin gPackager )
				)
				( objectStatus "C6U9" )
				( pin "a"
					( attribute "PN" "1"
						( Origin gPackager )
					)
					( objectStatus "C6U9.1" )
				)
				( pin "b"
					( attribute "PN" "2"
						( Origin gPackager )
					)
					( objectStatus "C6U9.2" )
				)
			)
			( gate "@baseboard_fab2_lib.baseboard_fab2(sch_1):page46_i14"
				( attribute "BOM_COST" "MEM"
					( Origin gFrontEnd )
				)
				( attribute "CDS_LIB" "mstr_sconn"
					( Origin gPackager )
				)
				( attribute "CDS_LOCATION" "J6U1"
					( Origin gPackager )
				)
				( attribute "CDS_SEC" "1"
					( Origin gPackager )
				)
				( attribute "LOCATION" "J6U1"
					( Origin gFrontEnd )
				)
				( attribute "MATERIAL" "SCONN"
					( Origin gFrontEnd )
				)
				( attribute "PACK_TYPE" "PIP"
					( Origin gFrontEnd )
				)
				( attribute "PART_NUMBER" "H44441-003"
					( Origin gFrontEnd )
				)
				( attribute "PHYS_PAGE" "46"
					( Origin gFrontEnd )
				)
				( attribute "ROOM" "DDR4_CH_B"
					( Origin gFrontEnd )
				)
				( attribute "ROT" "0"
					( Origin gFrontEnd )
				)
				( attribute "SEC" "1"
					( Origin gFrontEnd )
				)
				( attribute "SEC_TYPE" "PIP"
					( Origin gFrontEnd )
				)
				( attribute "VER" "1"
					( Origin gFrontEnd )
				)
				( attribute "XY" "(-825,2600)"
					( Origin gFrontEnd )
				)
				( attribute "CHIPS_PART_NAME" "SCONN288_H44441003"
					( Origin gPackager )
				)
				( attribute "CDS_PART_NAME" "SCONN288_H44441003_PIP-SCONN,HA"
					( Origin gPackager )
				)
				( objectStatus "J6U1" )
				( pin "a0"
					( attribute "PN" "79"
						( Origin gPackager )
					)
					( objectStatus "J6U1.79" )
				)
				( pin "a1"
					( attribute "PN" "72"
						( Origin gPackager )
					)
					( objectStatus "J6U1.72" )
				)
				( pin "a2"
					( attribute "PN" "216"
						( Origin gPackager )
					)
					( objectStatus "J6U1.216" )
				)
				( pin "a3"
					( attribute "PN" "71"
						( Origin gPackager )
					)
					( objectStatus "J6U1.71" )
				)
				( pin "a4"
					( attribute "PN" "214"
						( Origin gPackager )
					)
					( objectStatus "J6U1.214" )
				)
				( pin "a5"
					( attribute "PN" "213"
						( Origin gPackager )
					)
					( objectStatus "J6U1.213" )
				)
				( pin "a6"
					( attribute "PN" "69"
						( Origin gPackager )
					)
					( objectStatus "J6U1.69" )
				)
				( pin "a7"
					( attribute "PN" "211"
						( Origin gPackager )
					)
					( objectStatus "J6U1.211" )
				)
				( pin "a8"
					( attribute "PN" "68"
						( Origin gPackager )
					)
					( objectStatus "J6U1.68" )
				)
				( pin "a9"
					( attribute "PN" "66"
						( Origin gPackager )
					)
					( objectStatus "J6U1.66" )
				)
				( pin "a10"
					( attribute "PN" "225"
						( Origin gPackager )
					)
					( objectStatus "J6U1.225" )
				)
				( pin "a11"
					( attribute "PN" "210"
						( Origin gPackager )
					)
					( objectStatus "J6U1.210" )
				)
				( pin "a12"
					( attribute "PN" "65"
						( Origin gPackager )
					)
					( objectStatus "J6U1.65" )
				)
				( pin "a13"
					( attribute "PN" "232"
						( Origin gPackager )
					)
					( objectStatus "J6U1.232" )
				)
				( pin "a14_we_n"
					( attribute "PN" "228"
						( Origin gPackager )
					)
					( objectStatus "J6U1.228" )
				)
				( pin "a15_cas_n"
					( attribute "PN" "86"
						( Origin gPackager )
					)
					( objectStatus "J6U1.86" )
				)
				( pin "a16_ras_n"
					( attribute "PN" "82"
						( Origin gPackager )
					)
					( objectStatus "J6U1.82" )
				)
				( pin "a17"
					( attribute "PN" "234"
						( Origin gPackager )
					)
					( objectStatus "J6U1.234" )
				)
				( pin "act_n"
					( attribute "PN" "62"
						( Origin gPackager )
					)
					( objectStatus "J6U1.62" )
				)
				( pin "alert_n"
					( attribute "PN" "208"
						( Origin gPackager )
					)
					( objectStatus "J6U1.208" )
				)
				( pin "ba(0)"
					( attribute "PN" "81"
						( Origin gPackager )
					)
					( objectStatus "J6U1.81" )
				)
				( pin "ba(1)"
					( attribute "PN" "224"
						( Origin gPackager )
					)
					( objectStatus "J6U1.224" )
				)
				( pin "bg(0)"
					( attribute "PN" "63"
						( Origin gPackager )
					)
					( objectStatus "J6U1.63" )
				)
				( pin "bg(1)"
					( attribute "PN" "207"
						( Origin gPackager )
					)
					( objectStatus "J6U1.207" )
				)
				( pin "c(2)"
					( attribute "PN" "235"
						( Origin gPackager )
					)
					( objectStatus "J6U1.235" )
				)
				( pin "cb(0)"
					( attribute "PN" "49"
						( Origin gPackager )
					)
					( objectStatus "J6U1.49" )
				)
				( pin "cb(1)"
					( attribute "PN" "194"
						( Origin gPackager )
					)
					( objectStatus "J6U1.194" )
				)
				( pin "cb(2)"
					( attribute "PN" "56"
						( Origin gPackager )
					)
					( objectStatus "J6U1.56" )
				)
				( pin "cb(3)"
					( attribute "PN" "201"
						( Origin gPackager )
					)
					( objectStatus "J6U1.201" )
				)
				( pin "cb(4)"
					( attribute "PN" "47"
						( Origin gPackager )
					)
					( objectStatus "J6U1.47" )
				)
				( pin "cb(5)"
					( attribute "PN" "192"
						( Origin gPackager )
					)
					( objectStatus "J6U1.192" )
				)
				( pin "cb(6)"
					( attribute "PN" "54"
						( Origin gPackager )
					)
					( objectStatus "J6U1.54" )
				)
				( pin "cb(7)"
					( attribute "PN" "199"
						( Origin gPackager )
					)
					( objectStatus "J6U1.199" )
				)
				( pin "ck0n"
					( attribute "PN" "75"
						( Origin gPackager )
					)
					( objectStatus "J6U1.75" )
				)
				( pin "ck0p"
					( attribute "PN" "74"
						( Origin gPackager )
					)
					( objectStatus "J6U1.74" )
				)
				( pin "ck1n"
					( attribute "PN" "219"
						( Origin gPackager )
					)
					( objectStatus "J6U1.219" )
				)
				( pin "ck1p"
					( attribute "PN" "218"
						( Origin gPackager )
					)
					( objectStatus "J6U1.218" )
				)
				( pin "cke(0)"
					( attribute "PN" "60"
						( Origin gPackager )
					)
					( objectStatus "J6U1.60" )
				)
				( pin "cke(1)"
					( attribute "PN" "203"
						( Origin gPackager )
					)
					( objectStatus "J6U1.203" )
				)
				( pin "dq(0)"
					( attribute "PN" "5"
						( Origin gPackager )
					)
					( objectStatus "J6U1.5" )
				)
				( pin "dq(1)"
					( attribute "PN" "150"
						( Origin gPackager )
					)
					( objectStatus "J6U1.150" )
				)
				( pin "dq(2)"
					( attribute "PN" "12"
						( Origin gPackager )
					)
					( objectStatus "J6U1.12" )
				)
				( pin "dq(3)"
					( attribute "PN" "157"
						( Origin gPackager )
					)
					( objectStatus "J6U1.157" )
				)
				( pin "dq(4)"
					( attribute "PN" "3"
						( Origin gPackager )
					)
					( objectStatus "J6U1.3" )
				)
				( pin "dq(5)"
					( attribute "PN" "148"
						( Origin gPackager )
					)
					( objectStatus "J6U1.148" )
				)
				( pin "dq(6)"
					( attribute "PN" "10"
						( Origin gPackager )
					)
					( objectStatus "J6U1.10" )
				)
				( pin "dq(7)"
					( attribute "PN" "155"
						( Origin gPackager )
					)
					( objectStatus "J6U1.155" )
				)
				( pin "dq(8)"
					( attribute "PN" "16"
						( Origin gPackager )
					)
					( objectStatus "J6U1.16" )
				)
				( pin "dq(9)"
					( attribute "PN" "161"
						( Origin gPackager )
					)
					( objectStatus "J6U1.161" )
				)
				( pin "dq(10)"
					( attribute "PN" "23"
						( Origin gPackager )
					)
					( objectStatus "J6U1.23" )
				)
				( pin "dq(11)"
					( attribute "PN" "168"
						( Origin gPackager )
					)
					( objectStatus "J6U1.168" )
				)
				( pin "dq(12)"
					( attribute "PN" "14"
						( Origin gPackager )
					)
					( objectStatus "J6U1.14" )
				)
				( pin "dq(13)"
					( attribute "PN" "159"
						( Origin gPackager )
					)
					( objectStatus "J6U1.159" )
				)
				( pin "dq(14)"
					( attribute "PN" "21"
						( Origin gPackager )
					)
					( objectStatus "J6U1.21" )
				)
				( pin "dq(15)"
					( attribute "PN" "166"
						( Origin gPackager )
					)
					( objectStatus "J6U1.166" )
				)
				( pin "dq(16)"
					( attribute "PN" "27"
						( Origin gPackager )
					)
					( objectStatus "J6U1.27" )
				)
				( pin "dq(17)"
					( attribute "PN" "172"
						( Origin gPackager )
					)
					( objectStatus "J6U1.172" )
				)
				( pin "dq(18)"
					( attribute "PN" "34"
						( Origin gPackager )
					)
					( objectStatus "J6U1.34" )
				)
				( pin "dq(19)"
					( attribute "PN" "179"
						( Origin gPackager )
					)
					( objectStatus "J6U1.179" )
				)
				( pin "dq(20)"
					( attribute "PN" "25"
						( Origin gPackager )
					)
					( objectStatus "J6U1.25" )
				)
				( pin "dq(21)"
					( attribute "PN" "170"
						( Origin gPackager )
					)
					( objectStatus "J6U1.170" )
				)
				( pin "dq(22)"
					( attribute "PN" "32"
						( Origin gPackager )
					)
					( objectStatus "J6U1.32" )
				)
				( pin "dq(23)"
					( attribute "PN" "177"
						( Origin gPackager )
					)
					( objectStatus "J6U1.177" )
				)
				( pin "dq(24)"
					( attribute "PN" "38"
						( Origin gPackager )
					)
					( objectStatus "J6U1.38" )
				)
				( pin "dq(25)"
					( attribute "PN" "183"
						( Origin gPackager )
					)
					( objectStatus "J6U1.183" )
				)
				( pin "dq(26)"
					( attribute "PN" "45"
						( Origin gPackager )
					)
					( objectStatus "J6U1.45" )
				)
				( pin "dq(27)"
					( attribute "PN" "190"
						( Origin gPackager )
					)
					( objectStatus "J6U1.190" )
				)
				( pin "dq(28)"
					( attribute "PN" "36"
						( Origin gPackager )
					)
					( objectStatus "J6U1.36" )
				)
				( pin "dq(29)"
					( attribute "PN" "181"
						( Origin gPackager )
					)
					( objectStatus "J6U1.181" )
				)
				( pin "dq(30)"
					( attribute "PN" "43"
						( Origin gPackager )
					)
					( objectStatus "J6U1.43" )
				)
				( pin "dq(31)"
					( attribute "PN" "188"
						( Origin gPackager )
					)
					( objectStatus "J6U1.188" )
				)
				( pin "dq(32)"
					( attribute "PN" "97"
						( Origin gPackager )
					)
					( objectStatus "J6U1.97" )
				)
				( pin "dq(33)"
					( attribute "PN" "242"
						( Origin gPackager )
					)
					( objectStatus "J6U1.242" )
				)
				( pin "dq(34)"
					( attribute "PN" "104"
						( Origin gPackager )
					)
					( objectStatus "J6U1.104" )
				)
				( pin "dq(35)"
					( attribute "PN" "249"
						( Origin gPackager )
					)
					( objectStatus "J6U1.249" )
				)
				( pin "dq(36)"
					( attribute "PN" "95"
						( Origin gPackager )
					)
					( objectStatus "J6U1.95" )
				)
				( pin "dq(37)"
					( attribute "PN" "240"
						( Origin gPackager )
					)
					( objectStatus "J6U1.240" )
				)
				( pin "dq(38)"
					( attribute "PN" "102"
						( Origin gPackager )
					)
					( objectStatus "J6U1.102" )
				)
				( pin "dq(39)"
					( attribute "PN" "247"
						( Origin gPackager )
					)
					( objectStatus "J6U1.247" )
				)
				( pin "dq(40)"
					( attribute "PN" "108"
						( Origin gPackager )
					)
					( objectStatus "J6U1.108" )
				)
				( pin "dq(41)"
					( attribute "PN" "253"
						( Origin gPackager )
					)
					( objectStatus "J6U1.253" )
				)
				( pin "dq(42)"
					( attribute "PN" "115"
						( Origin gPackager )
					)
					( objectStatus "J6U1.115" )
				)
				( pin "dq(43)"
					( attribute "PN" "260"
						( Origin gPackager )
					)
					( objectStatus "J6U1.260" )
				)
				( pin "dq(44)"
					( attribute "PN" "106"
						( Origin gPackager )
					)
					( objectStatus "J6U1.106" )
				)
				( pin "dq(45)"
					( attribute "PN" "251"
						( Origin gPackager )
					)
					( objectStatus "J6U1.251" )
				)
				( pin "dq(46)"
					( attribute "PN" "113"
						( Origin gPackager )
					)
					( objectStatus "J6U1.113" )
				)
				( pin "dq(47)"
					( attribute "PN" "258"
						( Origin gPackager )
					)
					( objectStatus "J6U1.258" )
				)
				( pin "dq(48)"
					( attribute "PN" "119"
						( Origin gPackager )
					)
					( objectStatus "J6U1.119" )
				)
				( pin "dq(49)"
					( attribute "PN" "264"
						( Origin gPackager )
					)
					( objectStatus "J6U1.264" )
				)
				( pin "dq(50)"
					( attribute "PN" "126"
						( Origin gPackager )
					)
					( objectStatus "J6U1.126" )
				)
				( pin "dq(51)"
					( attribute "PN" "271"
						( Origin gPackager )
					)
					( objectStatus "J6U1.271" )
				)
				( pin "dq(52)"
					( attribute "PN" "117"
						( Origin gPackager )
					)
					( objectStatus "J6U1.117" )
				)
				( pin "dq(53)"
					( attribute "PN" "262"
						( Origin gPackager )
					)
					( objectStatus "J6U1.262" )
				)
				( pin "dq(54)"
					( attribute "PN" "124"
						( Origin gPackager )
					)
					( objectStatus "J6U1.124" )
				)
				( pin "dq(55)"
					( attribute "PN" "269"
						( Origin gPackager )
					)
					( objectStatus "J6U1.269" )
				)
				( pin "dq(56)"
					( attribute "PN" "130"
						( Origin gPackager )
					)
					( objectStatus "J6U1.130" )
				)
				( pin "dq(57)"
					( attribute "PN" "275"
						( Origin gPackager )
					)
					( objectStatus "J6U1.275" )
				)
				( pin "dq(58)"
					( attribute "PN" "137"
						( Origin gPackager )
					)
					( objectStatus "J6U1.137" )
				)
				( pin "dq(59)"
					( attribute "PN" "282"
						( Origin gPackager )
					)
					( objectStatus "J6U1.282" )
				)
				( pin "dq(60)"
					( attribute "PN" "128"
						( Origin gPackager )
					)
					( objectStatus "J6U1.128" )
				)
				( pin "dq(61)"
					( attribute "PN" "273"
						( Origin gPackager )
					)
					( objectStatus "J6U1.273" )
				)
				( pin "dq(62)"
					( attribute "PN" "135"
						( Origin gPackager )
					)
					( objectStatus "J6U1.135" )
				)
				( pin "dq(63)"
					( attribute "PN" "280"
						( Origin gPackager )
					)
					( objectStatus "J6U1.280" )
				)
				( pin "event_n"
					( attribute "PN" "78"
						( Origin gPackager )
					)
					( objectStatus "J6U1.78" )
				)
				( pin "odt(0)"
					( attribute "PN" "87"
						( Origin gPackager )
					)
					( objectStatus "J6U1.87" )
				)
				( pin "odt(1)"
					( attribute "PN" "91"
						( Origin gPackager )
					)
					( objectStatus "J6U1.91" )
				)
				( pin "par"
					( attribute "PN" "222"
						( Origin gPackager )
					)
					( objectStatus "J6U1.222" )
				)
				( pin "reset_n"
					( attribute "PN" "58"
						( Origin gPackager )
					)
					( objectStatus "J6U1.58" )
				)
				( pin "rfu(0)"
					( attribute "PN" "205"
						( Origin gPackager )
					)
					( objectStatus "J6U1.205" )
				)
				( pin "rfu(1)"
					( attribute "PN" "227"
						( Origin gPackager )
					)
					( objectStatus "J6U1.227" )
				)
				( pin "rfu(2)"
					( attribute "PN" "144"
						( Origin gPackager )
					)
					( objectStatus "J6U1.144" )
				)
				( pin "s0_n"
					( attribute "PN" "84"
						( Origin gPackager )
					)
					( objectStatus "J6U1.84" )
				)
				( pin "s1_n"
					( attribute "PN" "89"
						( Origin gPackager )
					)
					( objectStatus "J6U1.89" )
				)
				( pin "s2_n_c(0)"
					( attribute "PN" "93"
						( Origin gPackager )
					)
					( objectStatus "J6U1.93" )
				)
				( pin "s3_n_c(1)"
					( attribute "PN" "237"
						( Origin gPackager )
					)
					( objectStatus "J6U1.237" )
				)
				( pin "sa(0)"
					( attribute "PN" "139"
						( Origin gPackager )
					)
					( objectStatus "J6U1.139" )
				)
				( pin "sa(1)"
					( attribute "PN" "140"
						( Origin gPackager )
					)
					( objectStatus "J6U1.140" )
				)
				( pin "sa(2)"
					( attribute "PN" "238"
						( Origin gPackager )
					)
					( objectStatus "J6U1.238" )
				)
				( pin "save_n_nc"
					( attribute "PN" "230"
						( Origin gPackager )
					)
					( objectStatus "J6U1.230" )
				)
				( pin "scl"
					( attribute "PN" "141"
						( Origin gPackager )
					)
					( objectStatus "J6U1.141" )
				)
				( pin "sda"
					( attribute "PN" "285"
						( Origin gPackager )
					)
					( objectStatus "J6U1.285" )
				)
				( pin "vddspd"
					( attribute "PN" "284"
						( Origin gPackager )
					)
					( objectStatus "J6U1.284" )
				)
				( pin "vrefca"
					( attribute "PN" "146"
						( Origin gPackager )
					)
					( objectStatus "J6U1.146" )
				)
			)
			( gate "@baseboard_fab2_lib.baseboard_fab2(sch_1):page46_i67"
				( attribute "BOM_COST" "MEM"
					( Origin gFrontEnd )
				)
				( attribute "CDS_LIB" "mstr_sconn"
					( Origin gPackager )
				)
				( attribute "CDS_LOCATION" "J6U1"
					( Origin gPackager )
				)
				( attribute "CDS_SEC" "4"
					( Origin gPackager )
				)
				( attribute "LOCATION" "J6U1"
					( Origin gFrontEnd )
				)
				( attribute "MATERIAL" "SCONN"
					( Origin gFrontEnd )
				)
				( attribute "PACK_TYPE" "PIP"
					( Origin gFrontEnd )
				)
				( attribute "PART_NUMBER" "H44441-003"
					( Origin gFrontEnd )
				)
				( attribute "PHYS_PAGE" "46"
					( Origin gFrontEnd )
				)
				( attribute "ROOM" "DDR4_CH_B"
					( Origin gFrontEnd )
				)
				( attribute "ROT" "0"
					( Origin gFrontEnd )
				)
				( attribute "SEC" "4"
					( Origin gFrontEnd )
				)
				( attribute "SEC_TYPE" "PIP"
					( Origin gFrontEnd )
				)
				( attribute "VER" "4"
					( Origin gFrontEnd )
				)
				( attribute "XY" "(1675,1650)"
					( Origin gFrontEnd )
				)
				( attribute "CHIPS_PART_NAME" "SCONN288_H44441003"
					( Origin gPackager )
				)
				( attribute "CDS_PART_NAME" "SCONN288_H44441003_PIP-SCONN,HA"
					( Origin gPackager )
				)
				( objectStatus "J6U1" )
				( pin "\12v\(0)"
					( attribute "PN" "145"
						( Origin gPackager )
					)
					( objectStatus "J6U1.145" )
				)
				( pin "\12v\(1)"
					( attribute "PN" "1"
						( Origin gPackager )
					)
					( objectStatus "J6U1.1" )
				)
				( pin "vdd(0)"
					( attribute "PN" "236"
						( Origin gPackager )
					)
					( objectStatus "J6U1.236" )
				)
				( pin "vdd(1)"
					( attribute "PN" "233"
						( Origin gPackager )
					)
					( objectStatus "J6U1.233" )
				)
				( pin "vdd(2)"
					( attribute "PN" "231"
						( Origin gPackager )
					)
					( objectStatus "J6U1.231" )
				)
				( pin "vdd(3)"
					( attribute "PN" "229"
						( Origin gPackager )
					)
					( objectStatus "J6U1.229" )
				)
				( pin "vdd(4)"
					( attribute "PN" "226"
						( Origin gPackager )
					)
					( objectStatus "J6U1.226" )
				)
				( pin "vdd(5)"
					( attribute "PN" "223"
						( Origin gPackager )
					)
					( objectStatus "J6U1.223" )
				)
				( pin "vdd(6)"
					( attribute "PN" "220"
						( Origin gPackager )
					)
					( objectStatus "J6U1.220" )
				)
				( pin "vdd(7)"
					( attribute "PN" "217"
						( Origin gPackager )
					)
					( objectStatus "J6U1.217" )
				)
				( pin "vdd(8)"
					( attribute "PN" "215"
						( Origin gPackager )
					)
					( objectStatus "J6U1.215" )
				)
				( pin "vdd(9)"
					( attribute "PN" "212"
						( Origin gPackager )
					)
					( objectStatus "J6U1.212" )
				)
				( pin "vdd(10)"
					( attribute "PN" "209"
						( Origin gPackager )
					)
					( objectStatus "J6U1.209" )
				)
				( pin "vdd(11)"
					( attribute "PN" "206"
						( Origin gPackager )
					)
					( objectStatus "J6U1.206" )
				)
				( pin "vdd(12)"
					( attribute "PN" "204"
						( Origin gPackager )
					)
					( objectStatus "J6U1.204" )
				)
				( pin "vdd(13)"
					( attribute "PN" "92"
						( Origin gPackager )
					)
					( objectStatus "J6U1.92" )
				)
				( pin "vdd(14)"
					( attribute "PN" "90"
						( Origin gPackager )
					)
					( objectStatus "J6U1.90" )
				)
				( pin "vdd(15)"
					( attribute "PN" "88"
						( Origin gPackager )
					)
					( objectStatus "J6U1.88" )
				)
				( pin "vdd(16)"
					( attribute "PN" "85"
						( Origin gPackager )
					)
					( objectStatus "J6U1.85" )
				)
				( pin "vdd(17)"
					( attribute "PN" "83"
						( Origin gPackager )
					)
					( objectStatus "J6U1.83" )
				)
				( pin "vdd(18)"
					( attribute "PN" "80"
						( Origin gPackager )
					)
					( objectStatus "J6U1.80" )
				)
				( pin "vdd(19)"
					( attribute "PN" "76"
						( Origin gPackager )
					)
					( objectStatus "J6U1.76" )
				)
				( pin "vdd(20)"
					( attribute "PN" "73"
						( Origin gPackager )
					)
					( objectStatus "J6U1.73" )
				)
				( pin "vdd(21)"
					( attribute "PN" "70"
						( Origin gPackager )
					)
					( objectStatus "J6U1.70" )
				)
				( pin "vdd(22)"
					( attribute "PN" "67"
						( Origin gPackager )
					)
					( objectStatus "J6U1.67" )
				)
				( pin "vdd(23)"
					( attribute "PN" "64"
						( Origin gPackager )
					)
					( objectStatus "J6U1.64" )
				)
				( pin "vdd(24)"
					( attribute "PN" "61"
						( Origin gPackager )
					)
					( objectStatus "J6U1.61" )
				)
				( pin "vdd(25)"
					( attribute "PN" "59"
						( Origin gPackager )
					)
					( objectStatus "J6U1.59" )
				)
				( pin "vpp(0)"
					( attribute "PN" "287"
						( Origin gPackager )
					)
					( objectStatus "J6U1.287" )
				)
				( pin "vpp(1)"
					( attribute "PN" "286"
						( Origin gPackager )
					)
					( objectStatus "J6U1.286" )
				)
				( pin "vpp(2)"
					( attribute "PN" "288"
						( Origin gPackager )
					)
					( objectStatus "J6U1.288" )
				)
				( pin "vpp(3)"
					( attribute "PN" "143"
						( Origin gPackager )
					)
					( objectStatus "J6U1.143" )
				)
				( pin "vpp(4)"
					( attribute "PN" "142"
						( Origin gPackager )
					)
					( objectStatus "J6U1.142" )
				)
				( pin "vtt(0)"
					( attribute "PN" "221"
						( Origin gPackager )
					)
					( objectStatus "J6U1.221" )
				)
				( pin "vtt(1)"
					( attribute "PN" "77"
						( Origin gPackager )
					)
					( objectStatus "J6U1.77" )
				)
			)
			( gate "@baseboard_fab2_lib.baseboard_fab2(sch_1):page46_i112"
				( attribute "BOM_COST" "MEM"
					( Origin gFrontEnd )
				)
				( attribute "CDS_LIB" "mstr_sconn"
					( Origin gPackager )
				)
				( attribute "CDS_LOCATION" "J6U1"
					( Origin gPackager )
				)
				( attribute "CDS_SEC" "2"
					( Origin gPackager )
				)
				( attribute "LOCATION" "J6U1"
					( Origin gFrontEnd )
				)
				( attribute "MATERIAL" "SCONN"
					( Origin gFrontEnd )
				)
				( attribute "PACK_TYPE" "PIP"
					( Origin gFrontEnd )
				)
				( attribute "PART_NUMBER" "H44441-003"
					( Origin gFrontEnd )
				)
				( attribute "PHYS_PAGE" "46"
					( Origin gFrontEnd )
				)
				( attribute "ROOM" "DDR4_CH_B"
					( Origin gFrontEnd )
				)
				( attribute "ROT" "0"
					( Origin gFrontEnd )
				)
				( attribute "SEC" "2"
					( Origin gFrontEnd )
				)
				( attribute "SEC_TYPE" "PIP"
					( Origin gFrontEnd )
				)
				( attribute "VER" "2"
					( Origin gFrontEnd )
				)
				( attribute "XY" "(1625,3950)"
					( Origin gFrontEnd )
				)
				( attribute "CHIPS_PART_NAME" "SCONN288_H44441003"
					( Origin gPackager )
				)
				( attribute "CDS_PART_NAME" "SCONN288_H44441003_PIP-SCONN,HA"
					( Origin gPackager )
				)
				( objectStatus "J6U1" )
				( pin "dqs0n"
					( attribute "PN" "152"
						( Origin gPackager )
					)
					( objectStatus "J6U1.152" )
				)
				( pin "dqs0p"
					( attribute "PN" "153"
						( Origin gPackager )
					)
					( objectStatus "J6U1.153" )
				)
				( pin "dqs1n"
					( attribute "PN" "163"
						( Origin gPackager )
					)
					( objectStatus "J6U1.163" )
				)
				( pin "dqs1p"
					( attribute "PN" "164"
						( Origin gPackager )
					)
					( objectStatus "J6U1.164" )
				)
				( pin "dqs2n"
					( attribute "PN" "174"
						( Origin gPackager )
					)
					( objectStatus "J6U1.174" )
				)
				( pin "dqs2p"
					( attribute "PN" "175"
						( Origin gPackager )
					)
					( objectStatus "J6U1.175" )
				)
				( pin "dqs3n"
					( attribute "PN" "185"
						( Origin gPackager )
					)
					( objectStatus "J6U1.185" )
				)
				( pin "dqs3p"
					( attribute "PN" "186"
						( Origin gPackager )
					)
					( objectStatus "J6U1.186" )
				)
				( pin "dqs4n"
					( attribute "PN" "244"
						( Origin gPackager )
					)
					( objectStatus "J6U1.244" )
				)
				( pin "dqs4p"
					( attribute "PN" "245"
						( Origin gPackager )
					)
					( objectStatus "J6U1.245" )
				)
				( pin "dqs5n"
					( attribute "PN" "255"
						( Origin gPackager )
					)
					( objectStatus "J6U1.255" )
				)
				( pin "dqs5p"
					( attribute "PN" "256"
						( Origin gPackager )
					)
					( objectStatus "J6U1.256" )
				)
				( pin "dqs6n"
					( attribute "PN" "266"
						( Origin gPackager )
					)
					( objectStatus "J6U1.266" )
				)
				( pin "dqs6p"
					( attribute "PN" "267"
						( Origin gPackager )
					)
					( objectStatus "J6U1.267" )
				)
				( pin "dqs7n"
					( attribute "PN" "277"
						( Origin gPackager )
					)
					( objectStatus "J6U1.277" )
				)
				( pin "dqs7p"
					( attribute "PN" "278"
						( Origin gPackager )
					)
					( objectStatus "J6U1.278" )
				)
				( pin "dqs8n"
					( attribute "PN" "196"
						( Origin gPackager )
					)
					( objectStatus "J6U1.196" )
				)
				( pin "dqs8p"
					( attribute "PN" "197"
						( Origin gPackager )
					)
					( objectStatus "J6U1.197" )
				)
				( pin "dqs9n"
					( attribute "PN" "8"
						( Origin gPackager )
					)
					( objectStatus "J6U1.8" )
				)
				( pin "dqs9p"
					( attribute "PN" "7"
						( Origin gPackager )
					)
					( objectStatus "J6U1.7" )
				)
				( pin "dqs10n"
					( attribute "PN" "19"
						( Origin gPackager )
					)
					( objectStatus "J6U1.19" )
				)
				( pin "dqs10p"
					( attribute "PN" "18"
						( Origin gPackager )
					)
					( objectStatus "J6U1.18" )
				)
				( pin "dqs11n"
					( attribute "PN" "30"
						( Origin gPackager )
					)
					( objectStatus "J6U1.30" )
				)
				( pin "dqs11p"
					( attribute "PN" "29"
						( Origin gPackager )
					)
					( objectStatus "J6U1.29" )
				)
				( pin "dqs12n"
					( attribute "PN" "41"
						( Origin gPackager )
					)
					( objectStatus "J6U1.41" )
				)
				( pin "dqs12p"
					( attribute "PN" "40"
						( Origin gPackager )
					)
					( objectStatus "J6U1.40" )
				)
				( pin "dqs13n"
					( attribute "PN" "100"
						( Origin gPackager )
					)
					( objectStatus "J6U1.100" )
				)
				( pin "dqs13p"
					( attribute "PN" "99"
						( Origin gPackager )
					)
					( objectStatus "J6U1.99" )
				)
				( pin "dqs14n"
					( attribute "PN" "111"
						( Origin gPackager )
					)
					( objectStatus "J6U1.111" )
				)
				( pin "dqs14p"
					( attribute "PN" "110"
						( Origin gPackager )
					)
					( objectStatus "J6U1.110" )
				)
				( pin "dqs15n"
					( attribute "PN" "122"
						( Origin gPackager )
					)
					( objectStatus "J6U1.122" )
				)
				( pin "dqs15p"
					( attribute "PN" "121"
						( Origin gPackager )
					)
					( objectStatus "J6U1.121" )
				)
				( pin "dqs16n"
					( attribute "PN" "133"
						( Origin gPackager )
					)
					( objectStatus "J6U1.133" )
				)
				( pin "dqs16p"
					( attribute "PN" "132"
						( Origin gPackager )
					)
					( objectStatus "J6U1.132" )
				)
				( pin "dqs17n"
					( attribute "PN" "52"
						( Origin gPackager )
					)
					( objectStatus "J6U1.52" )
				)
				( pin "dqs17p"
					( attribute "PN" "51"
						( Origin gPackager )
					)
					( objectStatus "J6U1.51" )
				)
			)
			( gate "@baseboard_fab2_lib.baseboard_fab2(sch_1):page46_i138"
				( attribute "BOM_COST" "MEM"
					( Origin gFrontEnd )
				)
				( attribute "CDS_LIB" "mstr_sconn"
					( Origin gPackager )
				)
				( attribute "CDS_LOCATION" "J6U1"
					( Origin gPackager )
				)
				( attribute "CDS_SEC" "3"
					( Origin gPackager )
				)
				( attribute "LOCATION" "J6U1"
					( Origin gFrontEnd )
				)
				( attribute "MATERIAL" "SCONN"
					( Origin gFrontEnd )
				)
				( attribute "PACK_TYPE" "PIP"
					( Origin gFrontEnd )
				)
				( attribute "PART_NUMBER" "H44441-003"
					( Origin gFrontEnd )
				)
				( attribute "PHYS_PAGE" "46"
					( Origin gFrontEnd )
				)
				( attribute "ROOM" "DDR4_CH_B"
					( Origin gFrontEnd )
				)
				( attribute "ROT" "0"
					( Origin gFrontEnd )
				)
				( attribute "SEC" "3"
					( Origin gFrontEnd )
				)
				( attribute "SEC_TYPE" "PIP"
					( Origin gFrontEnd )
				)
				( attribute "VER" "3"
					( Origin gFrontEnd )
				)
				( attribute "XY" "(3425,2250)"
					( Origin gFrontEnd )
				)
				( attribute "CHIPS_PART_NAME" "SCONN288_H44441003"
					( Origin gPackager )
				)
				( attribute "CDS_PART_NAME" "SCONN288_H44441003_PIP-SCONN,HA"
					( Origin gPackager )
				)
				( objectStatus "J6U1" )
				( pin "vss(0)"
					( attribute "PN" "283"
						( Origin gPackager )
					)
					( objectStatus "J6U1.283" )
				)
				( pin "vss(1)"
					( attribute "PN" "281"
						( Origin gPackager )
					)
					( objectStatus "J6U1.281" )
				)
				( pin "vss(2)"
					( attribute "PN" "279"
						( Origin gPackager )
					)
					( objectStatus "J6U1.279" )
				)
				( pin "vss(3)"
					( attribute "PN" "276"
						( Origin gPackager )
					)
					( objectStatus "J6U1.276" )
				)
				( pin "vss(4)"
					( attribute "PN" "274"
						( Origin gPackager )
					)
					( objectStatus "J6U1.274" )
				)
				( pin "vss(5)"
					( attribute "PN" "272"
						( Origin gPackager )
					)
					( objectStatus "J6U1.272" )
				)
				( pin "vss(6)"
					( attribute "PN" "270"
						( Origin gPackager )
					)
					( objectStatus "J6U1.270" )
				)
				( pin "vss(7)"
					( attribute "PN" "268"
						( Origin gPackager )
					)
					( objectStatus "J6U1.268" )
				)
				( pin "vss(8)"
					( attribute "PN" "265"
						( Origin gPackager )
					)
					( objectStatus "J6U1.265" )
				)
				( pin "vss(9)"
					( attribute "PN" "263"
						( Origin gPackager )
					)
					( objectStatus "J6U1.263" )
				)
				( pin "vss(10)"
					( attribute "PN" "261"
						( Origin gPackager )
					)
					( objectStatus "J6U1.261" )
				)
				( pin "vss(11)"
					( attribute "PN" "259"
						( Origin gPackager )
					)
					( objectStatus "J6U1.259" )
				)
				( pin "vss(12)"
					( attribute "PN" "257"
						( Origin gPackager )
					)
					( objectStatus "J6U1.257" )
				)
				( pin "vss(13)"
					( attribute "PN" "254"
						( Origin gPackager )
					)
					( objectStatus "J6U1.254" )
				)
				( pin "vss(14)"
					( attribute "PN" "252"
						( Origin gPackager )
					)
					( objectStatus "J6U1.252" )
				)
				( pin "vss(15)"
					( attribute "PN" "250"
						( Origin gPackager )
					)
					( objectStatus "J6U1.250" )
				)
				( pin "vss(16)"
					( attribute "PN" "248"
						( Origin gPackager )
					)
					( objectStatus "J6U1.248" )
				)
				( pin "vss(17)"
					( attribute "PN" "246"
						( Origin gPackager )
					)
					( objectStatus "J6U1.246" )
				)
				( pin "vss(18)"
					( attribute "PN" "243"
						( Origin gPackager )
					)
					( objectStatus "J6U1.243" )
				)
				( pin "vss(19)"
					( attribute "PN" "241"
						( Origin gPackager )
					)
					( objectStatus "J6U1.241" )
				)
				( pin "vss(20)"
					( attribute "PN" "239"
						( Origin gPackager )
					)
					( objectStatus "J6U1.239" )
				)
				( pin "vss(21)"
					( attribute "PN" "202"
						( Origin gPackager )
					)
					( objectStatus "J6U1.202" )
				)
				( pin "vss(22)"
					( attribute "PN" "200"
						( Origin gPackager )
					)
					( objectStatus "J6U1.200" )
				)
				( pin "vss(23)"
					( attribute "PN" "198"
						( Origin gPackager )
					)
					( objectStatus "J6U1.198" )
				)
				( pin "vss(24)"
					( attribute "PN" "195"
						( Origin gPackager )
					)
					( objectStatus "J6U1.195" )
				)
				( pin "vss(25)"
					( attribute "PN" "193"
						( Origin gPackager )
					)
					( objectStatus "J6U1.193" )
				)
				( pin "vss(26)"
					( attribute "PN" "191"
						( Origin gPackager )
					)
					( objectStatus "J6U1.191" )
				)
				( pin "vss(27)"
					( attribute "PN" "189"
						( Origin gPackager )
					)
					( objectStatus "J6U1.189" )
				)
				( pin "vss(28)"
					( attribute "PN" "187"
						( Origin gPackager )
					)
					( objectStatus "J6U1.187" )
				)
				( pin "vss(29)"
					( attribute "PN" "184"
						( Origin gPackager )
					)
					( objectStatus "J6U1.184" )
				)
				( pin "vss(30)"
					( attribute "PN" "182"
						( Origin gPackager )
					)
					( objectStatus "J6U1.182" )
				)
				( pin "vss(31)"
					( attribute "PN" "180"
						( Origin gPackager )
					)
					( objectStatus "J6U1.180" )
				)
				( pin "vss(32)"
					( attribute "PN" "178"
						( Origin gPackager )
					)
					( objectStatus "J6U1.178" )
				)
				( pin "vss(33)"
					( attribute "PN" "176"
						( Origin gPackager )
					)
					( objectStatus "J6U1.176" )
				)
				( pin "vss(34)"
					( attribute "PN" "173"
						( Origin gPackager )
					)
					( objectStatus "J6U1.173" )
				)
				( pin "vss(35)"
					( attribute "PN" "171"
						( Origin gPackager )
					)
					( objectStatus "J6U1.171" )
				)
				( pin "vss(36)"
					( attribute "PN" "169"
						( Origin gPackager )
					)
					( objectStatus "J6U1.169" )
				)
				( pin "vss(37)"
					( attribute "PN" "167"
						( Origin gPackager )
					)
					( objectStatus "J6U1.167" )
				)
				( pin "vss(38)"
					( attribute "PN" "165"
						( Origin gPackager )
					)
					( objectStatus "J6U1.165" )
				)
				( pin "vss(39)"
					( attribute "PN" "162"
						( Origin gPackager )
					)
					( objectStatus "J6U1.162" )
				)
				( pin "vss(40)"
					( attribute "PN" "160"
						( Origin gPackager )
					)
					( objectStatus "J6U1.160" )
				)
				( pin "vss(41)"
					( attribute "PN" "158"
						( Origin gPackager )
					)
					( objectStatus "J6U1.158" )
				)
				( pin "vss(42)"
					( attribute "PN" "156"
						( Origin gPackager )
					)
					( objectStatus "J6U1.156" )
				)
				( pin "vss(43)"
					( attribute "PN" "154"
						( Origin gPackager )
					)
					( objectStatus "J6U1.154" )
				)
				( pin "vss(44)"
					( attribute "PN" "151"
						( Origin gPackager )
					)
					( objectStatus "J6U1.151" )
				)
				( pin "vss(45)"
					( attribute "PN" "149"
						( Origin gPackager )
					)
					( objectStatus "J6U1.149" )
				)
				( pin "vss(46)"
					( attribute "PN" "147"
						( Origin gPackager )
					)
					( objectStatus "J6U1.147" )
				)
				( pin "vss(47)"
					( attribute "PN" "138"
						( Origin gPackager )
					)
					( objectStatus "J6U1.138" )
				)
				( pin "vss(48)"
					( attribute "PN" "136"
						( Origin gPackager )
					)
					( objectStatus "J6U1.136" )
				)
				( pin "vss(49)"
					( attribute "PN" "134"
						( Origin gPackager )
					)
					( objectStatus "J6U1.134" )
				)
				( pin "vss(50)"
					( attribute "PN" "131"
						( Origin gPackager )
					)
					( objectStatus "J6U1.131" )
				)
				( pin "vss(51)"
					( attribute "PN" "129"
						( Origin gPackager )
					)
					( objectStatus "J6U1.129" )
				)
				( pin "vss(52)"
					( attribute "PN" "127"
						( Origin gPackager )
					)
					( objectStatus "J6U1.127" )
				)
				( pin "vss(53)"
					( attribute "PN" "125"
						( Origin gPackager )
					)
					( objectStatus "J6U1.125" )
				)
				( pin "vss(54)"
					( attribute "PN" "123"
						( Origin gPackager )
					)
					( objectStatus "J6U1.123" )
				)
				( pin "vss(55)"
					( attribute "PN" "120"
						( Origin gPackager )
					)
					( objectStatus "J6U1.120" )
				)
				( pin "vss(56)"
					( attribute "PN" "118"
						( Origin gPackager )
					)
					( objectStatus "J6U1.118" )
				)
				( pin "vss(57)"
					( attribute "PN" "116"
						( Origin gPackager )
					)
					( objectStatus "J6U1.116" )
				)
				( pin "vss(58)"
					( attribute "PN" "114"
						( Origin gPackager )
					)
					( objectStatus "J6U1.114" )
				)
				( pin "vss(59)"
					( attribute "PN" "112"
						( Origin gPackager )
					)
					( objectStatus "J6U1.112" )
				)
				( pin "vss(60)"
					( attribute "PN" "109"
						( Origin gPackager )
					)
					( objectStatus "J6U1.109" )
				)
				( pin "vss(61)"
					( attribute "PN" "107"
						( Origin gPackager )
					)
					( objectStatus "J6U1.107" )
				)
				( pin "vss(62)"
					( attribute "PN" "105"
						( Origin gPackager )
					)
					( objectStatus "J6U1.105" )
				)
				( pin "vss(63)"
					( attribute "PN" "103"
						( Origin gPackager )
					)
					( objectStatus "J6U1.103" )
				)
				( pin "vss(64)"
					( attribute "PN" "101"
						( Origin gPackager )
					)
					( objectStatus "J6U1.101" )
				)
				( pin "vss(65)"
					( attribute "PN" "98"
						( Origin gPackager )
					)
					( objectStatus "J6U1.98" )
				)
				( pin "vss(66)"
					( attribute "PN" "96"
						( Origin gPackager )
					)
					( objectStatus "J6U1.96" )
				)
				( pin "vss(67)"
					( attribute "PN" "94"
						( Origin gPackager )
					)
					( objectStatus "J6U1.94" )
				)
				( pin "vss(68)"
					( attribute "PN" "57"
						( Origin gPackager )
					)
					( objectStatus "J6U1.57" )
				)
				( pin "vss(69)"
					( attribute "PN" "55"
						( Origin gPackager )
					)
					( objectStatus "J6U1.55" )
				)
				( pin "vss(70)"
					( attribute "PN" "53"
						( Origin gPackager )
					)
					( objectStatus "J6U1.53" )
				)
				( pin "vss(71)"
					( attribute "PN" "50"
						( Origin gPackager )
					)
					( objectStatus "J6U1.50" )
				)
				( pin "vss(72)"
					( attribute "PN" "48"
						( Origin gPackager )
					)
					( objectStatus "J6U1.48" )
				)
				( pin "vss(73)"
					( attribute "PN" "46"
						( Origin gPackager )
					)
					( objectStatus "J6U1.46" )
				)
				( pin "vss(74)"
					( attribute "PN" "44"
						( Origin gPackager )
					)
					( objectStatus "J6U1.44" )
				)
				( pin "vss(75)"
					( attribute "PN" "42"
						( Origin gPackager )
					)
					( objectStatus "J6U1.42" )
				)
				( pin "vss(76)"
					( attribute "PN" "39"
						( Origin gPackager )
					)
					( objectStatus "J6U1.39" )
				)
				( pin "vss(77)"
					( attribute "PN" "37"
						( Origin gPackager )
					)
					( objectStatus "J6U1.37" )
				)
				( pin "vss(78)"
					( attribute "PN" "35"
						( Origin gPackager )
					)
					( objectStatus "J6U1.35" )
				)
				( pin "vss(79)"
					( attribute "PN" "33"
						( Origin gPackager )
					)
					( objectStatus "J6U1.33" )
				)
				( pin "vss(80)"
					( attribute "PN" "31"
						( Origin gPackager )
					)
					( objectStatus "J6U1.31" )
				)
				( pin "vss(81)"
					( attribute "PN" "28"
						( Origin gPackager )
					)
					( objectStatus "J6U1.28" )
				)
				( pin "vss(82)"
					( attribute "PN" "26"
						( Origin gPackager )
					)
					( objectStatus "J6U1.26" )
				)
				( pin "vss(83)"
					( attribute "PN" "24"
						( Origin gPackager )
					)
					( objectStatus "J6U1.24" )
				)
				( pin "vss(84)"
					( attribute "PN" "22"
						( Origin gPackager )
					)
					( objectStatus "J6U1.22" )
				)
				( pin "vss(85)"
					( attribute "PN" "20"
						( Origin gPackager )
					)
					( objectStatus "J6U1.20" )
				)
				( pin "vss(86)"
					( attribute "PN" "17"
						( Origin gPackager )
					)
					( objectStatus "J6U1.17" )
				)
				( pin "vss(87)"
					( attribute "PN" "15"
						( Origin gPackager )
					)
					( objectStatus "J6U1.15" )
				)
				( pin "vss(88)"
					( attribute "PN" "13"
						( Origin gPackager )
					)
					( objectStatus "J6U1.13" )
				)
				( pin "vss(89)"
					( attribute "PN" "11"
						( Origin gPackager )
					)
					( objectStatus "J6U1.11" )
				)
				( pin "vss(90)"
					( attribute "PN" "9"
						( Origin gPackager )
					)
					( objectStatus "J6U1.9" )
				)
				( pin "vss(91)"
					( attribute "PN" "6"
						( Origin gPackager )
					)
					( objectStatus "J6U1.6" )
				)
				( pin "vss(92)"
					( attribute "PN" "4"
						( Origin gPackager )
					)
					( objectStatus "J6U1.4" )
				)
				( pin "vss(93)"
					( attribute "PN" "2"
						( Origin gPackager )
					)
					( objectStatus "J6U1.2" )
				)
			)
			( gate "@baseboard_fab2_lib.baseboard_fab2(sch_1):page47_i43"
				( attribute "BOM_COST" "MEM"
					( Origin gFrontEnd )
				)
				( attribute "CDS_LIB" "mstr_sconn"
					( Origin gPackager )
				)
				( attribute "CDS_LOCATION" "J4G3"
					( Origin gPackager )
				)
				( attribute "CDS_SEC" "3"
					( Origin gPackager )
				)
				( attribute "LOCATION" "J4G3"
					( Origin gFrontEnd )
				)
				( attribute "MATERIAL" "SCONN"
					( Origin gFrontEnd )
				)
				( attribute "PACK_TYPE" "PIP"
					( Origin gFrontEnd )
				)
				( attribute "PART_NUMBER" "H44441-004"
					( Origin gFrontEnd )
				)
				( attribute "PHYS_PAGE" "47"
					( Origin gFrontEnd )
				)
				( attribute "ROOM" "DDR4_CH_C"
					( Origin gFrontEnd )
				)
				( attribute "ROT" "0"
					( Origin gFrontEnd )
				)
				( attribute "SEC" "3"
					( Origin gFrontEnd )
				)
				( attribute "SEC_TYPE" "PIP"
					( Origin gFrontEnd )
				)
				( attribute "VER" "3"
					( Origin gFrontEnd )
				)
				( attribute "XY" "(1800,2650)"
					( Origin gFrontEnd )
				)
				( attribute "CHIPS_PART_NAME" "SCONN288_H44441004"
					( Origin gPackager )
				)
				( attribute "CDS_PART_NAME" "SCONN288_H44441004_PIP-SCONN,HA"
					( Origin gPackager )
				)
				( objectStatus "J4G3" )
				( pin "vss(0)"
					( attribute "PN" "283"
						( Origin gPackager )
					)
					( objectStatus "J4G3.283" )
				)
				( pin "vss(1)"
					( attribute "PN" "281"
						( Origin gPackager )
					)
					( objectStatus "J4G3.281" )
				)
				( pin "vss(2)"
					( attribute "PN" "279"
						( Origin gPackager )
					)
					( objectStatus "J4G3.279" )
				)
				( pin "vss(3)"
					( attribute "PN" "276"
						( Origin gPackager )
					)
					( objectStatus "J4G3.276" )
				)
				( pin "vss(4)"
					( attribute "PN" "274"
						( Origin gPackager )
					)
					( objectStatus "J4G3.274" )
				)
				( pin "vss(5)"
					( attribute "PN" "272"
						( Origin gPackager )
					)
					( objectStatus "J4G3.272" )
				)
				( pin "vss(6)"
					( attribute "PN" "270"
						( Origin gPackager )
					)
					( objectStatus "J4G3.270" )
				)
				( pin "vss(7)"
					( attribute "PN" "268"
						( Origin gPackager )
					)
					( objectStatus "J4G3.268" )
				)
				( pin "vss(8)"
					( attribute "PN" "265"
						( Origin gPackager )
					)
					( objectStatus "J4G3.265" )
				)
				( pin "vss(9)"
					( attribute "PN" "263"
						( Origin gPackager )
					)
					( objectStatus "J4G3.263" )
				)
				( pin "vss(10)"
					( attribute "PN" "261"
						( Origin gPackager )
					)
					( objectStatus "J4G3.261" )
				)
				( pin "vss(11)"
					( attribute "PN" "259"
						( Origin gPackager )
					)
					( objectStatus "J4G3.259" )
				)
				( pin "vss(12)"
					( attribute "PN" "257"
						( Origin gPackager )
					)
					( objectStatus "J4G3.257" )
				)
				( pin "vss(13)"
					( attribute "PN" "254"
						( Origin gPackager )
					)
					( objectStatus "J4G3.254" )
				)
				( pin "vss(14)"
					( attribute "PN" "252"
						( Origin gPackager )
					)
					( objectStatus "J4G3.252" )
				)
				( pin "vss(15)"
					( attribute "PN" "250"
						( Origin gPackager )
					)
					( objectStatus "J4G3.250" )
				)
				( pin "vss(16)"
					( attribute "PN" "248"
						( Origin gPackager )
					)
					( objectStatus "J4G3.248" )
				)
				( pin "vss(17)"
					( attribute "PN" "246"
						( Origin gPackager )
					)
					( objectStatus "J4G3.246" )
				)
				( pin "vss(18)"
					( attribute "PN" "243"
						( Origin gPackager )
					)
					( objectStatus "J4G3.243" )
				)
				( pin "vss(19)"
					( attribute "PN" "241"
						( Origin gPackager )
					)
					( objectStatus "J4G3.241" )
				)
				( pin "vss(20)"
					( attribute "PN" "239"
						( Origin gPackager )
					)
					( objectStatus "J4G3.239" )
				)
				( pin "vss(21)"
					( attribute "PN" "202"
						( Origin gPackager )
					)
					( objectStatus "J4G3.202" )
				)
				( pin "vss(22)"
					( attribute "PN" "200"
						( Origin gPackager )
					)
					( objectStatus "J4G3.200" )
				)
				( pin "vss(23)"
					( attribute "PN" "198"
						( Origin gPackager )
					)
					( objectStatus "J4G3.198" )
				)
				( pin "vss(24)"
					( attribute "PN" "195"
						( Origin gPackager )
					)
					( objectStatus "J4G3.195" )
				)
				( pin "vss(25)"
					( attribute "PN" "193"
						( Origin gPackager )
					)
					( objectStatus "J4G3.193" )
				)
				( pin "vss(26)"
					( attribute "PN" "191"
						( Origin gPackager )
					)
					( objectStatus "J4G3.191" )
				)
				( pin "vss(27)"
					( attribute "PN" "189"
						( Origin gPackager )
					)
					( objectStatus "J4G3.189" )
				)
				( pin "vss(28)"
					( attribute "PN" "187"
						( Origin gPackager )
					)
					( objectStatus "J4G3.187" )
				)
				( pin "vss(29)"
					( attribute "PN" "184"
						( Origin gPackager )
					)
					( objectStatus "J4G3.184" )
				)
				( pin "vss(30)"
					( attribute "PN" "182"
						( Origin gPackager )
					)
					( objectStatus "J4G3.182" )
				)
				( pin "vss(31)"
					( attribute "PN" "180"
						( Origin gPackager )
					)
					( objectStatus "J4G3.180" )
				)
				( pin "vss(32)"
					( attribute "PN" "178"
						( Origin gPackager )
					)
					( objectStatus "J4G3.178" )
				)
				( pin "vss(33)"
					( attribute "PN" "176"
						( Origin gPackager )
					)
					( objectStatus "J4G3.176" )
				)
				( pin "vss(34)"
					( attribute "PN" "173"
						( Origin gPackager )
					)
					( objectStatus "J4G3.173" )
				)
				( pin "vss(35)"
					( attribute "PN" "171"
						( Origin gPackager )
					)
					( objectStatus "J4G3.171" )
				)
				( pin "vss(36)"
					( attribute "PN" "169"
						( Origin gPackager )
					)
					( objectStatus "J4G3.169" )
				)
				( pin "vss(37)"
					( attribute "PN" "167"
						( Origin gPackager )
					)
					( objectStatus "J4G3.167" )
				)
				( pin "vss(38)"
					( attribute "PN" "165"
						( Origin gPackager )
					)
					( objectStatus "J4G3.165" )
				)
				( pin "vss(39)"
					( attribute "PN" "162"
						( Origin gPackager )
					)
					( objectStatus "J4G3.162" )
				)
				( pin "vss(40)"
					( attribute "PN" "160"
						( Origin gPackager )
					)
					( objectStatus "J4G3.160" )
				)
				( pin "vss(41)"
					( attribute "PN" "158"
						( Origin gPackager )
					)
					( objectStatus "J4G3.158" )
				)
				( pin "vss(42)"
					( attribute "PN" "156"
						( Origin gPackager )
					)
					( objectStatus "J4G3.156" )
				)
				( pin "vss(43)"
					( attribute "PN" "154"
						( Origin gPackager )
					)
					( objectStatus "J4G3.154" )
				)
				( pin "vss(44)"
					( attribute "PN" "151"
						( Origin gPackager )
					)
					( objectStatus "J4G3.151" )
				)
				( pin "vss(45)"
					( attribute "PN" "149"
						( Origin gPackager )
					)
					( objectStatus "J4G3.149" )
				)
				( pin "vss(46)"
					( attribute "PN" "147"
						( Origin gPackager )
					)
					( objectStatus "J4G3.147" )
				)
				( pin "vss(47)"
					( attribute "PN" "138"
						( Origin gPackager )
					)
					( objectStatus "J4G3.138" )
				)
				( pin "vss(48)"
					( attribute "PN" "136"
						( Origin gPackager )
					)
					( objectStatus "J4G3.136" )
				)
				( pin "vss(49)"
					( attribute "PN" "134"
						( Origin gPackager )
					)
					( objectStatus "J4G3.134" )
				)
				( pin "vss(50)"
					( attribute "PN" "131"
						( Origin gPackager )
					)
					( objectStatus "J4G3.131" )
				)
				( pin "vss(51)"
					( attribute "PN" "129"
						( Origin gPackager )
					)
					( objectStatus "J4G3.129" )
				)
				( pin "vss(52)"
					( attribute "PN" "127"
						( Origin gPackager )
					)
					( objectStatus "J4G3.127" )
				)
				( pin "vss(53)"
					( attribute "PN" "125"
						( Origin gPackager )
					)
					( objectStatus "J4G3.125" )
				)
				( pin "vss(54)"
					( attribute "PN" "123"
						( Origin gPackager )
					)
					( objectStatus "J4G3.123" )
				)
				( pin "vss(55)"
					( attribute "PN" "120"
						( Origin gPackager )
					)
					( objectStatus "J4G3.120" )
				)
				( pin "vss(56)"
					( attribute "PN" "118"
						( Origin gPackager )
					)
					( objectStatus "J4G3.118" )
				)
				( pin "vss(57)"
					( attribute "PN" "116"
						( Origin gPackager )
					)
					( objectStatus "J4G3.116" )
				)
				( pin "vss(58)"
					( attribute "PN" "114"
						( Origin gPackager )
					)
					( objectStatus "J4G3.114" )
				)
				( pin "vss(59)"
					( attribute "PN" "112"
						( Origin gPackager )
					)
					( objectStatus "J4G3.112" )
				)
				( pin "vss(60)"
					( attribute "PN" "109"
						( Origin gPackager )
					)
					( objectStatus "J4G3.109" )
				)
				( pin "vss(61)"
					( attribute "PN" "107"
						( Origin gPackager )
					)
					( objectStatus "J4G3.107" )
				)
				( pin "vss(62)"
					( attribute "PN" "105"
						( Origin gPackager )
					)
					( objectStatus "J4G3.105" )
				)
				( pin "vss(63)"
					( attribute "PN" "103"
						( Origin gPackager )
					)
					( objectStatus "J4G3.103" )
				)
				( pin "vss(64)"
					( attribute "PN" "101"
						( Origin gPackager )
					)
					( objectStatus "J4G3.101" )
				)
				( pin "vss(65)"
					( attribute "PN" "98"
						( Origin gPackager )
					)
					( objectStatus "J4G3.98" )
				)
				( pin "vss(66)"
					( attribute "PN" "96"
						( Origin gPackager )
					)
					( objectStatus "J4G3.96" )
				)
				( pin "vss(67)"
					( attribute "PN" "94"
						( Origin gPackager )
					)
					( objectStatus "J4G3.94" )
				)
				( pin "vss(68)"
					( attribute "PN" "57"
						( Origin gPackager )
					)
					( objectStatus "J4G3.57" )
				)
				( pin "vss(69)"
					( attribute "PN" "55"
						( Origin gPackager )
					)
					( objectStatus "J4G3.55" )
				)
				( pin "vss(70)"
					( attribute "PN" "53"
						( Origin gPackager )
					)
					( objectStatus "J4G3.53" )
				)
				( pin "vss(71)"
					( attribute "PN" "50"
						( Origin gPackager )
					)
					( objectStatus "J4G3.50" )
				)
				( pin "vss(72)"
					( attribute "PN" "48"
						( Origin gPackager )
					)
					( objectStatus "J4G3.48" )
				)
				( pin "vss(73)"
					( attribute "PN" "46"
						( Origin gPackager )
					)
					( objectStatus "J4G3.46" )
				)
				( pin "vss(74)"
					( attribute "PN" "44"
						( Origin gPackager )
					)
					( objectStatus "J4G3.44" )
				)
				( pin "vss(75)"
					( attribute "PN" "42"
						( Origin gPackager )
					)
					( objectStatus "J4G3.42" )
				)
				( pin "vss(76)"
					( attribute "PN" "39"
						( Origin gPackager )
					)
					( objectStatus "J4G3.39" )
				)
				( pin "vss(77)"
					( attribute "PN" "37"
						( Origin gPackager )
					)
					( objectStatus "J4G3.37" )
				)
				( pin "vss(78)"
					( attribute "PN" "35"
						( Origin gPackager )
					)
					( objectStatus "J4G3.35" )
				)
				( pin "vss(79)"
					( attribute "PN" "33"
						( Origin gPackager )
					)
					( objectStatus "J4G3.33" )
				)
				( pin "vss(80)"
					( attribute "PN" "31"
						( Origin gPackager )
					)
					( objectStatus "J4G3.31" )
				)
				( pin "vss(81)"
					( attribute "PN" "28"
						( Origin gPackager )
					)
					( objectStatus "J4G3.28" )
				)
				( pin "vss(82)"
					( attribute "PN" "26"
						( Origin gPackager )
					)
					( objectStatus "J4G3.26" )
				)
				( pin "vss(83)"
					( attribute "PN" "24"
						( Origin gPackager )
					)
					( objectStatus "J4G3.24" )
				)
				( pin "vss(84)"
					( attribute "PN" "22"
						( Origin gPackager )
					)
					( objectStatus "J4G3.22" )
				)
				( pin "vss(85)"
					( attribute "PN" "20"
						( Origin gPackager )
					)
					( objectStatus "J4G3.20" )
				)
				( pin "vss(86)"
					( attribute "PN" "17"
						( Origin gPackager )
					)
					( objectStatus "J4G3.17" )
				)
				( pin "vss(87)"
					( attribute "PN" "15"
						( Origin gPackager )
					)
					( objectStatus "J4G3.15" )
				)
				( pin "vss(88)"
					( attribute "PN" "13"
						( Origin gPackager )
					)
					( objectStatus "J4G3.13" )
				)
				( pin "vss(89)"
					( attribute "PN" "11"
						( Origin gPackager )
					)
					( objectStatus "J4G3.11" )
				)
				( pin "vss(90)"
					( attribute "PN" "9"
						( Origin gPackager )
					)
					( objectStatus "J4G3.9" )
				)
				( pin "vss(91)"
					( attribute "PN" "6"
						( Origin gPackager )
					)
					( objectStatus "J4G3.6" )
				)
				( pin "vss(92)"
					( attribute "PN" "4"
						( Origin gPackager )
					)
					( objectStatus "J4G3.4" )
				)
				( pin "vss(93)"
					( attribute "PN" "2"
						( Origin gPackager )
					)
					( objectStatus "J4G3.2" )
				)
			)
			( gate "@baseboard_fab2_lib.baseboard_fab2(sch_1):page47_i61"
				( attribute "BOM_COST" "MEM"
					( Origin gFrontEnd )
				)
				( attribute "CDS_LIB" "mstr_sconn"
					( Origin gPackager )
				)
				( attribute "CDS_LOCATION" "J4G3"
					( Origin gPackager )
				)
				( attribute "CDS_SEC" "2"
					( Origin gPackager )
				)
				( attribute "LOCATION" "J4G3"
					( Origin gFrontEnd )
				)
				( attribute "MATERIAL" "SCONN"
					( Origin gFrontEnd )
				)
				( attribute "PACK_TYPE" "PIP"
					( Origin gFrontEnd )
				)
				( attribute "PART_NUMBER" "H44441-004"
					( Origin gFrontEnd )
				)
				( attribute "PHYS_PAGE" "47"
					( Origin gFrontEnd )
				)
				( attribute "ROOM" "DDR4_CH_C"
					( Origin gFrontEnd )
				)
				( attribute "ROT" "0"
					( Origin gFrontEnd )
				)
				( attribute "SEC" "2"
					( Origin gFrontEnd )
				)
				( attribute "SEC_TYPE" "PIP"
					( Origin gFrontEnd )
				)
				( attribute "VER" "2"
					( Origin gFrontEnd )
				)
				( attribute "XY" "(0,4350)"
					( Origin gFrontEnd )
				)
				( attribute "CHIPS_PART_NAME" "SCONN288_H44441004"
					( Origin gPackager )
				)
				( attribute "CDS_PART_NAME" "SCONN288_H44441004_PIP-SCONN,HA"
					( Origin gPackager )
				)
				( objectStatus "J4G3" )
				( pin "dqs0n"
					( attribute "PN" "152"
						( Origin gPackager )
					)
					( objectStatus "J4G3.152" )
				)
				( pin "dqs0p"
					( attribute "PN" "153"
						( Origin gPackager )
					)
					( objectStatus "J4G3.153" )
				)
				( pin "dqs1n"
					( attribute "PN" "163"
						( Origin gPackager )
					)
					( objectStatus "J4G3.163" )
				)
				( pin "dqs1p"
					( attribute "PN" "164"
						( Origin gPackager )
					)
					( objectStatus "J4G3.164" )
				)
				( pin "dqs2n"
					( attribute "PN" "174"
						( Origin gPackager )
					)
					( objectStatus "J4G3.174" )
				)
				( pin "dqs2p"
					( attribute "PN" "175"
						( Origin gPackager )
					)
					( objectStatus "J4G3.175" )
				)
				( pin "dqs3n"
					( attribute "PN" "185"
						( Origin gPackager )
					)
					( objectStatus "J4G3.185" )
				)
				( pin "dqs3p"
					( attribute "PN" "186"
						( Origin gPackager )
					)
					( objectStatus "J4G3.186" )
				)
				( pin "dqs4n"
					( attribute "PN" "244"
						( Origin gPackager )
					)
					( objectStatus "J4G3.244" )
				)
				( pin "dqs4p"
					( attribute "PN" "245"
						( Origin gPackager )
					)
					( objectStatus "J4G3.245" )
				)
				( pin "dqs5n"
					( attribute "PN" "255"
						( Origin gPackager )
					)
					( objectStatus "J4G3.255" )
				)
				( pin "dqs5p"
					( attribute "PN" "256"
						( Origin gPackager )
					)
					( objectStatus "J4G3.256" )
				)
				( pin "dqs6n"
					( attribute "PN" "266"
						( Origin gPackager )
					)
					( objectStatus "J4G3.266" )
				)
				( pin "dqs6p"
					( attribute "PN" "267"
						( Origin gPackager )
					)
					( objectStatus "J4G3.267" )
				)
				( pin "dqs7n"
					( attribute "PN" "277"
						( Origin gPackager )
					)
					( objectStatus "J4G3.277" )
				)
				( pin "dqs7p"
					( attribute "PN" "278"
						( Origin gPackager )
					)
					( objectStatus "J4G3.278" )
				)
				( pin "dqs8n"
					( attribute "PN" "196"
						( Origin gPackager )
					)
					( objectStatus "J4G3.196" )
				)
				( pin "dqs8p"
					( attribute "PN" "197"
						( Origin gPackager )
					)
					( objectStatus "J4G3.197" )
				)
				( pin "dqs9n"
					( attribute "PN" "8"
						( Origin gPackager )
					)
					( objectStatus "J4G3.8" )
				)
				( pin "dqs9p"
					( attribute "PN" "7"
						( Origin gPackager )
					)
					( objectStatus "J4G3.7" )
				)
				( pin "dqs10n"
					( attribute "PN" "19"
						( Origin gPackager )
					)
					( objectStatus "J4G3.19" )
				)
				( pin "dqs10p"
					( attribute "PN" "18"
						( Origin gPackager )
					)
					( objectStatus "J4G3.18" )
				)
				( pin "dqs11n"
					( attribute "PN" "30"
						( Origin gPackager )
					)
					( objectStatus "J4G3.30" )
				)
				( pin "dqs11p"
					( attribute "PN" "29"
						( Origin gPackager )
					)
					( objectStatus "J4G3.29" )
				)
				( pin "dqs12n"
					( attribute "PN" "41"
						( Origin gPackager )
					)
					( objectStatus "J4G3.41" )
				)
				( pin "dqs12p"
					( attribute "PN" "40"
						( Origin gPackager )
					)
					( objectStatus "J4G3.40" )
				)
				( pin "dqs13n"
					( attribute "PN" "100"
						( Origin gPackager )
					)
					( objectStatus "J4G3.100" )
				)
				( pin "dqs13p"
					( attribute "PN" "99"
						( Origin gPackager )
					)
					( objectStatus "J4G3.99" )
				)
				( pin "dqs14n"
					( attribute "PN" "111"
						( Origin gPackager )
					)
					( objectStatus "J4G3.111" )
				)
				( pin "dqs14p"
					( attribute "PN" "110"
						( Origin gPackager )
					)
					( objectStatus "J4G3.110" )
				)
				( pin "dqs15n"
					( attribute "PN" "122"
						( Origin gPackager )
					)
					( objectStatus "J4G3.122" )
				)
				( pin "dqs15p"
					( attribute "PN" "121"
						( Origin gPackager )
					)
					( objectStatus "J4G3.121" )
				)
				( pin "dqs16n"
					( attribute "PN" "133"
						( Origin gPackager )
					)
					( objectStatus "J4G3.133" )
				)
				( pin "dqs16p"
					( attribute "PN" "132"
						( Origin gPackager )
					)
					( objectStatus "J4G3.132" )
				)
				( pin "dqs17n"
					( attribute "PN" "52"
						( Origin gPackager )
					)
					( objectStatus "J4G3.52" )
				)
				( pin "dqs17p"
					( attribute "PN" "51"
						( Origin gPackager )
					)
					( objectStatus "J4G3.51" )
				)
			)
			( gate "@baseboard_fab2_lib.baseboard_fab2(sch_1):page47_i111"
				( attribute "BOM_COST" "MEM"
					( Origin gFrontEnd )
				)
				( attribute "CDS_LIB" "mstr_sconn"
					( Origin gPackager )
				)
				( attribute "CDS_LOCATION" "J4G3"
					( Origin gPackager )
				)
				( attribute "CDS_SEC" "1"
					( Origin gPackager )
				)
				( attribute "LOCATION" "J4G3"
					( Origin gFrontEnd )
				)
				( attribute "MATERIAL" "SCONN"
					( Origin gFrontEnd )
				)
				( attribute "PACK_TYPE" "PIP"
					( Origin gFrontEnd )
				)
				( attribute "PART_NUMBER" "H44441-004"
					( Origin gFrontEnd )
				)
				( attribute "PHYS_PAGE" "47"
					( Origin gFrontEnd )
				)
				( attribute "ROOM" "DDR4_CH_C"
					( Origin gFrontEnd )
				)
				( attribute "ROT" "0"
					( Origin gFrontEnd )
				)
				( attribute "SEC" "1"
					( Origin gFrontEnd )
				)
				( attribute "SEC_TYPE" "PIP"
					( Origin gFrontEnd )
				)
				( attribute "VER" "1"
					( Origin gFrontEnd )
				)
				( attribute "XY" "(-2450,3000)"
					( Origin gFrontEnd )
				)
				( attribute "CHIPS_PART_NAME" "SCONN288_H44441004"
					( Origin gPackager )
				)
				( attribute "CDS_PART_NAME" "SCONN288_H44441004_PIP-SCONN,HA"
					( Origin gPackager )
				)
				( objectStatus "J4G3" )
				( pin "a0"
					( attribute "PN" "79"
						( Origin gPackager )
					)
					( objectStatus "J4G3.79" )
				)
				( pin "a1"
					( attribute "PN" "72"
						( Origin gPackager )
					)
					( objectStatus "J4G3.72" )
				)
				( pin "a2"
					( attribute "PN" "216"
						( Origin gPackager )
					)
					( objectStatus "J4G3.216" )
				)
				( pin "a3"
					( attribute "PN" "71"
						( Origin gPackager )
					)
					( objectStatus "J4G3.71" )
				)
				( pin "a4"
					( attribute "PN" "214"
						( Origin gPackager )
					)
					( objectStatus "J4G3.214" )
				)
				( pin "a5"
					( attribute "PN" "213"
						( Origin gPackager )
					)
					( objectStatus "J4G3.213" )
				)
				( pin "a6"
					( attribute "PN" "69"
						( Origin gPackager )
					)
					( objectStatus "J4G3.69" )
				)
				( pin "a7"
					( attribute "PN" "211"
						( Origin gPackager )
					)
					( objectStatus "J4G3.211" )
				)
				( pin "a8"
					( attribute "PN" "68"
						( Origin gPackager )
					)
					( objectStatus "J4G3.68" )
				)
				( pin "a9"
					( attribute "PN" "66"
						( Origin gPackager )
					)
					( objectStatus "J4G3.66" )
				)
				( pin "a10"
					( attribute "PN" "225"
						( Origin gPackager )
					)
					( objectStatus "J4G3.225" )
				)
				( pin "a11"
					( attribute "PN" "210"
						( Origin gPackager )
					)
					( objectStatus "J4G3.210" )
				)
				( pin "a12"
					( attribute "PN" "65"
						( Origin gPackager )
					)
					( objectStatus "J4G3.65" )
				)
				( pin "a13"
					( attribute "PN" "232"
						( Origin gPackager )
					)
					( objectStatus "J4G3.232" )
				)
				( pin "a14_we_n"
					( attribute "PN" "228"
						( Origin gPackager )
					)
					( objectStatus "J4G3.228" )
				)
				( pin "a15_cas_n"
					( attribute "PN" "86"
						( Origin gPackager )
					)
					( objectStatus "J4G3.86" )
				)
				( pin "a16_ras_n"
					( attribute "PN" "82"
						( Origin gPackager )
					)
					( objectStatus "J4G3.82" )
				)
				( pin "a17"
					( attribute "PN" "234"
						( Origin gPackager )
					)
					( objectStatus "J4G3.234" )
				)
				( pin "act_n"
					( attribute "PN" "62"
						( Origin gPackager )
					)
					( objectStatus "J4G3.62" )
				)
				( pin "alert_n"
					( attribute "PN" "208"
						( Origin gPackager )
					)
					( objectStatus "J4G3.208" )
				)
				( pin "ba(0)"
					( attribute "PN" "81"
						( Origin gPackager )
					)
					( objectStatus "J4G3.81" )
				)
				( pin "ba(1)"
					( attribute "PN" "224"
						( Origin gPackager )
					)
					( objectStatus "J4G3.224" )
				)
				( pin "bg(0)"
					( attribute "PN" "63"
						( Origin gPackager )
					)
					( objectStatus "J4G3.63" )
				)
				( pin "bg(1)"
					( attribute "PN" "207"
						( Origin gPackager )
					)
					( objectStatus "J4G3.207" )
				)
				( pin "c(2)"
					( attribute "PN" "235"
						( Origin gPackager )
					)
					( objectStatus "J4G3.235" )
				)
				( pin "cb(0)"
					( attribute "PN" "49"
						( Origin gPackager )
					)
					( objectStatus "J4G3.49" )
				)
				( pin "cb(1)"
					( attribute "PN" "194"
						( Origin gPackager )
					)
					( objectStatus "J4G3.194" )
				)
				( pin "cb(2)"
					( attribute "PN" "56"
						( Origin gPackager )
					)
					( objectStatus "J4G3.56" )
				)
				( pin "cb(3)"
					( attribute "PN" "201"
						( Origin gPackager )
					)
					( objectStatus "J4G3.201" )
				)
				( pin "cb(4)"
					( attribute "PN" "47"
						( Origin gPackager )
					)
					( objectStatus "J4G3.47" )
				)
				( pin "cb(5)"
					( attribute "PN" "192"
						( Origin gPackager )
					)
					( objectStatus "J4G3.192" )
				)
				( pin "cb(6)"
					( attribute "PN" "54"
						( Origin gPackager )
					)
					( objectStatus "J4G3.54" )
				)
				( pin "cb(7)"
					( attribute "PN" "199"
						( Origin gPackager )
					)
					( objectStatus "J4G3.199" )
				)
				( pin "ck0n"
					( attribute "PN" "75"
						( Origin gPackager )
					)
					( objectStatus "J4G3.75" )
				)
				( pin "ck0p"
					( attribute "PN" "74"
						( Origin gPackager )
					)
					( objectStatus "J4G3.74" )
				)
				( pin "ck1n"
					( attribute "PN" "219"
						( Origin gPackager )
					)
					( objectStatus "J4G3.219" )
				)
				( pin "ck1p"
					( attribute "PN" "218"
						( Origin gPackager )
					)
					( objectStatus "J4G3.218" )
				)
				( pin "cke(0)"
					( attribute "PN" "60"
						( Origin gPackager )
					)
					( objectStatus "J4G3.60" )
				)
				( pin "cke(1)"
					( attribute "PN" "203"
						( Origin gPackager )
					)
					( objectStatus "J4G3.203" )
				)
				( pin "dq(0)"
					( attribute "PN" "5"
						( Origin gPackager )
					)
					( objectStatus "J4G3.5" )
				)
				( pin "dq(1)"
					( attribute "PN" "150"
						( Origin gPackager )
					)
					( objectStatus "J4G3.150" )
				)
				( pin "dq(2)"
					( attribute "PN" "12"
						( Origin gPackager )
					)
					( objectStatus "J4G3.12" )
				)
				( pin "dq(3)"
					( attribute "PN" "157"
						( Origin gPackager )
					)
					( objectStatus "J4G3.157" )
				)
				( pin "dq(4)"
					( attribute "PN" "3"
						( Origin gPackager )
					)
					( objectStatus "J4G3.3" )
				)
				( pin "dq(5)"
					( attribute "PN" "148"
						( Origin gPackager )
					)
					( objectStatus "J4G3.148" )
				)
				( pin "dq(6)"
					( attribute "PN" "10"
						( Origin gPackager )
					)
					( objectStatus "J4G3.10" )
				)
				( pin "dq(7)"
					( attribute "PN" "155"
						( Origin gPackager )
					)
					( objectStatus "J4G3.155" )
				)
				( pin "dq(8)"
					( attribute "PN" "16"
						( Origin gPackager )
					)
					( objectStatus "J4G3.16" )
				)
				( pin "dq(9)"
					( attribute "PN" "161"
						( Origin gPackager )
					)
					( objectStatus "J4G3.161" )
				)
				( pin "dq(10)"
					( attribute "PN" "23"
						( Origin gPackager )
					)
					( objectStatus "J4G3.23" )
				)
				( pin "dq(11)"
					( attribute "PN" "168"
						( Origin gPackager )
					)
					( objectStatus "J4G3.168" )
				)
				( pin "dq(12)"
					( attribute "PN" "14"
						( Origin gPackager )
					)
					( objectStatus "J4G3.14" )
				)
				( pin "dq(13)"
					( attribute "PN" "159"
						( Origin gPackager )
					)
					( objectStatus "J4G3.159" )
				)
				( pin "dq(14)"
					( attribute "PN" "21"
						( Origin gPackager )
					)
					( objectStatus "J4G3.21" )
				)
				( pin "dq(15)"
					( attribute "PN" "166"
						( Origin gPackager )
					)
					( objectStatus "J4G3.166" )
				)
				( pin "dq(16)"
					( attribute "PN" "27"
						( Origin gPackager )
					)
					( objectStatus "J4G3.27" )
				)
				( pin "dq(17)"
					( attribute "PN" "172"
						( Origin gPackager )
					)
					( objectStatus "J4G3.172" )
				)
				( pin "dq(18)"
					( attribute "PN" "34"
						( Origin gPackager )
					)
					( objectStatus "J4G3.34" )
				)
				( pin "dq(19)"
					( attribute "PN" "179"
						( Origin gPackager )
					)
					( objectStatus "J4G3.179" )
				)
				( pin "dq(20)"
					( attribute "PN" "25"
						( Origin gPackager )
					)
					( objectStatus "J4G3.25" )
				)
				( pin "dq(21)"
					( attribute "PN" "170"
						( Origin gPackager )
					)
					( objectStatus "J4G3.170" )
				)
				( pin "dq(22)"
					( attribute "PN" "32"
						( Origin gPackager )
					)
					( objectStatus "J4G3.32" )
				)
				( pin "dq(23)"
					( attribute "PN" "177"
						( Origin gPackager )
					)
					( objectStatus "J4G3.177" )
				)
				( pin "dq(24)"
					( attribute "PN" "38"
						( Origin gPackager )
					)
					( objectStatus "J4G3.38" )
				)
				( pin "dq(25)"
					( attribute "PN" "183"
						( Origin gPackager )
					)
					( objectStatus "J4G3.183" )
				)
				( pin "dq(26)"
					( attribute "PN" "45"
						( Origin gPackager )
					)
					( objectStatus "J4G3.45" )
				)
				( pin "dq(27)"
					( attribute "PN" "190"
						( Origin gPackager )
					)
					( objectStatus "J4G3.190" )
				)
				( pin "dq(28)"
					( attribute "PN" "36"
						( Origin gPackager )
					)
					( objectStatus "J4G3.36" )
				)
				( pin "dq(29)"
					( attribute "PN" "181"
						( Origin gPackager )
					)
					( objectStatus "J4G3.181" )
				)
				( pin "dq(30)"
					( attribute "PN" "43"
						( Origin gPackager )
					)
					( objectStatus "J4G3.43" )
				)
				( pin "dq(31)"
					( attribute "PN" "188"
						( Origin gPackager )
					)
					( objectStatus "J4G3.188" )
				)
				( pin "dq(32)"
					( attribute "PN" "97"
						( Origin gPackager )
					)
					( objectStatus "J4G3.97" )
				)
				( pin "dq(33)"
					( attribute "PN" "242"
						( Origin gPackager )
					)
					( objectStatus "J4G3.242" )
				)
				( pin "dq(34)"
					( attribute "PN" "104"
						( Origin gPackager )
					)
					( objectStatus "J4G3.104" )
				)
				( pin "dq(35)"
					( attribute "PN" "249"
						( Origin gPackager )
					)
					( objectStatus "J4G3.249" )
				)
				( pin "dq(36)"
					( attribute "PN" "95"
						( Origin gPackager )
					)
					( objectStatus "J4G3.95" )
				)
				( pin "dq(37)"
					( attribute "PN" "240"
						( Origin gPackager )
					)
					( objectStatus "J4G3.240" )
				)
				( pin "dq(38)"
					( attribute "PN" "102"
						( Origin gPackager )
					)
					( objectStatus "J4G3.102" )
				)
				( pin "dq(39)"
					( attribute "PN" "247"
						( Origin gPackager )
					)
					( objectStatus "J4G3.247" )
				)
				( pin "dq(40)"
					( attribute "PN" "108"
						( Origin gPackager )
					)
					( objectStatus "J4G3.108" )
				)
				( pin "dq(41)"
					( attribute "PN" "253"
						( Origin gPackager )
					)
					( objectStatus "J4G3.253" )
				)
				( pin "dq(42)"
					( attribute "PN" "115"
						( Origin gPackager )
					)
					( objectStatus "J4G3.115" )
				)
				( pin "dq(43)"
					( attribute "PN" "260"
						( Origin gPackager )
					)
					( objectStatus "J4G3.260" )
				)
				( pin "dq(44)"
					( attribute "PN" "106"
						( Origin gPackager )
					)
					( objectStatus "J4G3.106" )
				)
				( pin "dq(45)"
					( attribute "PN" "251"
						( Origin gPackager )
					)
					( objectStatus "J4G3.251" )
				)
				( pin "dq(46)"
					( attribute "PN" "113"
						( Origin gPackager )
					)
					( objectStatus "J4G3.113" )
				)
				( pin "dq(47)"
					( attribute "PN" "258"
						( Origin gPackager )
					)
					( objectStatus "J4G3.258" )
				)
				( pin "dq(48)"
					( attribute "PN" "119"
						( Origin gPackager )
					)
					( objectStatus "J4G3.119" )
				)
				( pin "dq(49)"
					( attribute "PN" "264"
						( Origin gPackager )
					)
					( objectStatus "J4G3.264" )
				)
				( pin "dq(50)"
					( attribute "PN" "126"
						( Origin gPackager )
					)
					( objectStatus "J4G3.126" )
				)
				( pin "dq(51)"
					( attribute "PN" "271"
						( Origin gPackager )
					)
					( objectStatus "J4G3.271" )
				)
				( pin "dq(52)"
					( attribute "PN" "117"
						( Origin gPackager )
					)
					( objectStatus "J4G3.117" )
				)
				( pin "dq(53)"
					( attribute "PN" "262"
						( Origin gPackager )
					)
					( objectStatus "J4G3.262" )
				)
				( pin "dq(54)"
					( attribute "PN" "124"
						( Origin gPackager )
					)
					( objectStatus "J4G3.124" )
				)
				( pin "dq(55)"
					( attribute "PN" "269"
						( Origin gPackager )
					)
					( objectStatus "J4G3.269" )
				)
				( pin "dq(56)"
					( attribute "PN" "130"
						( Origin gPackager )
					)
					( objectStatus "J4G3.130" )
				)
				( pin "dq(57)"
					( attribute "PN" "275"
						( Origin gPackager )
					)
					( objectStatus "J4G3.275" )
				)
				( pin "dq(58)"
					( attribute "PN" "137"
						( Origin gPackager )
					)
					( objectStatus "J4G3.137" )
				)
				( pin "dq(59)"
					( attribute "PN" "282"
						( Origin gPackager )
					)
					( objectStatus "J4G3.282" )
				)
				( pin "dq(60)"
					( attribute "PN" "128"
						( Origin gPackager )
					)
					( objectStatus "J4G3.128" )
				)
				( pin "dq(61)"
					( attribute "PN" "273"
						( Origin gPackager )
					)
					( objectStatus "J4G3.273" )
				)
				( pin "dq(62)"
					( attribute "PN" "135"
						( Origin gPackager )
					)
					( objectStatus "J4G3.135" )
				)
				( pin "dq(63)"
					( attribute "PN" "280"
						( Origin gPackager )
					)
					( objectStatus "J4G3.280" )
				)
				( pin "event_n"
					( attribute "PN" "78"
						( Origin gPackager )
					)
					( objectStatus "J4G3.78" )
				)
				( pin "odt(0)"
					( attribute "PN" "87"
						( Origin gPackager )
					)
					( objectStatus "J4G3.87" )
				)
				( pin "odt(1)"
					( attribute "PN" "91"
						( Origin gPackager )
					)
					( objectStatus "J4G3.91" )
				)
				( pin "par"
					( attribute "PN" "222"
						( Origin gPackager )
					)
					( objectStatus "J4G3.222" )
				)
				( pin "reset_n"
					( attribute "PN" "58"
						( Origin gPackager )
					)
					( objectStatus "J4G3.58" )
				)
				( pin "rfu(0)"
					( attribute "PN" "205"
						( Origin gPackager )
					)
					( objectStatus "J4G3.205" )
				)
				( pin "rfu(1)"
					( attribute "PN" "227"
						( Origin gPackager )
					)
					( objectStatus "J4G3.227" )
				)
				( pin "rfu(2)"
					( attribute "PN" "144"
						( Origin gPackager )
					)
					( objectStatus "J4G3.144" )
				)
				( pin "s0_n"
					( attribute "PN" "84"
						( Origin gPackager )
					)
					( objectStatus "J4G3.84" )
				)
				( pin "s1_n"
					( attribute "PN" "89"
						( Origin gPackager )
					)
					( objectStatus "J4G3.89" )
				)
				( pin "s2_n_c(0)"
					( attribute "PN" "93"
						( Origin gPackager )
					)
					( objectStatus "J4G3.93" )
				)
				( pin "s3_n_c(1)"
					( attribute "PN" "237"
						( Origin gPackager )
					)
					( objectStatus "J4G3.237" )
				)
				( pin "sa(0)"
					( attribute "PN" "139"
						( Origin gPackager )
					)
					( objectStatus "J4G3.139" )
				)
				( pin "sa(1)"
					( attribute "PN" "140"
						( Origin gPackager )
					)
					( objectStatus "J4G3.140" )
				)
				( pin "sa(2)"
					( attribute "PN" "238"
						( Origin gPackager )
					)
					( objectStatus "J4G3.238" )
				)
				( pin "save_n_nc"
					( attribute "PN" "230"
						( Origin gPackager )
					)
					( objectStatus "J4G3.230" )
				)
				( pin "scl"
					( attribute "PN" "141"
						( Origin gPackager )
					)
					( objectStatus "J4G3.141" )
				)
				( pin "sda"
					( attribute "PN" "285"
						( Origin gPackager )
					)
					( objectStatus "J4G3.285" )
				)
				( pin "vddspd"
					( attribute "PN" "284"
						( Origin gPackager )
					)
					( objectStatus "J4G3.284" )
				)
				( pin "vrefca"
					( attribute "PN" "146"
						( Origin gPackager )
					)
					( objectStatus "J4G3.146" )
				)
			)
			( gate "@baseboard_fab2_lib.baseboard_fab2(sch_1):page47_i179"
				( attribute "BOM_COST" "MEM"
					( Origin gFrontEnd )
				)
				( attribute "CDS_LIB" "mstr_sconn"
					( Origin gPackager )
				)
				( attribute "CDS_LOCATION" "J4G3"
					( Origin gPackager )
				)
				( attribute "CDS_SEC" "4"
					( Origin gPackager )
				)
				( attribute "LOCATION" "J4G3"
					( Origin gFrontEnd )
				)
				( attribute "MATERIAL" "SCONN"
					( Origin gFrontEnd )
				)
				( attribute "PACK_TYPE" "PIP"
					( Origin gFrontEnd )
				)
				( attribute "PART_NUMBER" "H44441-004"
					( Origin gFrontEnd )
				)
				( attribute "PHYS_PAGE" "47"
					( Origin gFrontEnd )
				)
				( attribute "ROOM" "DDR4_CH_C"
					( Origin gFrontEnd )
				)
				( attribute "ROT" "0"
					( Origin gFrontEnd )
				)
				( attribute "SEC" "4"
					( Origin gFrontEnd )
				)
				( attribute "SEC_TYPE" "PIP"
					( Origin gFrontEnd )
				)
				( attribute "VER" "4"
					( Origin gFrontEnd )
				)
				( attribute "XY" "(0,2050)"
					( Origin gFrontEnd )
				)
				( attribute "CHIPS_PART_NAME" "SCONN288_H44441004"
					( Origin gPackager )
				)
				( attribute "CDS_PART_NAME" "SCONN288_H44441004_PIP-SCONN,HA"
					( Origin gPackager )
				)
				( objectStatus "J4G3" )
				( pin "\12v\(0)"
					( attribute "PN" "145"
						( Origin gPackager )
					)
					( objectStatus "J4G3.145" )
				)
				( pin "\12v\(1)"
					( attribute "PN" "1"
						( Origin gPackager )
					)
					( objectStatus "J4G3.1" )
				)
				( pin "vdd(0)"
					( attribute "PN" "236"
						( Origin gPackager )
					)
					( objectStatus "J4G3.236" )
				)
				( pin "vdd(1)"
					( attribute "PN" "233"
						( Origin gPackager )
					)
					( objectStatus "J4G3.233" )
				)
				( pin "vdd(2)"
					( attribute "PN" "231"
						( Origin gPackager )
					)
					( objectStatus "J4G3.231" )
				)
				( pin "vdd(3)"
					( attribute "PN" "229"
						( Origin gPackager )
					)
					( objectStatus "J4G3.229" )
				)
				( pin "vdd(4)"
					( attribute "PN" "226"
						( Origin gPackager )
					)
					( objectStatus "J4G3.226" )
				)
				( pin "vdd(5)"
					( attribute "PN" "223"
						( Origin gPackager )
					)
					( objectStatus "J4G3.223" )
				)
				( pin "vdd(6)"
					( attribute "PN" "220"
						( Origin gPackager )
					)
					( objectStatus "J4G3.220" )
				)
				( pin "vdd(7)"
					( attribute "PN" "217"
						( Origin gPackager )
					)
					( objectStatus "J4G3.217" )
				)
				( pin "vdd(8)"
					( attribute "PN" "215"
						( Origin gPackager )
					)
					( objectStatus "J4G3.215" )
				)
				( pin "vdd(9)"
					( attribute "PN" "212"
						( Origin gPackager )
					)
					( objectStatus "J4G3.212" )
				)
				( pin "vdd(10)"
					( attribute "PN" "209"
						( Origin gPackager )
					)
					( objectStatus "J4G3.209" )
				)
				( pin "vdd(11)"
					( attribute "PN" "206"
						( Origin gPackager )
					)
					( objectStatus "J4G3.206" )
				)
				( pin "vdd(12)"
					( attribute "PN" "204"
						( Origin gPackager )
					)
					( objectStatus "J4G3.204" )
				)
				( pin "vdd(13)"
					( attribute "PN" "92"
						( Origin gPackager )
					)
					( objectStatus "J4G3.92" )
				)
				( pin "vdd(14)"
					( attribute "PN" "90"
						( Origin gPackager )
					)
					( objectStatus "J4G3.90" )
				)
				( pin "vdd(15)"
					( attribute "PN" "88"
						( Origin gPackager )
					)
					( objectStatus "J4G3.88" )
				)
				( pin "vdd(16)"
					( attribute "PN" "85"
						( Origin gPackager )
					)
					( objectStatus "J4G3.85" )
				)
				( pin "vdd(17)"
					( attribute "PN" "83"
						( Origin gPackager )
					)
					( objectStatus "J4G3.83" )
				)
				( pin "vdd(18)"
					( attribute "PN" "80"
						( Origin gPackager )
					)
					( objectStatus "J4G3.80" )
				)
				( pin "vdd(19)"
					( attribute "PN" "76"
						( Origin gPackager )
					)
					( objectStatus "J4G3.76" )
				)
				( pin "vdd(20)"
					( attribute "PN" "73"
						( Origin gPackager )
					)
					( objectStatus "J4G3.73" )
				)
				( pin "vdd(21)"
					( attribute "PN" "70"
						( Origin gPackager )
					)
					( objectStatus "J4G3.70" )
				)
				( pin "vdd(22)"
					( attribute "PN" "67"
						( Origin gPackager )
					)
					( objectStatus "J4G3.67" )
				)
				( pin "vdd(23)"
					( attribute "PN" "64"
						( Origin gPackager )
					)
					( objectStatus "J4G3.64" )
				)
				( pin "vdd(24)"
					( attribute "PN" "61"
						( Origin gPackager )
					)
					( objectStatus "J4G3.61" )
				)
				( pin "vdd(25)"
					( attribute "PN" "59"
						( Origin gPackager )
					)
					( objectStatus "J4G3.59" )
				)
				( pin "vpp(0)"
					( attribute "PN" "287"
						( Origin gPackager )
					)
					( objectStatus "J4G3.287" )
				)
				( pin "vpp(1)"
					( attribute "PN" "286"
						( Origin gPackager )
					)
					( objectStatus "J4G3.286" )
				)
				( pin "vpp(2)"
					( attribute "PN" "288"
						( Origin gPackager )
					)
					( objectStatus "J4G3.288" )
				)
				( pin "vpp(3)"
					( attribute "PN" "143"
						( Origin gPackager )
					)
					( objectStatus "J4G3.143" )
				)
				( pin "vpp(4)"
					( attribute "PN" "142"
						( Origin gPackager )
					)
					( objectStatus "J4G3.142" )
				)
				( pin "vtt(0)"
					( attribute "PN" "221"
						( Origin gPackager )
					)
					( objectStatus "J4G3.221" )
				)
				( pin "vtt(1)"
					( attribute "PN" "77"
						( Origin gPackager )
					)
					( objectStatus "J4G3.77" )
				)
			)
			( gate "@baseboard_fab2_lib.baseboard_fab2(sch_1):page47_i188"
				( attribute "BOM_COST" "MEM"
					( Origin gFrontEnd )
				)
				( attribute "CDS_LIB" "dev_discrete"
					( Origin gPackager )
				)
				( attribute "CDS_LOCATION" "C4G19"
					( Origin gPackager )
				)
				( attribute "CDS_SEC" "1"
					( Origin gPackager )
				)
				( attribute "LOCATION" "C4G19"
					( Origin gFrontEnd )
				)
				( attribute "MATERIAL" "X7R"
					( Origin gFrontEnd )
				)
				( attribute "PACK_TYPE" "0402V"
					( Origin gFrontEnd )
				)
				( attribute "PART_NUMBER" "A36096-045"
					( Origin gFrontEnd )
				)
				( attribute "PHYS_PAGE" "47"
					( Origin gFrontEnd )
				)
				( attribute "ROOM" "DDR4_CH_C"
					( Origin gFrontEnd )
				)
				( attribute "ROT" "2"
					( Origin gFrontEnd )
				)
				( attribute "SEC" "1"
					( Origin gFrontEnd )
				)
				( attribute "SEC_TYPE" "0402V"
					( Origin gFrontEnd )
				)
				( attribute "TOLERANCE" "10%"
					( Origin gFrontEnd )
				)
				( attribute "VALUE" "0.01UF"
					( Origin gFrontEnd )
				)
				( attribute "VER" "1"
					( Origin gFrontEnd )
				)
				( attribute "VOLTAGE" "25V"
					( Units "uVoltage" "V" 1.000000)
					( Origin gFrontEnd )
				)
				( attribute "XY" "(-4650,1300)"
					( Origin gFrontEnd )
				)
				( attribute "CHIPS_PART_NAME" "CAP_A"
					( Origin gPackager )
				)
				( attribute "CDS_PART_NAME" "CAP_A_0402V-0.01UF,25V,10%,X7RA"
					( Origin gPackager )
				)
				( objectStatus "C4G19" )
				( pin "a"
					( attribute "PN" "1"
						( Origin gPackager )
					)
					( objectStatus "C4G19.1" )
				)
				( pin "b"
					( attribute "PN" "2"
						( Origin gPackager )
					)
					( objectStatus "C4G19.2" )
				)
			)
			( gate "@baseboard_fab2_lib.baseboard_fab2(sch_1):page48_i43"
				( attribute "BOM_COST" "MEM"
					( Origin gFrontEnd )
				)
				( attribute "CDS_LIB" "mstr_sconn"
					( Origin gPackager )
				)
				( attribute "CDS_LOCATION" "J6U2"
					( Origin gPackager )
				)
				( attribute "CDS_SEC" "3"
					( Origin gPackager )
				)
				( attribute "LOCATION" "J6U2"
					( Origin gFrontEnd )
				)
				( attribute "MATERIAL" "SCONN"
					( Origin gFrontEnd )
				)
				( attribute "PACK_TYPE" "PIP"
					( Origin gFrontEnd )
				)
				( attribute "PART_NUMBER" "H44441-003"
					( Origin gFrontEnd )
				)
				( attribute "PHYS_PAGE" "48"
					( Origin gFrontEnd )
				)
				( attribute "ROOM" "DDR4_CH_C1"
					( Origin gFrontEnd )
				)
				( attribute "ROT" "0"
					( Origin gFrontEnd )
				)
				( attribute "SEC" "3"
					( Origin gFrontEnd )
				)
				( attribute "SEC_TYPE" "PIP"
					( Origin gFrontEnd )
				)
				( attribute "VER" "3"
					( Origin gFrontEnd )
				)
				( attribute "XY" "(1800,2600)"
					( Origin gFrontEnd )
				)
				( attribute "CHIPS_PART_NAME" "SCONN288_H44441003"
					( Origin gPackager )
				)
				( attribute "CDS_PART_NAME" "SCONN288_H44441003_PIP-SCONN,HA"
					( Origin gPackager )
				)
				( objectStatus "J6U2" )
				( pin "vss(0)"
					( attribute "PN" "283"
						( Origin gPackager )
					)
					( objectStatus "J6U2.283" )
				)
				( pin "vss(1)"
					( attribute "PN" "281"
						( Origin gPackager )
					)
					( objectStatus "J6U2.281" )
				)
				( pin "vss(2)"
					( attribute "PN" "279"
						( Origin gPackager )
					)
					( objectStatus "J6U2.279" )
				)
				( pin "vss(3)"
					( attribute "PN" "276"
						( Origin gPackager )
					)
					( objectStatus "J6U2.276" )
				)
				( pin "vss(4)"
					( attribute "PN" "274"
						( Origin gPackager )
					)
					( objectStatus "J6U2.274" )
				)
				( pin "vss(5)"
					( attribute "PN" "272"
						( Origin gPackager )
					)
					( objectStatus "J6U2.272" )
				)
				( pin "vss(6)"
					( attribute "PN" "270"
						( Origin gPackager )
					)
					( objectStatus "J6U2.270" )
				)
				( pin "vss(7)"
					( attribute "PN" "268"
						( Origin gPackager )
					)
					( objectStatus "J6U2.268" )
				)
				( pin "vss(8)"
					( attribute "PN" "265"
						( Origin gPackager )
					)
					( objectStatus "J6U2.265" )
				)
				( pin "vss(9)"
					( attribute "PN" "263"
						( Origin gPackager )
					)
					( objectStatus "J6U2.263" )
				)
				( pin "vss(10)"
					( attribute "PN" "261"
						( Origin gPackager )
					)
					( objectStatus "J6U2.261" )
				)
				( pin "vss(11)"
					( attribute "PN" "259"
						( Origin gPackager )
					)
					( objectStatus "J6U2.259" )
				)
				( pin "vss(12)"
					( attribute "PN" "257"
						( Origin gPackager )
					)
					( objectStatus "J6U2.257" )
				)
				( pin "vss(13)"
					( attribute "PN" "254"
						( Origin gPackager )
					)
					( objectStatus "J6U2.254" )
				)
				( pin "vss(14)"
					( attribute "PN" "252"
						( Origin gPackager )
					)
					( objectStatus "J6U2.252" )
				)
				( pin "vss(15)"
					( attribute "PN" "250"
						( Origin gPackager )
					)
					( objectStatus "J6U2.250" )
				)
				( pin "vss(16)"
					( attribute "PN" "248"
						( Origin gPackager )
					)
					( objectStatus "J6U2.248" )
				)
				( pin "vss(17)"
					( attribute "PN" "246"
						( Origin gPackager )
					)
					( objectStatus "J6U2.246" )
				)
				( pin "vss(18)"
					( attribute "PN" "243"
						( Origin gPackager )
					)
					( objectStatus "J6U2.243" )
				)
				( pin "vss(19)"
					( attribute "PN" "241"
						( Origin gPackager )
					)
					( objectStatus "J6U2.241" )
				)
				( pin "vss(20)"
					( attribute "PN" "239"
						( Origin gPackager )
					)
					( objectStatus "J6U2.239" )
				)
				( pin "vss(21)"
					( attribute "PN" "202"
						( Origin gPackager )
					)
					( objectStatus "J6U2.202" )
				)
				( pin "vss(22)"
					( attribute "PN" "200"
						( Origin gPackager )
					)
					( objectStatus "J6U2.200" )
				)
				( pin "vss(23)"
					( attribute "PN" "198"
						( Origin gPackager )
					)
					( objectStatus "J6U2.198" )
				)
				( pin "vss(24)"
					( attribute "PN" "195"
						( Origin gPackager )
					)
					( objectStatus "J6U2.195" )
				)
				( pin "vss(25)"
					( attribute "PN" "193"
						( Origin gPackager )
					)
					( objectStatus "J6U2.193" )
				)
				( pin "vss(26)"
					( attribute "PN" "191"
						( Origin gPackager )
					)
					( objectStatus "J6U2.191" )
				)
				( pin "vss(27)"
					( attribute "PN" "189"
						( Origin gPackager )
					)
					( objectStatus "J6U2.189" )
				)
				( pin "vss(28)"
					( attribute "PN" "187"
						( Origin gPackager )
					)
					( objectStatus "J6U2.187" )
				)
				( pin "vss(29)"
					( attribute "PN" "184"
						( Origin gPackager )
					)
					( objectStatus "J6U2.184" )
				)
				( pin "vss(30)"
					( attribute "PN" "182"
						( Origin gPackager )
					)
					( objectStatus "J6U2.182" )
				)
				( pin "vss(31)"
					( attribute "PN" "180"
						( Origin gPackager )
					)
					( objectStatus "J6U2.180" )
				)
				( pin "vss(32)"
					( attribute "PN" "178"
						( Origin gPackager )
					)
					( objectStatus "J6U2.178" )
				)
				( pin "vss(33)"
					( attribute "PN" "176"
						( Origin gPackager )
					)
					( objectStatus "J6U2.176" )
				)
				( pin "vss(34)"
					( attribute "PN" "173"
						( Origin gPackager )
					)
					( objectStatus "J6U2.173" )
				)
				( pin "vss(35)"
					( attribute "PN" "171"
						( Origin gPackager )
					)
					( objectStatus "J6U2.171" )
				)
				( pin "vss(36)"
					( attribute "PN" "169"
						( Origin gPackager )
					)
					( objectStatus "J6U2.169" )
				)
				( pin "vss(37)"
					( attribute "PN" "167"
						( Origin gPackager )
					)
					( objectStatus "J6U2.167" )
				)
				( pin "vss(38)"
					( attribute "PN" "165"
						( Origin gPackager )
					)
					( objectStatus "J6U2.165" )
				)
				( pin "vss(39)"
					( attribute "PN" "162"
						( Origin gPackager )
					)
					( objectStatus "J6U2.162" )
				)
				( pin "vss(40)"
					( attribute "PN" "160"
						( Origin gPackager )
					)
					( objectStatus "J6U2.160" )
				)
				( pin "vss(41)"
					( attribute "PN" "158"
						( Origin gPackager )
					)
					( objectStatus "J6U2.158" )
				)
				( pin "vss(42)"
					( attribute "PN" "156"
						( Origin gPackager )
					)
					( objectStatus "J6U2.156" )
				)
				( pin "vss(43)"
					( attribute "PN" "154"
						( Origin gPackager )
					)
					( objectStatus "J6U2.154" )
				)
				( pin "vss(44)"
					( attribute "PN" "151"
						( Origin gPackager )
					)
					( objectStatus "J6U2.151" )
				)
				( pin "vss(45)"
					( attribute "PN" "149"
						( Origin gPackager )
					)
					( objectStatus "J6U2.149" )
				)
				( pin "vss(46)"
					( attribute "PN" "147"
						( Origin gPackager )
					)
					( objectStatus "J6U2.147" )
				)
				( pin "vss(47)"
					( attribute "PN" "138"
						( Origin gPackager )
					)
					( objectStatus "J6U2.138" )
				)
				( pin "vss(48)"
					( attribute "PN" "136"
						( Origin gPackager )
					)
					( objectStatus "J6U2.136" )
				)
				( pin "vss(49)"
					( attribute "PN" "134"
						( Origin gPackager )
					)
					( objectStatus "J6U2.134" )
				)
				( pin "vss(50)"
					( attribute "PN" "131"
						( Origin gPackager )
					)
					( objectStatus "J6U2.131" )
				)
				( pin "vss(51)"
					( attribute "PN" "129"
						( Origin gPackager )
					)
					( objectStatus "J6U2.129" )
				)
				( pin "vss(52)"
					( attribute "PN" "127"
						( Origin gPackager )
					)
					( objectStatus "J6U2.127" )
				)
				( pin "vss(53)"
					( attribute "PN" "125"
						( Origin gPackager )
					)
					( objectStatus "J6U2.125" )
				)
				( pin "vss(54)"
					( attribute "PN" "123"
						( Origin gPackager )
					)
					( objectStatus "J6U2.123" )
				)
				( pin "vss(55)"
					( attribute "PN" "120"
						( Origin gPackager )
					)
					( objectStatus "J6U2.120" )
				)
				( pin "vss(56)"
					( attribute "PN" "118"
						( Origin gPackager )
					)
					( objectStatus "J6U2.118" )
				)
				( pin "vss(57)"
					( attribute "PN" "116"
						( Origin gPackager )
					)
					( objectStatus "J6U2.116" )
				)
				( pin "vss(58)"
					( attribute "PN" "114"
						( Origin gPackager )
					)
					( objectStatus "J6U2.114" )
				)
				( pin "vss(59)"
					( attribute "PN" "112"
						( Origin gPackager )
					)
					( objectStatus "J6U2.112" )
				)
				( pin "vss(60)"
					( attribute "PN" "109"
						( Origin gPackager )
					)
					( objectStatus "J6U2.109" )
				)
				( pin "vss(61)"
					( attribute "PN" "107"
						( Origin gPackager )
					)
					( objectStatus "J6U2.107" )
				)
				( pin "vss(62)"
					( attribute "PN" "105"
						( Origin gPackager )
					)
					( objectStatus "J6U2.105" )
				)
				( pin "vss(63)"
					( attribute "PN" "103"
						( Origin gPackager )
					)
					( objectStatus "J6U2.103" )
				)
				( pin "vss(64)"
					( attribute "PN" "101"
						( Origin gPackager )
					)
					( objectStatus "J6U2.101" )
				)
				( pin "vss(65)"
					( attribute "PN" "98"
						( Origin gPackager )
					)
					( objectStatus "J6U2.98" )
				)
				( pin "vss(66)"
					( attribute "PN" "96"
						( Origin gPackager )
					)
					( objectStatus "J6U2.96" )
				)
				( pin "vss(67)"
					( attribute "PN" "94"
						( Origin gPackager )
					)
					( objectStatus "J6U2.94" )
				)
				( pin "vss(68)"
					( attribute "PN" "57"
						( Origin gPackager )
					)
					( objectStatus "J6U2.57" )
				)
				( pin "vss(69)"
					( attribute "PN" "55"
						( Origin gPackager )
					)
					( objectStatus "J6U2.55" )
				)
				( pin "vss(70)"
					( attribute "PN" "53"
						( Origin gPackager )
					)
					( objectStatus "J6U2.53" )
				)
				( pin "vss(71)"
					( attribute "PN" "50"
						( Origin gPackager )
					)
					( objectStatus "J6U2.50" )
				)
				( pin "vss(72)"
					( attribute "PN" "48"
						( Origin gPackager )
					)
					( objectStatus "J6U2.48" )
				)
				( pin "vss(73)"
					( attribute "PN" "46"
						( Origin gPackager )
					)
					( objectStatus "J6U2.46" )
				)
				( pin "vss(74)"
					( attribute "PN" "44"
						( Origin gPackager )
					)
					( objectStatus "J6U2.44" )
				)
				( pin "vss(75)"
					( attribute "PN" "42"
						( Origin gPackager )
					)
					( objectStatus "J6U2.42" )
				)
				( pin "vss(76)"
					( attribute "PN" "39"
						( Origin gPackager )
					)
					( objectStatus "J6U2.39" )
				)
				( pin "vss(77)"
					( attribute "PN" "37"
						( Origin gPackager )
					)
					( objectStatus "J6U2.37" )
				)
				( pin "vss(78)"
					( attribute "PN" "35"
						( Origin gPackager )
					)
					( objectStatus "J6U2.35" )
				)
				( pin "vss(79)"
					( attribute "PN" "33"
						( Origin gPackager )
					)
					( objectStatus "J6U2.33" )
				)
				( pin "vss(80)"
					( attribute "PN" "31"
						( Origin gPackager )
					)
					( objectStatus "J6U2.31" )
				)
				( pin "vss(81)"
					( attribute "PN" "28"
						( Origin gPackager )
					)
					( objectStatus "J6U2.28" )
				)
				( pin "vss(82)"
					( attribute "PN" "26"
						( Origin gPackager )
					)
					( objectStatus "J6U2.26" )
				)
				( pin "vss(83)"
					( attribute "PN" "24"
						( Origin gPackager )
					)
					( objectStatus "J6U2.24" )
				)
				( pin "vss(84)"
					( attribute "PN" "22"
						( Origin gPackager )
					)
					( objectStatus "J6U2.22" )
				)
				( pin "vss(85)"
					( attribute "PN" "20"
						( Origin gPackager )
					)
					( objectStatus "J6U2.20" )
				)
				( pin "vss(86)"
					( attribute "PN" "17"
						( Origin gPackager )
					)
					( objectStatus "J6U2.17" )
				)
				( pin "vss(87)"
					( attribute "PN" "15"
						( Origin gPackager )
					)
					( objectStatus "J6U2.15" )
				)
				( pin "vss(88)"
					( attribute "PN" "13"
						( Origin gPackager )
					)
					( objectStatus "J6U2.13" )
				)
				( pin "vss(89)"
					( attribute "PN" "11"
						( Origin gPackager )
					)
					( objectStatus "J6U2.11" )
				)
				( pin "vss(90)"
					( attribute "PN" "9"
						( Origin gPackager )
					)
					( objectStatus "J6U2.9" )
				)
				( pin "vss(91)"
					( attribute "PN" "6"
						( Origin gPackager )
					)
					( objectStatus "J6U2.6" )
				)
				( pin "vss(92)"
					( attribute "PN" "4"
						( Origin gPackager )
					)
					( objectStatus "J6U2.4" )
				)
				( pin "vss(93)"
					( attribute "PN" "2"
						( Origin gPackager )
					)
					( objectStatus "J6U2.2" )
				)
			)
			( gate "@baseboard_fab2_lib.baseboard_fab2(sch_1):page48_i61"
				( attribute "BOM_COST" "MEM"
					( Origin gFrontEnd )
				)
				( attribute "CDS_LIB" "mstr_sconn"
					( Origin gPackager )
				)
				( attribute "CDS_LOCATION" "J6U2"
					( Origin gPackager )
				)
				( attribute "CDS_SEC" "2"
					( Origin gPackager )
				)
				( attribute "LOCATION" "J6U2"
					( Origin gFrontEnd )
				)
				( attribute "MATERIAL" "SCONN"
					( Origin gFrontEnd )
				)
				( attribute "PACK_TYPE" "PIP"
					( Origin gFrontEnd )
				)
				( attribute "PART_NUMBER" "H44441-003"
					( Origin gFrontEnd )
				)
				( attribute "PHYS_PAGE" "48"
					( Origin gFrontEnd )
				)
				( attribute "ROOM" "DDR4_CH_C1"
					( Origin gFrontEnd )
				)
				( attribute "ROT" "0"
					( Origin gFrontEnd )
				)
				( attribute "SEC" "2"
					( Origin gFrontEnd )
				)
				( attribute "SEC_TYPE" "PIP"
					( Origin gFrontEnd )
				)
				( attribute "VER" "2"
					( Origin gFrontEnd )
				)
				( attribute "XY" "(0,4300)"
					( Origin gFrontEnd )
				)
				( attribute "CHIPS_PART_NAME" "SCONN288_H44441003"
					( Origin gPackager )
				)
				( attribute "CDS_PART_NAME" "SCONN288_H44441003_PIP-SCONN,HA"
					( Origin gPackager )
				)
				( objectStatus "J6U2" )
				( pin "dqs0n"
					( attribute "PN" "152"
						( Origin gPackager )
					)
					( objectStatus "J6U2.152" )
				)
				( pin "dqs0p"
					( attribute "PN" "153"
						( Origin gPackager )
					)
					( objectStatus "J6U2.153" )
				)
				( pin "dqs1n"
					( attribute "PN" "163"
						( Origin gPackager )
					)
					( objectStatus "J6U2.163" )
				)
				( pin "dqs1p"
					( attribute "PN" "164"
						( Origin gPackager )
					)
					( objectStatus "J6U2.164" )
				)
				( pin "dqs2n"
					( attribute "PN" "174"
						( Origin gPackager )
					)
					( objectStatus "J6U2.174" )
				)
				( pin "dqs2p"
					( attribute "PN" "175"
						( Origin gPackager )
					)
					( objectStatus "J6U2.175" )
				)
				( pin "dqs3n"
					( attribute "PN" "185"
						( Origin gPackager )
					)
					( objectStatus "J6U2.185" )
				)
				( pin "dqs3p"
					( attribute "PN" "186"
						( Origin gPackager )
					)
					( objectStatus "J6U2.186" )
				)
				( pin "dqs4n"
					( attribute "PN" "244"
						( Origin gPackager )
					)
					( objectStatus "J6U2.244" )
				)
				( pin "dqs4p"
					( attribute "PN" "245"
						( Origin gPackager )
					)
					( objectStatus "J6U2.245" )
				)
				( pin "dqs5n"
					( attribute "PN" "255"
						( Origin gPackager )
					)
					( objectStatus "J6U2.255" )
				)
				( pin "dqs5p"
					( attribute "PN" "256"
						( Origin gPackager )
					)
					( objectStatus "J6U2.256" )
				)
				( pin "dqs6n"
					( attribute "PN" "266"
						( Origin gPackager )
					)
					( objectStatus "J6U2.266" )
				)
				( pin "dqs6p"
					( attribute "PN" "267"
						( Origin gPackager )
					)
					( objectStatus "J6U2.267" )
				)
				( pin "dqs7n"
					( attribute "PN" "277"
						( Origin gPackager )
					)
					( objectStatus "J6U2.277" )
				)
				( pin "dqs7p"
					( attribute "PN" "278"
						( Origin gPackager )
					)
					( objectStatus "J6U2.278" )
				)
				( pin "dqs8n"
					( attribute "PN" "196"
						( Origin gPackager )
					)
					( objectStatus "J6U2.196" )
				)
				( pin "dqs8p"
					( attribute "PN" "197"
						( Origin gPackager )
					)
					( objectStatus "J6U2.197" )
				)
				( pin "dqs9n"
					( attribute "PN" "8"
						( Origin gPackager )
					)
					( objectStatus "J6U2.8" )
				)
				( pin "dqs9p"
					( attribute "PN" "7"
						( Origin gPackager )
					)
					( objectStatus "J6U2.7" )
				)
				( pin "dqs10n"
					( attribute "PN" "19"
						( Origin gPackager )
					)
					( objectStatus "J6U2.19" )
				)
				( pin "dqs10p"
					( attribute "PN" "18"
						( Origin gPackager )
					)
					( objectStatus "J6U2.18" )
				)
				( pin "dqs11n"
					( attribute "PN" "30"
						( Origin gPackager )
					)
					( objectStatus "J6U2.30" )
				)
				( pin "dqs11p"
					( attribute "PN" "29"
						( Origin gPackager )
					)
					( objectStatus "J6U2.29" )
				)
				( pin "dqs12n"
					( attribute "PN" "41"
						( Origin gPackager )
					)
					( objectStatus "J6U2.41" )
				)
				( pin "dqs12p"
					( attribute "PN" "40"
						( Origin gPackager )
					)
					( objectStatus "J6U2.40" )
				)
				( pin "dqs13n"
					( attribute "PN" "100"
						( Origin gPackager )
					)
					( objectStatus "J6U2.100" )
				)
				( pin "dqs13p"
					( attribute "PN" "99"
						( Origin gPackager )
					)
					( objectStatus "J6U2.99" )
				)
				( pin "dqs14n"
					( attribute "PN" "111"
						( Origin gPackager )
					)
					( objectStatus "J6U2.111" )
				)
				( pin "dqs14p"
					( attribute "PN" "110"
						( Origin gPackager )
					)
					( objectStatus "J6U2.110" )
				)
				( pin "dqs15n"
					( attribute "PN" "122"
						( Origin gPackager )
					)
					( objectStatus "J6U2.122" )
				)
				( pin "dqs15p"
					( attribute "PN" "121"
						( Origin gPackager )
					)
					( objectStatus "J6U2.121" )
				)
				( pin "dqs16n"
					( attribute "PN" "133"
						( Origin gPackager )
					)
					( objectStatus "J6U2.133" )
				)
				( pin "dqs16p"
					( attribute "PN" "132"
						( Origin gPackager )
					)
					( objectStatus "J6U2.132" )
				)
				( pin "dqs17n"
					( attribute "PN" "52"
						( Origin gPackager )
					)
					( objectStatus "J6U2.52" )
				)
				( pin "dqs17p"
					( attribute "PN" "51"
						( Origin gPackager )
					)
					( objectStatus "J6U2.51" )
				)
			)
			( gate "@baseboard_fab2_lib.baseboard_fab2(sch_1):page48_i111"
				( attribute "BOM_COST" "MEM"
					( Origin gFrontEnd )
				)
				( attribute "CDS_LIB" "mstr_sconn"
					( Origin gPackager )
				)
				( attribute "CDS_LOCATION" "J6U2"
					( Origin gPackager )
				)
				( attribute "CDS_SEC" "1"
					( Origin gPackager )
				)
				( attribute "LOCATION" "J6U2"
					( Origin gFrontEnd )
				)
				( attribute "MATERIAL" "SCONN"
					( Origin gFrontEnd )
				)
				( attribute "PACK_TYPE" "PIP"
					( Origin gFrontEnd )
				)
				( attribute "PART_NUMBER" "H44441-003"
					( Origin gFrontEnd )
				)
				( attribute "PHYS_PAGE" "48"
					( Origin gFrontEnd )
				)
				( attribute "ROOM" "DDR4_CH_C1"
					( Origin gFrontEnd )
				)
				( attribute "ROT" "0"
					( Origin gFrontEnd )
				)
				( attribute "SEC" "1"
					( Origin gFrontEnd )
				)
				( attribute "SEC_TYPE" "PIP"
					( Origin gFrontEnd )
				)
				( attribute "VER" "1"
					( Origin gFrontEnd )
				)
				( attribute "XY" "(-2400,3200)"
					( Origin gFrontEnd )
				)
				( attribute "CHIPS_PART_NAME" "SCONN288_H44441003"
					( Origin gPackager )
				)
				( attribute "CDS_PART_NAME" "SCONN288_H44441003_PIP-SCONN,HA"
					( Origin gPackager )
				)
				( objectStatus "J6U2" )
				( pin "a0"
					( attribute "PN" "79"
						( Origin gPackager )
					)
					( objectStatus "J6U2.79" )
				)
				( pin "a1"
					( attribute "PN" "72"
						( Origin gPackager )
					)
					( objectStatus "J6U2.72" )
				)
				( pin "a2"
					( attribute "PN" "216"
						( Origin gPackager )
					)
					( objectStatus "J6U2.216" )
				)
				( pin "a3"
					( attribute "PN" "71"
						( Origin gPackager )
					)
					( objectStatus "J6U2.71" )
				)
				( pin "a4"
					( attribute "PN" "214"
						( Origin gPackager )
					)
					( objectStatus "J6U2.214" )
				)
				( pin "a5"
					( attribute "PN" "213"
						( Origin gPackager )
					)
					( objectStatus "J6U2.213" )
				)
				( pin "a6"
					( attribute "PN" "69"
						( Origin gPackager )
					)
					( objectStatus "J6U2.69" )
				)
				( pin "a7"
					( attribute "PN" "211"
						( Origin gPackager )
					)
					( objectStatus "J6U2.211" )
				)
				( pin "a8"
					( attribute "PN" "68"
						( Origin gPackager )
					)
					( objectStatus "J6U2.68" )
				)
				( pin "a9"
					( attribute "PN" "66"
						( Origin gPackager )
					)
					( objectStatus "J6U2.66" )
				)
				( pin "a10"
					( attribute "PN" "225"
						( Origin gPackager )
					)
					( objectStatus "J6U2.225" )
				)
				( pin "a11"
					( attribute "PN" "210"
						( Origin gPackager )
					)
					( objectStatus "J6U2.210" )
				)
				( pin "a12"
					( attribute "PN" "65"
						( Origin gPackager )
					)
					( objectStatus "J6U2.65" )
				)
				( pin "a13"
					( attribute "PN" "232"
						( Origin gPackager )
					)
					( objectStatus "J6U2.232" )
				)
				( pin "a14_we_n"
					( attribute "PN" "228"
						( Origin gPackager )
					)
					( objectStatus "J6U2.228" )
				)
				( pin "a15_cas_n"
					( attribute "PN" "86"
						( Origin gPackager )
					)
					( objectStatus "J6U2.86" )
				)
				( pin "a16_ras_n"
					( attribute "PN" "82"
						( Origin gPackager )
					)
					( objectStatus "J6U2.82" )
				)
				( pin "a17"
					( attribute "PN" "234"
						( Origin gPackager )
					)
					( objectStatus "J6U2.234" )
				)
				( pin "act_n"
					( attribute "PN" "62"
						( Origin gPackager )
					)
					( objectStatus "J6U2.62" )
				)
				( pin "alert_n"
					( attribute "PN" "208"
						( Origin gPackager )
					)
					( objectStatus "J6U2.208" )
				)
				( pin "ba(0)"
					( attribute "PN" "81"
						( Origin gPackager )
					)
					( objectStatus "J6U2.81" )
				)
				( pin "ba(1)"
					( attribute "PN" "224"
						( Origin gPackager )
					)
					( objectStatus "J6U2.224" )
				)
				( pin "bg(0)"
					( attribute "PN" "63"
						( Origin gPackager )
					)
					( objectStatus "J6U2.63" )
				)
				( pin "bg(1)"
					( attribute "PN" "207"
						( Origin gPackager )
					)
					( objectStatus "J6U2.207" )
				)
				( pin "c(2)"
					( attribute "PN" "235"
						( Origin gPackager )
					)
					( objectStatus "J6U2.235" )
				)
				( pin "cb(0)"
					( attribute "PN" "49"
						( Origin gPackager )
					)
					( objectStatus "J6U2.49" )
				)
				( pin "cb(1)"
					( attribute "PN" "194"
						( Origin gPackager )
					)
					( objectStatus "J6U2.194" )
				)
				( pin "cb(2)"
					( attribute "PN" "56"
						( Origin gPackager )
					)
					( objectStatus "J6U2.56" )
				)
				( pin "cb(3)"
					( attribute "PN" "201"
						( Origin gPackager )
					)
					( objectStatus "J6U2.201" )
				)
				( pin "cb(4)"
					( attribute "PN" "47"
						( Origin gPackager )
					)
					( objectStatus "J6U2.47" )
				)
				( pin "cb(5)"
					( attribute "PN" "192"
						( Origin gPackager )
					)
					( objectStatus "J6U2.192" )
				)
				( pin "cb(6)"
					( attribute "PN" "54"
						( Origin gPackager )
					)
					( objectStatus "J6U2.54" )
				)
				( pin "cb(7)"
					( attribute "PN" "199"
						( Origin gPackager )
					)
					( objectStatus "J6U2.199" )
				)
				( pin "ck0n"
					( attribute "PN" "75"
						( Origin gPackager )
					)
					( objectStatus "J6U2.75" )
				)
				( pin "ck0p"
					( attribute "PN" "74"
						( Origin gPackager )
					)
					( objectStatus "J6U2.74" )
				)
				( pin "ck1n"
					( attribute "PN" "219"
						( Origin gPackager )
					)
					( objectStatus "J6U2.219" )
				)
				( pin "ck1p"
					( attribute "PN" "218"
						( Origin gPackager )
					)
					( objectStatus "J6U2.218" )
				)
				( pin "cke(0)"
					( attribute "PN" "60"
						( Origin gPackager )
					)
					( objectStatus "J6U2.60" )
				)
				( pin "cke(1)"
					( attribute "PN" "203"
						( Origin gPackager )
					)
					( objectStatus "J6U2.203" )
				)
				( pin "dq(0)"
					( attribute "PN" "5"
						( Origin gPackager )
					)
					( objectStatus "J6U2.5" )
				)
				( pin "dq(1)"
					( attribute "PN" "150"
						( Origin gPackager )
					)
					( objectStatus "J6U2.150" )
				)
				( pin "dq(2)"
					( attribute "PN" "12"
						( Origin gPackager )
					)
					( objectStatus "J6U2.12" )
				)
				( pin "dq(3)"
					( attribute "PN" "157"
						( Origin gPackager )
					)
					( objectStatus "J6U2.157" )
				)
				( pin "dq(4)"
					( attribute "PN" "3"
						( Origin gPackager )
					)
					( objectStatus "J6U2.3" )
				)
				( pin "dq(5)"
					( attribute "PN" "148"
						( Origin gPackager )
					)
					( objectStatus "J6U2.148" )
				)
				( pin "dq(6)"
					( attribute "PN" "10"
						( Origin gPackager )
					)
					( objectStatus "J6U2.10" )
				)
				( pin "dq(7)"
					( attribute "PN" "155"
						( Origin gPackager )
					)
					( objectStatus "J6U2.155" )
				)
				( pin "dq(8)"
					( attribute "PN" "16"
						( Origin gPackager )
					)
					( objectStatus "J6U2.16" )
				)
				( pin "dq(9)"
					( attribute "PN" "161"
						( Origin gPackager )
					)
					( objectStatus "J6U2.161" )
				)
				( pin "dq(10)"
					( attribute "PN" "23"
						( Origin gPackager )
					)
					( objectStatus "J6U2.23" )
				)
				( pin "dq(11)"
					( attribute "PN" "168"
						( Origin gPackager )
					)
					( objectStatus "J6U2.168" )
				)
				( pin "dq(12)"
					( attribute "PN" "14"
						( Origin gPackager )
					)
					( objectStatus "J6U2.14" )
				)
				( pin "dq(13)"
					( attribute "PN" "159"
						( Origin gPackager )
					)
					( objectStatus "J6U2.159" )
				)
				( pin "dq(14)"
					( attribute "PN" "21"
						( Origin gPackager )
					)
					( objectStatus "J6U2.21" )
				)
				( pin "dq(15)"
					( attribute "PN" "166"
						( Origin gPackager )
					)
					( objectStatus "J6U2.166" )
				)
				( pin "dq(16)"
					( attribute "PN" "27"
						( Origin gPackager )
					)
					( objectStatus "J6U2.27" )
				)
				( pin "dq(17)"
					( attribute "PN" "172"
						( Origin gPackager )
					)
					( objectStatus "J6U2.172" )
				)
				( pin "dq(18)"
					( attribute "PN" "34"
						( Origin gPackager )
					)
					( objectStatus "J6U2.34" )
				)
				( pin "dq(19)"
					( attribute "PN" "179"
						( Origin gPackager )
					)
					( objectStatus "J6U2.179" )
				)
				( pin "dq(20)"
					( attribute "PN" "25"
						( Origin gPackager )
					)
					( objectStatus "J6U2.25" )
				)
				( pin "dq(21)"
					( attribute "PN" "170"
						( Origin gPackager )
					)
					( objectStatus "J6U2.170" )
				)
				( pin "dq(22)"
					( attribute "PN" "32"
						( Origin gPackager )
					)
					( objectStatus "J6U2.32" )
				)
				( pin "dq(23)"
					( attribute "PN" "177"
						( Origin gPackager )
					)
					( objectStatus "J6U2.177" )
				)
				( pin "dq(24)"
					( attribute "PN" "38"
						( Origin gPackager )
					)
					( objectStatus "J6U2.38" )
				)
				( pin "dq(25)"
					( attribute "PN" "183"
						( Origin gPackager )
					)
					( objectStatus "J6U2.183" )
				)
				( pin "dq(26)"
					( attribute "PN" "45"
						( Origin gPackager )
					)
					( objectStatus "J6U2.45" )
				)
				( pin "dq(27)"
					( attribute "PN" "190"
						( Origin gPackager )
					)
					( objectStatus "J6U2.190" )
				)
				( pin "dq(28)"
					( attribute "PN" "36"
						( Origin gPackager )
					)
					( objectStatus "J6U2.36" )
				)
				( pin "dq(29)"
					( attribute "PN" "181"
						( Origin gPackager )
					)
					( objectStatus "J6U2.181" )
				)
				( pin "dq(30)"
					( attribute "PN" "43"
						( Origin gPackager )
					)
					( objectStatus "J6U2.43" )
				)
				( pin "dq(31)"
					( attribute "PN" "188"
						( Origin gPackager )
					)
					( objectStatus "J6U2.188" )
				)
				( pin "dq(32)"
					( attribute "PN" "97"
						( Origin gPackager )
					)
					( objectStatus "J6U2.97" )
				)
				( pin "dq(33)"
					( attribute "PN" "242"
						( Origin gPackager )
					)
					( objectStatus "J6U2.242" )
				)
				( pin "dq(34)"
					( attribute "PN" "104"
						( Origin gPackager )
					)
					( objectStatus "J6U2.104" )
				)
				( pin "dq(35)"
					( attribute "PN" "249"
						( Origin gPackager )
					)
					( objectStatus "J6U2.249" )
				)
				( pin "dq(36)"
					( attribute "PN" "95"
						( Origin gPackager )
					)
					( objectStatus "J6U2.95" )
				)
				( pin "dq(37)"
					( attribute "PN" "240"
						( Origin gPackager )
					)
					( objectStatus "J6U2.240" )
				)
				( pin "dq(38)"
					( attribute "PN" "102"
						( Origin gPackager )
					)
					( objectStatus "J6U2.102" )
				)
				( pin "dq(39)"
					( attribute "PN" "247"
						( Origin gPackager )
					)
					( objectStatus "J6U2.247" )
				)
				( pin "dq(40)"
					( attribute "PN" "108"
						( Origin gPackager )
					)
					( objectStatus "J6U2.108" )
				)
				( pin "dq(41)"
					( attribute "PN" "253"
						( Origin gPackager )
					)
					( objectStatus "J6U2.253" )
				)
				( pin "dq(42)"
					( attribute "PN" "115"
						( Origin gPackager )
					)
					( objectStatus "J6U2.115" )
				)
				( pin "dq(43)"
					( attribute "PN" "260"
						( Origin gPackager )
					)
					( objectStatus "J6U2.260" )
				)
				( pin "dq(44)"
					( attribute "PN" "106"
						( Origin gPackager )
					)
					( objectStatus "J6U2.106" )
				)
				( pin "dq(45)"
					( attribute "PN" "251"
						( Origin gPackager )
					)
					( objectStatus "J6U2.251" )
				)
				( pin "dq(46)"
					( attribute "PN" "113"
						( Origin gPackager )
					)
					( objectStatus "J6U2.113" )
				)
				( pin "dq(47)"
					( attribute "PN" "258"
						( Origin gPackager )
					)
					( objectStatus "J6U2.258" )
				)
				( pin "dq(48)"
					( attribute "PN" "119"
						( Origin gPackager )
					)
					( objectStatus "J6U2.119" )
				)
				( pin "dq(49)"
					( attribute "PN" "264"
						( Origin gPackager )
					)
					( objectStatus "J6U2.264" )
				)
				( pin "dq(50)"
					( attribute "PN" "126"
						( Origin gPackager )
					)
					( objectStatus "J6U2.126" )
				)
				( pin "dq(51)"
					( attribute "PN" "271"
						( Origin gPackager )
					)
					( objectStatus "J6U2.271" )
				)
				( pin "dq(52)"
					( attribute "PN" "117"
						( Origin gPackager )
					)
					( objectStatus "J6U2.117" )
				)
				( pin "dq(53)"
					( attribute "PN" "262"
						( Origin gPackager )
					)
					( objectStatus "J6U2.262" )
				)
				( pin "dq(54)"
					( attribute "PN" "124"
						( Origin gPackager )
					)
					( objectStatus "J6U2.124" )
				)
				( pin "dq(55)"
					( attribute "PN" "269"
						( Origin gPackager )
					)
					( objectStatus "J6U2.269" )
				)
				( pin "dq(56)"
					( attribute "PN" "130"
						( Origin gPackager )
					)
					( objectStatus "J6U2.130" )
				)
				( pin "dq(57)"
					( attribute "PN" "275"
						( Origin gPackager )
					)
					( objectStatus "J6U2.275" )
				)
				( pin "dq(58)"
					( attribute "PN" "137"
						( Origin gPackager )
					)
					( objectStatus "J6U2.137" )
				)
				( pin "dq(59)"
					( attribute "PN" "282"
						( Origin gPackager )
					)
					( objectStatus "J6U2.282" )
				)
				( pin "dq(60)"
					( attribute "PN" "128"
						( Origin gPackager )
					)
					( objectStatus "J6U2.128" )
				)
				( pin "dq(61)"
					( attribute "PN" "273"
						( Origin gPackager )
					)
					( objectStatus "J6U2.273" )
				)
				( pin "dq(62)"
					( attribute "PN" "135"
						( Origin gPackager )
					)
					( objectStatus "J6U2.135" )
				)
				( pin "dq(63)"
					( attribute "PN" "280"
						( Origin gPackager )
					)
					( objectStatus "J6U2.280" )
				)
				( pin "event_n"
					( attribute "PN" "78"
						( Origin gPackager )
					)
					( objectStatus "J6U2.78" )
				)
				( pin "odt(0)"
					( attribute "PN" "87"
						( Origin gPackager )
					)
					( objectStatus "J6U2.87" )
				)
				( pin "odt(1)"
					( attribute "PN" "91"
						( Origin gPackager )
					)
					( objectStatus "J6U2.91" )
				)
				( pin "par"
					( attribute "PN" "222"
						( Origin gPackager )
					)
					( objectStatus "J6U2.222" )
				)
				( pin "reset_n"
					( attribute "PN" "58"
						( Origin gPackager )
					)
					( objectStatus "J6U2.58" )
				)
				( pin "rfu(0)"
					( attribute "PN" "205"
						( Origin gPackager )
					)
					( objectStatus "J6U2.205" )
				)
				( pin "rfu(1)"
					( attribute "PN" "227"
						( Origin gPackager )
					)
					( objectStatus "J6U2.227" )
				)
				( pin "rfu(2)"
					( attribute "PN" "144"
						( Origin gPackager )
					)
					( objectStatus "J6U2.144" )
				)
				( pin "s0_n"
					( attribute "PN" "84"
						( Origin gPackager )
					)
					( objectStatus "J6U2.84" )
				)
				( pin "s1_n"
					( attribute "PN" "89"
						( Origin gPackager )
					)
					( objectStatus "J6U2.89" )
				)
				( pin "s2_n_c(0)"
					( attribute "PN" "93"
						( Origin gPackager )
					)
					( objectStatus "J6U2.93" )
				)
				( pin "s3_n_c(1)"
					( attribute "PN" "237"
						( Origin gPackager )
					)
					( objectStatus "J6U2.237" )
				)
				( pin "sa(0)"
					( attribute "PN" "139"
						( Origin gPackager )
					)
					( objectStatus "J6U2.139" )
				)
				( pin "sa(1)"
					( attribute "PN" "140"
						( Origin gPackager )
					)
					( objectStatus "J6U2.140" )
				)
				( pin "sa(2)"
					( attribute "PN" "238"
						( Origin gPackager )
					)
					( objectStatus "J6U2.238" )
				)
				( pin "save_n_nc"
					( attribute "PN" "230"
						( Origin gPackager )
					)
					( objectStatus "J6U2.230" )
				)
				( pin "scl"
					( attribute "PN" "141"
						( Origin gPackager )
					)
					( objectStatus "J6U2.141" )
				)
				( pin "sda"
					( attribute "PN" "285"
						( Origin gPackager )
					)
					( objectStatus "J6U2.285" )
				)
				( pin "vddspd"
					( attribute "PN" "284"
						( Origin gPackager )
					)
					( objectStatus "J6U2.284" )
				)
				( pin "vrefca"
					( attribute "PN" "146"
						( Origin gPackager )
					)
					( objectStatus "J6U2.146" )
				)
			)
			( gate "@baseboard_fab2_lib.baseboard_fab2(sch_1):page48_i171"
				( attribute "BOM_COST" "MEM"
					( Origin gFrontEnd )
				)
				( attribute "CDS_LIB" "mstr_sconn"
					( Origin gPackager )
				)
				( attribute "CDS_LOCATION" "J6U2"
					( Origin gPackager )
				)
				( attribute "CDS_SEC" "4"
					( Origin gPackager )
				)
				( attribute "LOCATION" "J6U2"
					( Origin gFrontEnd )
				)
				( attribute "MATERIAL" "SCONN"
					( Origin gFrontEnd )
				)
				( attribute "PACK_TYPE" "PIP"
					( Origin gFrontEnd )
				)
				( attribute "PART_NUMBER" "H44441-003"
					( Origin gFrontEnd )
				)
				( attribute "PHYS_PAGE" "48"
					( Origin gFrontEnd )
				)
				( attribute "ROOM" "DDR4_CH_C1"
					( Origin gFrontEnd )
				)
				( attribute "ROT" "0"
					( Origin gFrontEnd )
				)
				( attribute "SEC" "4"
					( Origin gFrontEnd )
				)
				( attribute "SEC_TYPE" "PIP"
					( Origin gFrontEnd )
				)
				( attribute "VER" "4"
					( Origin gFrontEnd )
				)
				( attribute "XY" "(-100,2000)"
					( Origin gFrontEnd )
				)
				( attribute "CHIPS_PART_NAME" "SCONN288_H44441003"
					( Origin gPackager )
				)
				( attribute "CDS_PART_NAME" "SCONN288_H44441003_PIP-SCONN,HA"
					( Origin gPackager )
				)
				( objectStatus "J6U2" )
				( pin "\12v\(0)"
					( attribute "PN" "145"
						( Origin gPackager )
					)
					( objectStatus "J6U2.145" )
				)
				( pin "\12v\(1)"
					( attribute "PN" "1"
						( Origin gPackager )
					)
					( objectStatus "J6U2.1" )
				)
				( pin "vdd(0)"
					( attribute "PN" "236"
						( Origin gPackager )
					)
					( objectStatus "J6U2.236" )
				)
				( pin "vdd(1)"
					( attribute "PN" "233"
						( Origin gPackager )
					)
					( objectStatus "J6U2.233" )
				)
				( pin "vdd(2)"
					( attribute "PN" "231"
						( Origin gPackager )
					)
					( objectStatus "J6U2.231" )
				)
				( pin "vdd(3)"
					( attribute "PN" "229"
						( Origin gPackager )
					)
					( objectStatus "J6U2.229" )
				)
				( pin "vdd(4)"
					( attribute "PN" "226"
						( Origin gPackager )
					)
					( objectStatus "J6U2.226" )
				)
				( pin "vdd(5)"
					( attribute "PN" "223"
						( Origin gPackager )
					)
					( objectStatus "J6U2.223" )
				)
				( pin "vdd(6)"
					( attribute "PN" "220"
						( Origin gPackager )
					)
					( objectStatus "J6U2.220" )
				)
				( pin "vdd(7)"
					( attribute "PN" "217"
						( Origin gPackager )
					)
					( objectStatus "J6U2.217" )
				)
				( pin "vdd(8)"
					( attribute "PN" "215"
						( Origin gPackager )
					)
					( objectStatus "J6U2.215" )
				)
				( pin "vdd(9)"
					( attribute "PN" "212"
						( Origin gPackager )
					)
					( objectStatus "J6U2.212" )
				)
				( pin "vdd(10)"
					( attribute "PN" "209"
						( Origin gPackager )
					)
					( objectStatus "J6U2.209" )
				)
				( pin "vdd(11)"
					( attribute "PN" "206"
						( Origin gPackager )
					)
					( objectStatus "J6U2.206" )
				)
				( pin "vdd(12)"
					( attribute "PN" "204"
						( Origin gPackager )
					)
					( objectStatus "J6U2.204" )
				)
				( pin "vdd(13)"
					( attribute "PN" "92"
						( Origin gPackager )
					)
					( objectStatus "J6U2.92" )
				)
				( pin "vdd(14)"
					( attribute "PN" "90"
						( Origin gPackager )
					)
					( objectStatus "J6U2.90" )
				)
				( pin "vdd(15)"
					( attribute "PN" "88"
						( Origin gPackager )
					)
					( objectStatus "J6U2.88" )
				)
				( pin "vdd(16)"
					( attribute "PN" "85"
						( Origin gPackager )
					)
					( objectStatus "J6U2.85" )
				)
				( pin "vdd(17)"
					( attribute "PN" "83"
						( Origin gPackager )
					)
					( objectStatus "J6U2.83" )
				)
				( pin "vdd(18)"
					( attribute "PN" "80"
						( Origin gPackager )
					)
					( objectStatus "J6U2.80" )
				)
				( pin "vdd(19)"
					( attribute "PN" "76"
						( Origin gPackager )
					)
					( objectStatus "J6U2.76" )
				)
				( pin "vdd(20)"
					( attribute "PN" "73"
						( Origin gPackager )
					)
					( objectStatus "J6U2.73" )
				)
				( pin "vdd(21)"
					( attribute "PN" "70"
						( Origin gPackager )
					)
					( objectStatus "J6U2.70" )
				)
				( pin "vdd(22)"
					( attribute "PN" "67"
						( Origin gPackager )
					)
					( objectStatus "J6U2.67" )
				)
				( pin "vdd(23)"
					( attribute "PN" "64"
						( Origin gPackager )
					)
					( objectStatus "J6U2.64" )
				)
				( pin "vdd(24)"
					( attribute "PN" "61"
						( Origin gPackager )
					)
					( objectStatus "J6U2.61" )
				)
				( pin "vdd(25)"
					( attribute "PN" "59"
						( Origin gPackager )
					)
					( objectStatus "J6U2.59" )
				)
				( pin "vpp(0)"
					( attribute "PN" "287"
						( Origin gPackager )
					)
					( objectStatus "J6U2.287" )
				)
				( pin "vpp(1)"
					( attribute "PN" "286"
						( Origin gPackager )
					)
					( objectStatus "J6U2.286" )
				)
				( pin "vpp(2)"
					( attribute "PN" "288"
						( Origin gPackager )
					)
					( objectStatus "J6U2.288" )
				)
				( pin "vpp(3)"
					( attribute "PN" "143"
						( Origin gPackager )
					)
					( objectStatus "J6U2.143" )
				)
				( pin "vpp(4)"
					( attribute "PN" "142"
						( Origin gPackager )
					)
					( objectStatus "J6U2.142" )
				)
				( pin "vtt(0)"
					( attribute "PN" "221"
						( Origin gPackager )
					)
					( objectStatus "J6U2.221" )
				)
				( pin "vtt(1)"
					( attribute "PN" "77"
						( Origin gPackager )
					)
					( objectStatus "J6U2.77" )
				)
			)
			( gate "@baseboard_fab2_lib.baseboard_fab2(sch_1):page48_i176"
				( attribute "BOM_COST" "MEM"
					( Origin gFrontEnd )
				)
				( attribute "CDS_LIB" "dev_discrete"
					( Origin gPackager )
				)
				( attribute "CDS_LOCATION" "C6U17"
					( Origin gPackager )
				)
				( attribute "CDS_SEC" "1"
					( Origin gPackager )
				)
				( attribute "LOCATION" "C6U17"
					( Origin gFrontEnd )
				)
				( attribute "MATERIAL" "X7R"
					( Origin gFrontEnd )
				)
				( attribute "PACK_TYPE" "0402V"
					( Origin gFrontEnd )
				)
				( attribute "PART_NUMBER" "A36096-045"
					( Origin gFrontEnd )
				)
				( attribute "PHYS_PAGE" "48"
					( Origin gFrontEnd )
				)
				( attribute "ROOM" "DDR4_CH_B"
					( Origin gFrontEnd )
				)
				( attribute "ROT" "2"
					( Origin gFrontEnd )
				)
				( attribute "SEC" "1"
					( Origin gFrontEnd )
				)
				( attribute "SEC_TYPE" "0402V"
					( Origin gFrontEnd )
				)
				( attribute "TOLERANCE" "10%"
					( Origin gFrontEnd )
				)
				( attribute "VALUE" "0.01UF"
					( Origin gFrontEnd )
				)
				( attribute "VER" "1"
					( Origin gFrontEnd )
				)
				( attribute "VOLTAGE" "25V"
					( Units "uVoltage" "V" 1.000000)
					( Origin gFrontEnd )
				)
				( attribute "XY" "(-4650,1500)"
					( Origin gFrontEnd )
				)
				( attribute "CHIPS_PART_NAME" "CAP_A"
					( Origin gPackager )
				)
				( attribute "CDS_PART_NAME" "CAP_A_0402V-0.01UF,25V,10%,X7RA"
					( Origin gPackager )
				)
				( objectStatus "C6U17" )
				( pin "a"
					( attribute "PN" "1"
						( Origin gPackager )
					)
					( objectStatus "C6U17.1" )
				)
				( pin "b"
					( attribute "PN" "2"
						( Origin gPackager )
					)
					( objectStatus "C6U17.2" )
				)
			)
			( gate "@baseboard_fab2_lib.baseboard_fab2(sch_1):page49_i43"
				( attribute "BOM_COST" "MEM"
					( Origin gFrontEnd )
				)
				( attribute "CDS_LIB" "mstr_sconn"
					( Origin gPackager )
				)
				( attribute "CDS_LOCATION" "J4B1"
					( Origin gPackager )
				)
				( attribute "CDS_SEC" "3"
					( Origin gPackager )
				)
				( attribute "LOCATION" "J4B1"
					( Origin gFrontEnd )
				)
				( attribute "MATERIAL" "SCONN"
					( Origin gFrontEnd )
				)
				( attribute "PACK_TYPE" "PIP"
					( Origin gFrontEnd )
				)
				( attribute "PART_NUMBER" "H44441-004"
					( Origin gFrontEnd )
				)
				( attribute "PHYS_PAGE" "49"
					( Origin gFrontEnd )
				)
				( attribute "ROOM" "DDR4_CH_D"
					( Origin gFrontEnd )
				)
				( attribute "ROT" "0"
					( Origin gFrontEnd )
				)
				( attribute "SEC" "3"
					( Origin gFrontEnd )
				)
				( attribute "SEC_TYPE" "PIP"
					( Origin gFrontEnd )
				)
				( attribute "VER" "3"
					( Origin gFrontEnd )
				)
				( attribute "XY" "(1800,2450)"
					( Origin gFrontEnd )
				)
				( attribute "CHIPS_PART_NAME" "SCONN288_H44441004"
					( Origin gPackager )
				)
				( attribute "CDS_PART_NAME" "SCONN288_H44441004_PIP-SCONN,HA"
					( Origin gPackager )
				)
				( objectStatus "J4B1" )
				( pin "vss(0)"
					( attribute "PN" "283"
						( Origin gPackager )
					)
					( objectStatus "J4B1.283" )
				)
				( pin "vss(1)"
					( attribute "PN" "281"
						( Origin gPackager )
					)
					( objectStatus "J4B1.281" )
				)
				( pin "vss(2)"
					( attribute "PN" "279"
						( Origin gPackager )
					)
					( objectStatus "J4B1.279" )
				)
				( pin "vss(3)"
					( attribute "PN" "276"
						( Origin gPackager )
					)
					( objectStatus "J4B1.276" )
				)
				( pin "vss(4)"
					( attribute "PN" "274"
						( Origin gPackager )
					)
					( objectStatus "J4B1.274" )
				)
				( pin "vss(5)"
					( attribute "PN" "272"
						( Origin gPackager )
					)
					( objectStatus "J4B1.272" )
				)
				( pin "vss(6)"
					( attribute "PN" "270"
						( Origin gPackager )
					)
					( objectStatus "J4B1.270" )
				)
				( pin "vss(7)"
					( attribute "PN" "268"
						( Origin gPackager )
					)
					( objectStatus "J4B1.268" )
				)
				( pin "vss(8)"
					( attribute "PN" "265"
						( Origin gPackager )
					)
					( objectStatus "J4B1.265" )
				)
				( pin "vss(9)"
					( attribute "PN" "263"
						( Origin gPackager )
					)
					( objectStatus "J4B1.263" )
				)
				( pin "vss(10)"
					( attribute "PN" "261"
						( Origin gPackager )
					)
					( objectStatus "J4B1.261" )
				)
				( pin "vss(11)"
					( attribute "PN" "259"
						( Origin gPackager )
					)
					( objectStatus "J4B1.259" )
				)
				( pin "vss(12)"
					( attribute "PN" "257"
						( Origin gPackager )
					)
					( objectStatus "J4B1.257" )
				)
				( pin "vss(13)"
					( attribute "PN" "254"
						( Origin gPackager )
					)
					( objectStatus "J4B1.254" )
				)
				( pin "vss(14)"
					( attribute "PN" "252"
						( Origin gPackager )
					)
					( objectStatus "J4B1.252" )
				)
				( pin "vss(15)"
					( attribute "PN" "250"
						( Origin gPackager )
					)
					( objectStatus "J4B1.250" )
				)
				( pin "vss(16)"
					( attribute "PN" "248"
						( Origin gPackager )
					)
					( objectStatus "J4B1.248" )
				)
				( pin "vss(17)"
					( attribute "PN" "246"
						( Origin gPackager )
					)
					( objectStatus "J4B1.246" )
				)
				( pin "vss(18)"
					( attribute "PN" "243"
						( Origin gPackager )
					)
					( objectStatus "J4B1.243" )
				)
				( pin "vss(19)"
					( attribute "PN" "241"
						( Origin gPackager )
					)
					( objectStatus "J4B1.241" )
				)
				( pin "vss(20)"
					( attribute "PN" "239"
						( Origin gPackager )
					)
					( objectStatus "J4B1.239" )
				)
				( pin "vss(21)"
					( attribute "PN" "202"
						( Origin gPackager )
					)
					( objectStatus "J4B1.202" )
				)
				( pin "vss(22)"
					( attribute "PN" "200"
						( Origin gPackager )
					)
					( objectStatus "J4B1.200" )
				)
				( pin "vss(23)"
					( attribute "PN" "198"
						( Origin gPackager )
					)
					( objectStatus "J4B1.198" )
				)
				( pin "vss(24)"
					( attribute "PN" "195"
						( Origin gPackager )
					)
					( objectStatus "J4B1.195" )
				)
				( pin "vss(25)"
					( attribute "PN" "193"
						( Origin gPackager )
					)
					( objectStatus "J4B1.193" )
				)
				( pin "vss(26)"
					( attribute "PN" "191"
						( Origin gPackager )
					)
					( objectStatus "J4B1.191" )
				)
				( pin "vss(27)"
					( attribute "PN" "189"
						( Origin gPackager )
					)
					( objectStatus "J4B1.189" )
				)
				( pin "vss(28)"
					( attribute "PN" "187"
						( Origin gPackager )
					)
					( objectStatus "J4B1.187" )
				)
				( pin "vss(29)"
					( attribute "PN" "184"
						( Origin gPackager )
					)
					( objectStatus "J4B1.184" )
				)
				( pin "vss(30)"
					( attribute "PN" "182"
						( Origin gPackager )
					)
					( objectStatus "J4B1.182" )
				)
				( pin "vss(31)"
					( attribute "PN" "180"
						( Origin gPackager )
					)
					( objectStatus "J4B1.180" )
				)
				( pin "vss(32)"
					( attribute "PN" "178"
						( Origin gPackager )
					)
					( objectStatus "J4B1.178" )
				)
				( pin "vss(33)"
					( attribute "PN" "176"
						( Origin gPackager )
					)
					( objectStatus "J4B1.176" )
				)
				( pin "vss(34)"
					( attribute "PN" "173"
						( Origin gPackager )
					)
					( objectStatus "J4B1.173" )
				)
				( pin "vss(35)"
					( attribute "PN" "171"
						( Origin gPackager )
					)
					( objectStatus "J4B1.171" )
				)
				( pin "vss(36)"
					( attribute "PN" "169"
						( Origin gPackager )
					)
					( objectStatus "J4B1.169" )
				)
				( pin "vss(37)"
					( attribute "PN" "167"
						( Origin gPackager )
					)
					( objectStatus "J4B1.167" )
				)
				( pin "vss(38)"
					( attribute "PN" "165"
						( Origin gPackager )
					)
					( objectStatus "J4B1.165" )
				)
				( pin "vss(39)"
					( attribute "PN" "162"
						( Origin gPackager )
					)
					( objectStatus "J4B1.162" )
				)
				( pin "vss(40)"
					( attribute "PN" "160"
						( Origin gPackager )
					)
					( objectStatus "J4B1.160" )
				)
				( pin "vss(41)"
					( attribute "PN" "158"
						( Origin gPackager )
					)
					( objectStatus "J4B1.158" )
				)
				( pin "vss(42)"
					( attribute "PN" "156"
						( Origin gPackager )
					)
					( objectStatus "J4B1.156" )
				)
				( pin "vss(43)"
					( attribute "PN" "154"
						( Origin gPackager )
					)
					( objectStatus "J4B1.154" )
				)
				( pin "vss(44)"
					( attribute "PN" "151"
						( Origin gPackager )
					)
					( objectStatus "J4B1.151" )
				)
				( pin "vss(45)"
					( attribute "PN" "149"
						( Origin gPackager )
					)
					( objectStatus "J4B1.149" )
				)
				( pin "vss(46)"
					( attribute "PN" "147"
						( Origin gPackager )
					)
					( objectStatus "J4B1.147" )
				)
				( pin "vss(47)"
					( attribute "PN" "138"
						( Origin gPackager )
					)
					( objectStatus "J4B1.138" )
				)
				( pin "vss(48)"
					( attribute "PN" "136"
						( Origin gPackager )
					)
					( objectStatus "J4B1.136" )
				)
				( pin "vss(49)"
					( attribute "PN" "134"
						( Origin gPackager )
					)
					( objectStatus "J4B1.134" )
				)
				( pin "vss(50)"
					( attribute "PN" "131"
						( Origin gPackager )
					)
					( objectStatus "J4B1.131" )
				)
				( pin "vss(51)"
					( attribute "PN" "129"
						( Origin gPackager )
					)
					( objectStatus "J4B1.129" )
				)
				( pin "vss(52)"
					( attribute "PN" "127"
						( Origin gPackager )
					)
					( objectStatus "J4B1.127" )
				)
				( pin "vss(53)"
					( attribute "PN" "125"
						( Origin gPackager )
					)
					( objectStatus "J4B1.125" )
				)
				( pin "vss(54)"
					( attribute "PN" "123"
						( Origin gPackager )
					)
					( objectStatus "J4B1.123" )
				)
				( pin "vss(55)"
					( attribute "PN" "120"
						( Origin gPackager )
					)
					( objectStatus "J4B1.120" )
				)
				( pin "vss(56)"
					( attribute "PN" "118"
						( Origin gPackager )
					)
					( objectStatus "J4B1.118" )
				)
				( pin "vss(57)"
					( attribute "PN" "116"
						( Origin gPackager )
					)
					( objectStatus "J4B1.116" )
				)
				( pin "vss(58)"
					( attribute "PN" "114"
						( Origin gPackager )
					)
					( objectStatus "J4B1.114" )
				)
				( pin "vss(59)"
					( attribute "PN" "112"
						( Origin gPackager )
					)
					( objectStatus "J4B1.112" )
				)
				( pin "vss(60)"
					( attribute "PN" "109"
						( Origin gPackager )
					)
					( objectStatus "J4B1.109" )
				)
				( pin "vss(61)"
					( attribute "PN" "107"
						( Origin gPackager )
					)
					( objectStatus "J4B1.107" )
				)
				( pin "vss(62)"
					( attribute "PN" "105"
						( Origin gPackager )
					)
					( objectStatus "J4B1.105" )
				)
				( pin "vss(63)"
					( attribute "PN" "103"
						( Origin gPackager )
					)
					( objectStatus "J4B1.103" )
				)
				( pin "vss(64)"
					( attribute "PN" "101"
						( Origin gPackager )
					)
					( objectStatus "J4B1.101" )
				)
				( pin "vss(65)"
					( attribute "PN" "98"
						( Origin gPackager )
					)
					( objectStatus "J4B1.98" )
				)
				( pin "vss(66)"
					( attribute "PN" "96"
						( Origin gPackager )
					)
					( objectStatus "J4B1.96" )
				)
				( pin "vss(67)"
					( attribute "PN" "94"
						( Origin gPackager )
					)
					( objectStatus "J4B1.94" )
				)
				( pin "vss(68)"
					( attribute "PN" "57"
						( Origin gPackager )
					)
					( objectStatus "J4B1.57" )
				)
				( pin "vss(69)"
					( attribute "PN" "55"
						( Origin gPackager )
					)
					( objectStatus "J4B1.55" )
				)
				( pin "vss(70)"
					( attribute "PN" "53"
						( Origin gPackager )
					)
					( objectStatus "J4B1.53" )
				)
				( pin "vss(71)"
					( attribute "PN" "50"
						( Origin gPackager )
					)
					( objectStatus "J4B1.50" )
				)
				( pin "vss(72)"
					( attribute "PN" "48"
						( Origin gPackager )
					)
					( objectStatus "J4B1.48" )
				)
				( pin "vss(73)"
					( attribute "PN" "46"
						( Origin gPackager )
					)
					( objectStatus "J4B1.46" )
				)
				( pin "vss(74)"
					( attribute "PN" "44"
						( Origin gPackager )
					)
					( objectStatus "J4B1.44" )
				)
				( pin "vss(75)"
					( attribute "PN" "42"
						( Origin gPackager )
					)
					( objectStatus "J4B1.42" )
				)
				( pin "vss(76)"
					( attribute "PN" "39"
						( Origin gPackager )
					)
					( objectStatus "J4B1.39" )
				)
				( pin "vss(77)"
					( attribute "PN" "37"
						( Origin gPackager )
					)
					( objectStatus "J4B1.37" )
				)
				( pin "vss(78)"
					( attribute "PN" "35"
						( Origin gPackager )
					)
					( objectStatus "J4B1.35" )
				)
				( pin "vss(79)"
					( attribute "PN" "33"
						( Origin gPackager )
					)
					( objectStatus "J4B1.33" )
				)
				( pin "vss(80)"
					( attribute "PN" "31"
						( Origin gPackager )
					)
					( objectStatus "J4B1.31" )
				)
				( pin "vss(81)"
					( attribute "PN" "28"
						( Origin gPackager )
					)
					( objectStatus "J4B1.28" )
				)
				( pin "vss(82)"
					( attribute "PN" "26"
						( Origin gPackager )
					)
					( objectStatus "J4B1.26" )
				)
				( pin "vss(83)"
					( attribute "PN" "24"
						( Origin gPackager )
					)
					( objectStatus "J4B1.24" )
				)
				( pin "vss(84)"
					( attribute "PN" "22"
						( Origin gPackager )
					)
					( objectStatus "J4B1.22" )
				)
				( pin "vss(85)"
					( attribute "PN" "20"
						( Origin gPackager )
					)
					( objectStatus "J4B1.20" )
				)
				( pin "vss(86)"
					( attribute "PN" "17"
						( Origin gPackager )
					)
					( objectStatus "J4B1.17" )
				)
				( pin "vss(87)"
					( attribute "PN" "15"
						( Origin gPackager )
					)
					( objectStatus "J4B1.15" )
				)
				( pin "vss(88)"
					( attribute "PN" "13"
						( Origin gPackager )
					)
					( objectStatus "J4B1.13" )
				)
				( pin "vss(89)"
					( attribute "PN" "11"
						( Origin gPackager )
					)
					( objectStatus "J4B1.11" )
				)
				( pin "vss(90)"
					( attribute "PN" "9"
						( Origin gPackager )
					)
					( objectStatus "J4B1.9" )
				)
				( pin "vss(91)"
					( attribute "PN" "6"
						( Origin gPackager )
					)
					( objectStatus "J4B1.6" )
				)
				( pin "vss(92)"
					( attribute "PN" "4"
						( Origin gPackager )
					)
					( objectStatus "J4B1.4" )
				)
				( pin "vss(93)"
					( attribute "PN" "2"
						( Origin gPackager )
					)
					( objectStatus "J4B1.2" )
				)
			)
			( gate "@baseboard_fab2_lib.baseboard_fab2(sch_1):page49_i66"
				( attribute "BOM_COST" "MEM"
					( Origin gFrontEnd )
				)
				( attribute "CDS_LIB" "mstr_sconn"
					( Origin gPackager )
				)
				( attribute "CDS_LOCATION" "J4B1"
					( Origin gPackager )
				)
				( attribute "CDS_SEC" "2"
					( Origin gPackager )
				)
				( attribute "LOCATION" "J4B1"
					( Origin gFrontEnd )
				)
				( attribute "MATERIAL" "SCONN"
					( Origin gFrontEnd )
				)
				( attribute "PACK_TYPE" "PIP"
					( Origin gFrontEnd )
				)
				( attribute "PART_NUMBER" "H44441-004"
					( Origin gFrontEnd )
				)
				( attribute "PHYS_PAGE" "49"
					( Origin gFrontEnd )
				)
				( attribute "ROOM" "DDR4_CH_D"
					( Origin gFrontEnd )
				)
				( attribute "ROT" "0"
					( Origin gFrontEnd )
				)
				( attribute "SEC" "2"
					( Origin gFrontEnd )
				)
				( attribute "SEC_TYPE" "PIP"
					( Origin gFrontEnd )
				)
				( attribute "VER" "2"
					( Origin gFrontEnd )
				)
				( attribute "XY" "(-50,4350)"
					( Origin gFrontEnd )
				)
				( attribute "CHIPS_PART_NAME" "SCONN288_H44441004"
					( Origin gPackager )
				)
				( attribute "CDS_PART_NAME" "SCONN288_H44441004_PIP-SCONN,HA"
					( Origin gPackager )
				)
				( objectStatus "J4B1" )
				( pin "dqs0n"
					( attribute "PN" "152"
						( Origin gPackager )
					)
					( objectStatus "J4B1.152" )
				)
				( pin "dqs0p"
					( attribute "PN" "153"
						( Origin gPackager )
					)
					( objectStatus "J4B1.153" )
				)
				( pin "dqs1n"
					( attribute "PN" "163"
						( Origin gPackager )
					)
					( objectStatus "J4B1.163" )
				)
				( pin "dqs1p"
					( attribute "PN" "164"
						( Origin gPackager )
					)
					( objectStatus "J4B1.164" )
				)
				( pin "dqs2n"
					( attribute "PN" "174"
						( Origin gPackager )
					)
					( objectStatus "J4B1.174" )
				)
				( pin "dqs2p"
					( attribute "PN" "175"
						( Origin gPackager )
					)
					( objectStatus "J4B1.175" )
				)
				( pin "dqs3n"
					( attribute "PN" "185"
						( Origin gPackager )
					)
					( objectStatus "J4B1.185" )
				)
				( pin "dqs3p"
					( attribute "PN" "186"
						( Origin gPackager )
					)
					( objectStatus "J4B1.186" )
				)
				( pin "dqs4n"
					( attribute "PN" "244"
						( Origin gPackager )
					)
					( objectStatus "J4B1.244" )
				)
				( pin "dqs4p"
					( attribute "PN" "245"
						( Origin gPackager )
					)
					( objectStatus "J4B1.245" )
				)
				( pin "dqs5n"
					( attribute "PN" "255"
						( Origin gPackager )
					)
					( objectStatus "J4B1.255" )
				)
				( pin "dqs5p"
					( attribute "PN" "256"
						( Origin gPackager )
					)
					( objectStatus "J4B1.256" )
				)
				( pin "dqs6n"
					( attribute "PN" "266"
						( Origin gPackager )
					)
					( objectStatus "J4B1.266" )
				)
				( pin "dqs6p"
					( attribute "PN" "267"
						( Origin gPackager )
					)
					( objectStatus "J4B1.267" )
				)
				( pin "dqs7n"
					( attribute "PN" "277"
						( Origin gPackager )
					)
					( objectStatus "J4B1.277" )
				)
				( pin "dqs7p"
					( attribute "PN" "278"
						( Origin gPackager )
					)
					( objectStatus "J4B1.278" )
				)
				( pin "dqs8n"
					( attribute "PN" "196"
						( Origin gPackager )
					)
					( objectStatus "J4B1.196" )
				)
				( pin "dqs8p"
					( attribute "PN" "197"
						( Origin gPackager )
					)
					( objectStatus "J4B1.197" )
				)
				( pin "dqs9n"
					( attribute "PN" "8"
						( Origin gPackager )
					)
					( objectStatus "J4B1.8" )
				)
				( pin "dqs9p"
					( attribute "PN" "7"
						( Origin gPackager )
					)
					( objectStatus "J4B1.7" )
				)
				( pin "dqs10n"
					( attribute "PN" "19"
						( Origin gPackager )
					)
					( objectStatus "J4B1.19" )
				)
				( pin "dqs10p"
					( attribute "PN" "18"
						( Origin gPackager )
					)
					( objectStatus "J4B1.18" )
				)
				( pin "dqs11n"
					( attribute "PN" "30"
						( Origin gPackager )
					)
					( objectStatus "J4B1.30" )
				)
				( pin "dqs11p"
					( attribute "PN" "29"
						( Origin gPackager )
					)
					( objectStatus "J4B1.29" )
				)
				( pin "dqs12n"
					( attribute "PN" "41"
						( Origin gPackager )
					)
					( objectStatus "J4B1.41" )
				)
				( pin "dqs12p"
					( attribute "PN" "40"
						( Origin gPackager )
					)
					( objectStatus "J4B1.40" )
				)
				( pin "dqs13n"
					( attribute "PN" "100"
						( Origin gPackager )
					)
					( objectStatus "J4B1.100" )
				)
				( pin "dqs13p"
					( attribute "PN" "99"
						( Origin gPackager )
					)
					( objectStatus "J4B1.99" )
				)
				( pin "dqs14n"
					( attribute "PN" "111"
						( Origin gPackager )
					)
					( objectStatus "J4B1.111" )
				)
				( pin "dqs14p"
					( attribute "PN" "110"
						( Origin gPackager )
					)
					( objectStatus "J4B1.110" )
				)
				( pin "dqs15n"
					( attribute "PN" "122"
						( Origin gPackager )
					)
					( objectStatus "J4B1.122" )
				)
				( pin "dqs15p"
					( attribute "PN" "121"
						( Origin gPackager )
					)
					( objectStatus "J4B1.121" )
				)
				( pin "dqs16n"
					( attribute "PN" "133"
						( Origin gPackager )
					)
					( objectStatus "J4B1.133" )
				)
				( pin "dqs16p"
					( attribute "PN" "132"
						( Origin gPackager )
					)
					( objectStatus "J4B1.132" )
				)
				( pin "dqs17n"
					( attribute "PN" "52"
						( Origin gPackager )
					)
					( objectStatus "J4B1.52" )
				)
				( pin "dqs17p"
					( attribute "PN" "51"
						( Origin gPackager )
					)
					( objectStatus "J4B1.51" )
				)
			)
			( gate "@baseboard_fab2_lib.baseboard_fab2(sch_1):page49_i111"
				( attribute "BOM_COST" "MEM"
					( Origin gFrontEnd )
				)
				( attribute "CDS_LIB" "mstr_sconn"
					( Origin gPackager )
				)
				( attribute "CDS_LOCATION" "J4B1"
					( Origin gPackager )
				)
				( attribute "CDS_SEC" "1"
					( Origin gPackager )
				)
				( attribute "LOCATION" "J4B1"
					( Origin gFrontEnd )
				)
				( attribute "MATERIAL" "SCONN"
					( Origin gFrontEnd )
				)
				( attribute "PACK_TYPE" "PIP"
					( Origin gFrontEnd )
				)
				( attribute "PART_NUMBER" "H44441-004"
					( Origin gFrontEnd )
				)
				( attribute "PHYS_PAGE" "49"
					( Origin gFrontEnd )
				)
				( attribute "ROOM" "DDR4_CH_D"
					( Origin gFrontEnd )
				)
				( attribute "ROT" "0"
					( Origin gFrontEnd )
				)
				( attribute "SEC" "1"
					( Origin gFrontEnd )
				)
				( attribute "SEC_TYPE" "PIP"
					( Origin gFrontEnd )
				)
				( attribute "VER" "1"
					( Origin gFrontEnd )
				)
				( attribute "XY" "(-2500,3500)"
					( Origin gFrontEnd )
				)
				( attribute "CHIPS_PART_NAME" "SCONN288_H44441004"
					( Origin gPackager )
				)
				( attribute "CDS_PART_NAME" "SCONN288_H44441004_PIP-SCONN,HA"
					( Origin gPackager )
				)
				( objectStatus "J4B1" )
				( pin "a0"
					( attribute "PN" "79"
						( Origin gPackager )
					)
					( objectStatus "J4B1.79" )
				)
				( pin "a1"
					( attribute "PN" "72"
						( Origin gPackager )
					)
					( objectStatus "J4B1.72" )
				)
				( pin "a2"
					( attribute "PN" "216"
						( Origin gPackager )
					)
					( objectStatus "J4B1.216" )
				)
				( pin "a3"
					( attribute "PN" "71"
						( Origin gPackager )
					)
					( objectStatus "J4B1.71" )
				)
				( pin "a4"
					( attribute "PN" "214"
						( Origin gPackager )
					)
					( objectStatus "J4B1.214" )
				)
				( pin "a5"
					( attribute "PN" "213"
						( Origin gPackager )
					)
					( objectStatus "J4B1.213" )
				)
				( pin "a6"
					( attribute "PN" "69"
						( Origin gPackager )
					)
					( objectStatus "J4B1.69" )
				)
				( pin "a7"
					( attribute "PN" "211"
						( Origin gPackager )
					)
					( objectStatus "J4B1.211" )
				)
				( pin "a8"
					( attribute "PN" "68"
						( Origin gPackager )
					)
					( objectStatus "J4B1.68" )
				)
				( pin "a9"
					( attribute "PN" "66"
						( Origin gPackager )
					)
					( objectStatus "J4B1.66" )
				)
				( pin "a10"
					( attribute "PN" "225"
						( Origin gPackager )
					)
					( objectStatus "J4B1.225" )
				)
				( pin "a11"
					( attribute "PN" "210"
						( Origin gPackager )
					)
					( objectStatus "J4B1.210" )
				)
				( pin "a12"
					( attribute "PN" "65"
						( Origin gPackager )
					)
					( objectStatus "J4B1.65" )
				)
				( pin "a13"
					( attribute "PN" "232"
						( Origin gPackager )
					)
					( objectStatus "J4B1.232" )
				)
				( pin "a14_we_n"
					( attribute "PN" "228"
						( Origin gPackager )
					)
					( objectStatus "J4B1.228" )
				)
				( pin "a15_cas_n"
					( attribute "PN" "86"
						( Origin gPackager )
					)
					( objectStatus "J4B1.86" )
				)
				( pin "a16_ras_n"
					( attribute "PN" "82"
						( Origin gPackager )
					)
					( objectStatus "J4B1.82" )
				)
				( pin "a17"
					( attribute "PN" "234"
						( Origin gPackager )
					)
					( objectStatus "J4B1.234" )
				)
				( pin "act_n"
					( attribute "PN" "62"
						( Origin gPackager )
					)
					( objectStatus "J4B1.62" )
				)
				( pin "alert_n"
					( attribute "PN" "208"
						( Origin gPackager )
					)
					( objectStatus "J4B1.208" )
				)
				( pin "ba(0)"
					( attribute "PN" "81"
						( Origin gPackager )
					)
					( objectStatus "J4B1.81" )
				)
				( pin "ba(1)"
					( attribute "PN" "224"
						( Origin gPackager )
					)
					( objectStatus "J4B1.224" )
				)
				( pin "bg(0)"
					( attribute "PN" "63"
						( Origin gPackager )
					)
					( objectStatus "J4B1.63" )
				)
				( pin "bg(1)"
					( attribute "PN" "207"
						( Origin gPackager )
					)
					( objectStatus "J4B1.207" )
				)
				( pin "c(2)"
					( attribute "PN" "235"
						( Origin gPackager )
					)
					( objectStatus "J4B1.235" )
				)
				( pin "cb(0)"
					( attribute "PN" "49"
						( Origin gPackager )
					)
					( objectStatus "J4B1.49" )
				)
				( pin "cb(1)"
					( attribute "PN" "194"
						( Origin gPackager )
					)
					( objectStatus "J4B1.194" )
				)
				( pin "cb(2)"
					( attribute "PN" "56"
						( Origin gPackager )
					)
					( objectStatus "J4B1.56" )
				)
				( pin "cb(3)"
					( attribute "PN" "201"
						( Origin gPackager )
					)
					( objectStatus "J4B1.201" )
				)
				( pin "cb(4)"
					( attribute "PN" "47"
						( Origin gPackager )
					)
					( objectStatus "J4B1.47" )
				)
				( pin "cb(5)"
					( attribute "PN" "192"
						( Origin gPackager )
					)
					( objectStatus "J4B1.192" )
				)
				( pin "cb(6)"
					( attribute "PN" "54"
						( Origin gPackager )
					)
					( objectStatus "J4B1.54" )
				)
				( pin "cb(7)"
					( attribute "PN" "199"
						( Origin gPackager )
					)
					( objectStatus "J4B1.199" )
				)
				( pin "ck0n"
					( attribute "PN" "75"
						( Origin gPackager )
					)
					( objectStatus "J4B1.75" )
				)
				( pin "ck0p"
					( attribute "PN" "74"
						( Origin gPackager )
					)
					( objectStatus "J4B1.74" )
				)
				( pin "ck1n"
					( attribute "PN" "219"
						( Origin gPackager )
					)
					( objectStatus "J4B1.219" )
				)
				( pin "ck1p"
					( attribute "PN" "218"
						( Origin gPackager )
					)
					( objectStatus "J4B1.218" )
				)
				( pin "cke(0)"
					( attribute "PN" "60"
						( Origin gPackager )
					)
					( objectStatus "J4B1.60" )
				)
				( pin "cke(1)"
					( attribute "PN" "203"
						( Origin gPackager )
					)
					( objectStatus "J4B1.203" )
				)
				( pin "dq(0)"
					( attribute "PN" "5"
						( Origin gPackager )
					)
					( objectStatus "J4B1.5" )
				)
				( pin "dq(1)"
					( attribute "PN" "150"
						( Origin gPackager )
					)
					( objectStatus "J4B1.150" )
				)
				( pin "dq(2)"
					( attribute "PN" "12"
						( Origin gPackager )
					)
					( objectStatus "J4B1.12" )
				)
				( pin "dq(3)"
					( attribute "PN" "157"
						( Origin gPackager )
					)
					( objectStatus "J4B1.157" )
				)
				( pin "dq(4)"
					( attribute "PN" "3"
						( Origin gPackager )
					)
					( objectStatus "J4B1.3" )
				)
				( pin "dq(5)"
					( attribute "PN" "148"
						( Origin gPackager )
					)
					( objectStatus "J4B1.148" )
				)
				( pin "dq(6)"
					( attribute "PN" "10"
						( Origin gPackager )
					)
					( objectStatus "J4B1.10" )
				)
				( pin "dq(7)"
					( attribute "PN" "155"
						( Origin gPackager )
					)
					( objectStatus "J4B1.155" )
				)
				( pin "dq(8)"
					( attribute "PN" "16"
						( Origin gPackager )
					)
					( objectStatus "J4B1.16" )
				)
				( pin "dq(9)"
					( attribute "PN" "161"
						( Origin gPackager )
					)
					( objectStatus "J4B1.161" )
				)
				( pin "dq(10)"
					( attribute "PN" "23"
						( Origin gPackager )
					)
					( objectStatus "J4B1.23" )
				)
				( pin "dq(11)"
					( attribute "PN" "168"
						( Origin gPackager )
					)
					( objectStatus "J4B1.168" )
				)
				( pin "dq(12)"
					( attribute "PN" "14"
						( Origin gPackager )
					)
					( objectStatus "J4B1.14" )
				)
				( pin "dq(13)"
					( attribute "PN" "159"
						( Origin gPackager )
					)
					( objectStatus "J4B1.159" )
				)
				( pin "dq(14)"
					( attribute "PN" "21"
						( Origin gPackager )
					)
					( objectStatus "J4B1.21" )
				)
				( pin "dq(15)"
					( attribute "PN" "166"
						( Origin gPackager )
					)
					( objectStatus "J4B1.166" )
				)
				( pin "dq(16)"
					( attribute "PN" "27"
						( Origin gPackager )
					)
					( objectStatus "J4B1.27" )
				)
				( pin "dq(17)"
					( attribute "PN" "172"
						( Origin gPackager )
					)
					( objectStatus "J4B1.172" )
				)
				( pin "dq(18)"
					( attribute "PN" "34"
						( Origin gPackager )
					)
					( objectStatus "J4B1.34" )
				)
				( pin "dq(19)"
					( attribute "PN" "179"
						( Origin gPackager )
					)
					( objectStatus "J4B1.179" )
				)
				( pin "dq(20)"
					( attribute "PN" "25"
						( Origin gPackager )
					)
					( objectStatus "J4B1.25" )
				)
				( pin "dq(21)"
					( attribute "PN" "170"
						( Origin gPackager )
					)
					( objectStatus "J4B1.170" )
				)
				( pin "dq(22)"
					( attribute "PN" "32"
						( Origin gPackager )
					)
					( objectStatus "J4B1.32" )
				)
				( pin "dq(23)"
					( attribute "PN" "177"
						( Origin gPackager )
					)
					( objectStatus "J4B1.177" )
				)
				( pin "dq(24)"
					( attribute "PN" "38"
						( Origin gPackager )
					)
					( objectStatus "J4B1.38" )
				)
				( pin "dq(25)"
					( attribute "PN" "183"
						( Origin gPackager )
					)
					( objectStatus "J4B1.183" )
				)
				( pin "dq(26)"
					( attribute "PN" "45"
						( Origin gPackager )
					)
					( objectStatus "J4B1.45" )
				)
				( pin "dq(27)"
					( attribute "PN" "190"
						( Origin gPackager )
					)
					( objectStatus "J4B1.190" )
				)
				( pin "dq(28)"
					( attribute "PN" "36"
						( Origin gPackager )
					)
					( objectStatus "J4B1.36" )
				)
				( pin "dq(29)"
					( attribute "PN" "181"
						( Origin gPackager )
					)
					( objectStatus "J4B1.181" )
				)
				( pin "dq(30)"
					( attribute "PN" "43"
						( Origin gPackager )
					)
					( objectStatus "J4B1.43" )
				)
				( pin "dq(31)"
					( attribute "PN" "188"
						( Origin gPackager )
					)
					( objectStatus "J4B1.188" )
				)
				( pin "dq(32)"
					( attribute "PN" "97"
						( Origin gPackager )
					)
					( objectStatus "J4B1.97" )
				)
				( pin "dq(33)"
					( attribute "PN" "242"
						( Origin gPackager )
					)
					( objectStatus "J4B1.242" )
				)
				( pin "dq(34)"
					( attribute "PN" "104"
						( Origin gPackager )
					)
					( objectStatus "J4B1.104" )
				)
				( pin "dq(35)"
					( attribute "PN" "249"
						( Origin gPackager )
					)
					( objectStatus "J4B1.249" )
				)
				( pin "dq(36)"
					( attribute "PN" "95"
						( Origin gPackager )
					)
					( objectStatus "J4B1.95" )
				)
				( pin "dq(37)"
					( attribute "PN" "240"
						( Origin gPackager )
					)
					( objectStatus "J4B1.240" )
				)
				( pin "dq(38)"
					( attribute "PN" "102"
						( Origin gPackager )
					)
					( objectStatus "J4B1.102" )
				)
				( pin "dq(39)"
					( attribute "PN" "247"
						( Origin gPackager )
					)
					( objectStatus "J4B1.247" )
				)
				( pin "dq(40)"
					( attribute "PN" "108"
						( Origin gPackager )
					)
					( objectStatus "J4B1.108" )
				)
				( pin "dq(41)"
					( attribute "PN" "253"
						( Origin gPackager )
					)
					( objectStatus "J4B1.253" )
				)
				( pin "dq(42)"
					( attribute "PN" "115"
						( Origin gPackager )
					)
					( objectStatus "J4B1.115" )
				)
				( pin "dq(43)"
					( attribute "PN" "260"
						( Origin gPackager )
					)
					( objectStatus "J4B1.260" )
				)
				( pin "dq(44)"
					( attribute "PN" "106"
						( Origin gPackager )
					)
					( objectStatus "J4B1.106" )
				)
				( pin "dq(45)"
					( attribute "PN" "251"
						( Origin gPackager )
					)
					( objectStatus "J4B1.251" )
				)
				( pin "dq(46)"
					( attribute "PN" "113"
						( Origin gPackager )
					)
					( objectStatus "J4B1.113" )
				)
				( pin "dq(47)"
					( attribute "PN" "258"
						( Origin gPackager )
					)
					( objectStatus "J4B1.258" )
				)
				( pin "dq(48)"
					( attribute "PN" "119"
						( Origin gPackager )
					)
					( objectStatus "J4B1.119" )
				)
				( pin "dq(49)"
					( attribute "PN" "264"
						( Origin gPackager )
					)
					( objectStatus "J4B1.264" )
				)
				( pin "dq(50)"
					( attribute "PN" "126"
						( Origin gPackager )
					)
					( objectStatus "J4B1.126" )
				)
				( pin "dq(51)"
					( attribute "PN" "271"
						( Origin gPackager )
					)
					( objectStatus "J4B1.271" )
				)
				( pin "dq(52)"
					( attribute "PN" "117"
						( Origin gPackager )
					)
					( objectStatus "J4B1.117" )
				)
				( pin "dq(53)"
					( attribute "PN" "262"
						( Origin gPackager )
					)
					( objectStatus "J4B1.262" )
				)
				( pin "dq(54)"
					( attribute "PN" "124"
						( Origin gPackager )
					)
					( objectStatus "J4B1.124" )
				)
				( pin "dq(55)"
					( attribute "PN" "269"
						( Origin gPackager )
					)
					( objectStatus "J4B1.269" )
				)
				( pin "dq(56)"
					( attribute "PN" "130"
						( Origin gPackager )
					)
					( objectStatus "J4B1.130" )
				)
				( pin "dq(57)"
					( attribute "PN" "275"
						( Origin gPackager )
					)
					( objectStatus "J4B1.275" )
				)
				( pin "dq(58)"
					( attribute "PN" "137"
						( Origin gPackager )
					)
					( objectStatus "J4B1.137" )
				)
				( pin "dq(59)"
					( attribute "PN" "282"
						( Origin gPackager )
					)
					( objectStatus "J4B1.282" )
				)
				( pin "dq(60)"
					( attribute "PN" "128"
						( Origin gPackager )
					)
					( objectStatus "J4B1.128" )
				)
				( pin "dq(61)"
					( attribute "PN" "273"
						( Origin gPackager )
					)
					( objectStatus "J4B1.273" )
				)
				( pin "dq(62)"
					( attribute "PN" "135"
						( Origin gPackager )
					)
					( objectStatus "J4B1.135" )
				)
				( pin "dq(63)"
					( attribute "PN" "280"
						( Origin gPackager )
					)
					( objectStatus "J4B1.280" )
				)
				( pin "event_n"
					( attribute "PN" "78"
						( Origin gPackager )
					)
					( objectStatus "J4B1.78" )
				)
				( pin "odt(0)"
					( attribute "PN" "87"
						( Origin gPackager )
					)
					( objectStatus "J4B1.87" )
				)
				( pin "odt(1)"
					( attribute "PN" "91"
						( Origin gPackager )
					)
					( objectStatus "J4B1.91" )
				)
				( pin "par"
					( attribute "PN" "222"
						( Origin gPackager )
					)
					( objectStatus "J4B1.222" )
				)
				( pin "reset_n"
					( attribute "PN" "58"
						( Origin gPackager )
					)
					( objectStatus "J4B1.58" )
				)
				( pin "rfu(0)"
					( attribute "PN" "205"
						( Origin gPackager )
					)
					( objectStatus "J4B1.205" )
				)
				( pin "rfu(1)"
					( attribute "PN" "227"
						( Origin gPackager )
					)
					( objectStatus "J4B1.227" )
				)
				( pin "rfu(2)"
					( attribute "PN" "144"
						( Origin gPackager )
					)
					( objectStatus "J4B1.144" )
				)
				( pin "s0_n"
					( attribute "PN" "84"
						( Origin gPackager )
					)
					( objectStatus "J4B1.84" )
				)
				( pin "s1_n"
					( attribute "PN" "89"
						( Origin gPackager )
					)
					( objectStatus "J4B1.89" )
				)
				( pin "s2_n_c(0)"
					( attribute "PN" "93"
						( Origin gPackager )
					)
					( objectStatus "J4B1.93" )
				)
				( pin "s3_n_c(1)"
					( attribute "PN" "237"
						( Origin gPackager )
					)
					( objectStatus "J4B1.237" )
				)
				( pin "sa(0)"
					( attribute "PN" "139"
						( Origin gPackager )
					)
					( objectStatus "J4B1.139" )
				)
				( pin "sa(1)"
					( attribute "PN" "140"
						( Origin gPackager )
					)
					( objectStatus "J4B1.140" )
				)
				( pin "sa(2)"
					( attribute "PN" "238"
						( Origin gPackager )
					)
					( objectStatus "J4B1.238" )
				)
				( pin "save_n_nc"
					( attribute "PN" "230"
						( Origin gPackager )
					)
					( objectStatus "J4B1.230" )
				)
				( pin "scl"
					( attribute "PN" "141"
						( Origin gPackager )
					)
					( objectStatus "J4B1.141" )
				)
				( pin "sda"
					( attribute "PN" "285"
						( Origin gPackager )
					)
					( objectStatus "J4B1.285" )
				)
				( pin "vddspd"
					( attribute "PN" "284"
						( Origin gPackager )
					)
					( objectStatus "J4B1.284" )
				)
				( pin "vrefca"
					( attribute "PN" "146"
						( Origin gPackager )
					)
					( objectStatus "J4B1.146" )
				)
			)
			( gate "@baseboard_fab2_lib.baseboard_fab2(sch_1):page49_i169"
				( attribute "BOM_COST" "MEM"
					( Origin gFrontEnd )
				)
				( attribute "CDS_LIB" "mstr_sconn"
					( Origin gPackager )
				)
				( attribute "CDS_LOCATION" "J4B1"
					( Origin gPackager )
				)
				( attribute "CDS_SEC" "4"
					( Origin gPackager )
				)
				( attribute "LOCATION" "J4B1"
					( Origin gFrontEnd )
				)
				( attribute "MATERIAL" "SCONN"
					( Origin gFrontEnd )
				)
				( attribute "PACK_TYPE" "PIP"
					( Origin gFrontEnd )
				)
				( attribute "PART_NUMBER" "H44441-004"
					( Origin gFrontEnd )
				)
				( attribute "PHYS_PAGE" "49"
					( Origin gFrontEnd )
				)
				( attribute "ROOM" "DDR4_CH_D"
					( Origin gFrontEnd )
				)
				( attribute "ROT" "0"
					( Origin gFrontEnd )
				)
				( attribute "SEC" "4"
					( Origin gFrontEnd )
				)
				( attribute "SEC_TYPE" "PIP"
					( Origin gFrontEnd )
				)
				( attribute "VER" "4"
					( Origin gFrontEnd )
				)
				( attribute "XY" "(-50,1950)"
					( Origin gFrontEnd )
				)
				( attribute "CHIPS_PART_NAME" "SCONN288_H44441004"
					( Origin gPackager )
				)
				( attribute "CDS_PART_NAME" "SCONN288_H44441004_PIP-SCONN,HA"
					( Origin gPackager )
				)
				( objectStatus "J4B1" )
				( pin "\12v\(0)"
					( attribute "PN" "145"
						( Origin gPackager )
					)
					( objectStatus "J4B1.145" )
				)
				( pin "\12v\(1)"
					( attribute "PN" "1"
						( Origin gPackager )
					)
					( objectStatus "J4B1.1" )
				)
				( pin "vdd(0)"
					( attribute "PN" "236"
						( Origin gPackager )
					)
					( objectStatus "J4B1.236" )
				)
				( pin "vdd(1)"
					( attribute "PN" "233"
						( Origin gPackager )
					)
					( objectStatus "J4B1.233" )
				)
				( pin "vdd(2)"
					( attribute "PN" "231"
						( Origin gPackager )
					)
					( objectStatus "J4B1.231" )
				)
				( pin "vdd(3)"
					( attribute "PN" "229"
						( Origin gPackager )
					)
					( objectStatus "J4B1.229" )
				)
				( pin "vdd(4)"
					( attribute "PN" "226"
						( Origin gPackager )
					)
					( objectStatus "J4B1.226" )
				)
				( pin "vdd(5)"
					( attribute "PN" "223"
						( Origin gPackager )
					)
					( objectStatus "J4B1.223" )
				)
				( pin "vdd(6)"
					( attribute "PN" "220"
						( Origin gPackager )
					)
					( objectStatus "J4B1.220" )
				)
				( pin "vdd(7)"
					( attribute "PN" "217"
						( Origin gPackager )
					)
					( objectStatus "J4B1.217" )
				)
				( pin "vdd(8)"
					( attribute "PN" "215"
						( Origin gPackager )
					)
					( objectStatus "J4B1.215" )
				)
				( pin "vdd(9)"
					( attribute "PN" "212"
						( Origin gPackager )
					)
					( objectStatus "J4B1.212" )
				)
				( pin "vdd(10)"
					( attribute "PN" "209"
						( Origin gPackager )
					)
					( objectStatus "J4B1.209" )
				)
				( pin "vdd(11)"
					( attribute "PN" "206"
						( Origin gPackager )
					)
					( objectStatus "J4B1.206" )
				)
				( pin "vdd(12)"
					( attribute "PN" "204"
						( Origin gPackager )
					)
					( objectStatus "J4B1.204" )
				)
				( pin "vdd(13)"
					( attribute "PN" "92"
						( Origin gPackager )
					)
					( objectStatus "J4B1.92" )
				)
				( pin "vdd(14)"
					( attribute "PN" "90"
						( Origin gPackager )
					)
					( objectStatus "J4B1.90" )
				)
				( pin "vdd(15)"
					( attribute "PN" "88"
						( Origin gPackager )
					)
					( objectStatus "J4B1.88" )
				)
				( pin "vdd(16)"
					( attribute "PN" "85"
						( Origin gPackager )
					)
					( objectStatus "J4B1.85" )
				)
				( pin "vdd(17)"
					( attribute "PN" "83"
						( Origin gPackager )
					)
					( objectStatus "J4B1.83" )
				)
				( pin "vdd(18)"
					( attribute "PN" "80"
						( Origin gPackager )
					)
					( objectStatus "J4B1.80" )
				)
				( pin "vdd(19)"
					( attribute "PN" "76"
						( Origin gPackager )
					)
					( objectStatus "J4B1.76" )
				)
				( pin "vdd(20)"
					( attribute "PN" "73"
						( Origin gPackager )
					)
					( objectStatus "J4B1.73" )
				)
				( pin "vdd(21)"
					( attribute "PN" "70"
						( Origin gPackager )
					)
					( objectStatus "J4B1.70" )
				)
				( pin "vdd(22)"
					( attribute "PN" "67"
						( Origin gPackager )
					)
					( objectStatus "J4B1.67" )
				)
				( pin "vdd(23)"
					( attribute "PN" "64"
						( Origin gPackager )
					)
					( objectStatus "J4B1.64" )
				)
				( pin "vdd(24)"
					( attribute "PN" "61"
						( Origin gPackager )
					)
					( objectStatus "J4B1.61" )
				)
				( pin "vdd(25)"
					( attribute "PN" "59"
						( Origin gPackager )
					)
					( objectStatus "J4B1.59" )
				)
				( pin "vpp(0)"
					( attribute "PN" "287"
						( Origin gPackager )
					)
					( objectStatus "J4B1.287" )
				)
				( pin "vpp(1)"
					( attribute "PN" "286"
						( Origin gPackager )
					)
					( objectStatus "J4B1.286" )
				)
				( pin "vpp(2)"
					( attribute "PN" "288"
						( Origin gPackager )
					)
					( objectStatus "J4B1.288" )
				)
				( pin "vpp(3)"
					( attribute "PN" "143"
						( Origin gPackager )
					)
					( objectStatus "J4B1.143" )
				)
				( pin "vpp(4)"
					( attribute "PN" "142"
						( Origin gPackager )
					)
					( objectStatus "J4B1.142" )
				)
				( pin "vtt(0)"
					( attribute "PN" "221"
						( Origin gPackager )
					)
					( objectStatus "J4B1.221" )
				)
				( pin "vtt(1)"
					( attribute "PN" "77"
						( Origin gPackager )
					)
					( objectStatus "J4B1.77" )
				)
			)
			( gate "@baseboard_fab2_lib.baseboard_fab2(sch_1):page49_i179"
				( attribute "BOM_COST" "MEM"
					( Origin gFrontEnd )
				)
				( attribute "CDS_LIB" "dev_discrete"
					( Origin gPackager )
				)
				( attribute "CDS_LOCATION" "C4B12"
					( Origin gPackager )
				)
				( attribute "CDS_SEC" "1"
					( Origin gPackager )
				)
				( attribute "LOCATION" "C4B12"
					( Origin gFrontEnd )
				)
				( attribute "MATERIAL" "X7R"
					( Origin gFrontEnd )
				)
				( attribute "PACK_TYPE" "0402V"
					( Origin gFrontEnd )
				)
				( attribute "PART_NUMBER" "A36096-045"
					( Origin gFrontEnd )
				)
				( attribute "PHYS_PAGE" "49"
					( Origin gFrontEnd )
				)
				( attribute "ROOM" "DDR4_CH_B"
					( Origin gFrontEnd )
				)
				( attribute "ROT" "2"
					( Origin gFrontEnd )
				)
				( attribute "SEC" "1"
					( Origin gPackager )
				)
				( attribute "TOLERANCE" "10%"
					( Origin gFrontEnd )
				)
				( attribute "VALUE" "0.01UF"
					( Origin gFrontEnd )
				)
				( attribute "VER" "1"
					( Origin gFrontEnd )
				)
				( attribute "VOLTAGE" "25V"
					( Units "uVoltage" "V" 1.000000)
					( Origin gFrontEnd )
				)
				( attribute "XY" "(-4650,1800)"
					( Origin gFrontEnd )
				)
				( attribute "CHIPS_PART_NAME" "CAP_A"
					( Origin gPackager )
				)
				( attribute "CDS_PART_NAME" "CAP_A_0402V-0.01UF,25V,10%,X7RA"
					( Origin gPackager )
				)
				( objectStatus "C4B12" )
				( pin "a"
					( attribute "PN" "1"
						( Origin gPackager )
					)
					( objectStatus "C4B12.1" )
				)
				( pin "b"
					( attribute "PN" "2"
						( Origin gPackager )
					)
					( objectStatus "C4B12.2" )
				)
			)
			( gate "@baseboard_fab2_lib.baseboard_fab2(sch_1):page50_i44"
				( attribute "BOM_COST" "MEM"
					( Origin gFrontEnd )
				)
				( attribute "CDS_LIB" "mstr_sconn"
					( Origin gPackager )
				)
				( attribute "CDS_LOCATION" "J6M1"
					( Origin gPackager )
				)
				( attribute "CDS_SEC" "3"
					( Origin gPackager )
				)
				( attribute "LOCATION" "J6M1"
					( Origin gFrontEnd )
				)
				( attribute "MATERIAL" "SCONN"
					( Origin gFrontEnd )
				)
				( attribute "PACK_TYPE" "PIP"
					( Origin gFrontEnd )
				)
				( attribute "PART_NUMBER" "H44441-003"
					( Origin gFrontEnd )
				)
				( attribute "PHYS_PAGE" "50"
					( Origin gFrontEnd )
				)
				( attribute "ROOM" "DDR4_CH_D"
					( Origin gFrontEnd )
				)
				( attribute "ROT" "0"
					( Origin gFrontEnd )
				)
				( attribute "SEC" "3"
					( Origin gFrontEnd )
				)
				( attribute "SEC_TYPE" "PIP"
					( Origin gFrontEnd )
				)
				( attribute "VER" "3"
					( Origin gFrontEnd )
				)
				( attribute "XY" "(5250,2050)"
					( Origin gFrontEnd )
				)
				( attribute "CHIPS_PART_NAME" "SCONN288_H44441003"
					( Origin gPackager )
				)
				( attribute "CDS_PART_NAME" "SCONN288_H44441003_PIP-SCONN,HA"
					( Origin gPackager )
				)
				( objectStatus "J6M1" )
				( pin "vss(0)"
					( attribute "PN" "283"
						( Origin gPackager )
					)
					( objectStatus "J6M1.283" )
				)
				( pin "vss(1)"
					( attribute "PN" "281"
						( Origin gPackager )
					)
					( objectStatus "J6M1.281" )
				)
				( pin "vss(2)"
					( attribute "PN" "279"
						( Origin gPackager )
					)
					( objectStatus "J6M1.279" )
				)
				( pin "vss(3)"
					( attribute "PN" "276"
						( Origin gPackager )
					)
					( objectStatus "J6M1.276" )
				)
				( pin "vss(4)"
					( attribute "PN" "274"
						( Origin gPackager )
					)
					( objectStatus "J6M1.274" )
				)
				( pin "vss(5)"
					( attribute "PN" "272"
						( Origin gPackager )
					)
					( objectStatus "J6M1.272" )
				)
				( pin "vss(6)"
					( attribute "PN" "270"
						( Origin gPackager )
					)
					( objectStatus "J6M1.270" )
				)
				( pin "vss(7)"
					( attribute "PN" "268"
						( Origin gPackager )
					)
					( objectStatus "J6M1.268" )
				)
				( pin "vss(8)"
					( attribute "PN" "265"
						( Origin gPackager )
					)
					( objectStatus "J6M1.265" )
				)
				( pin "vss(9)"
					( attribute "PN" "263"
						( Origin gPackager )
					)
					( objectStatus "J6M1.263" )
				)
				( pin "vss(10)"
					( attribute "PN" "261"
						( Origin gPackager )
					)
					( objectStatus "J6M1.261" )
				)
				( pin "vss(11)"
					( attribute "PN" "259"
						( Origin gPackager )
					)
					( objectStatus "J6M1.259" )
				)
				( pin "vss(12)"
					( attribute "PN" "257"
						( Origin gPackager )
					)
					( objectStatus "J6M1.257" )
				)
				( pin "vss(13)"
					( attribute "PN" "254"
						( Origin gPackager )
					)
					( objectStatus "J6M1.254" )
				)
				( pin "vss(14)"
					( attribute "PN" "252"
						( Origin gPackager )
					)
					( objectStatus "J6M1.252" )
				)
				( pin "vss(15)"
					( attribute "PN" "250"
						( Origin gPackager )
					)
					( objectStatus "J6M1.250" )
				)
				( pin "vss(16)"
					( attribute "PN" "248"
						( Origin gPackager )
					)
					( objectStatus "J6M1.248" )
				)
				( pin "vss(17)"
					( attribute "PN" "246"
						( Origin gPackager )
					)
					( objectStatus "J6M1.246" )
				)
				( pin "vss(18)"
					( attribute "PN" "243"
						( Origin gPackager )
					)
					( objectStatus "J6M1.243" )
				)
				( pin "vss(19)"
					( attribute "PN" "241"
						( Origin gPackager )
					)
					( objectStatus "J6M1.241" )
				)
				( pin "vss(20)"
					( attribute "PN" "239"
						( Origin gPackager )
					)
					( objectStatus "J6M1.239" )
				)
				( pin "vss(21)"
					( attribute "PN" "202"
						( Origin gPackager )
					)
					( objectStatus "J6M1.202" )
				)
				( pin "vss(22)"
					( attribute "PN" "200"
						( Origin gPackager )
					)
					( objectStatus "J6M1.200" )
				)
				( pin "vss(23)"
					( attribute "PN" "198"
						( Origin gPackager )
					)
					( objectStatus "J6M1.198" )
				)
				( pin "vss(24)"
					( attribute "PN" "195"
						( Origin gPackager )
					)
					( objectStatus "J6M1.195" )
				)
				( pin "vss(25)"
					( attribute "PN" "193"
						( Origin gPackager )
					)
					( objectStatus "J6M1.193" )
				)
				( pin "vss(26)"
					( attribute "PN" "191"
						( Origin gPackager )
					)
					( objectStatus "J6M1.191" )
				)
				( pin "vss(27)"
					( attribute "PN" "189"
						( Origin gPackager )
					)
					( objectStatus "J6M1.189" )
				)
				( pin "vss(28)"
					( attribute "PN" "187"
						( Origin gPackager )
					)
					( objectStatus "J6M1.187" )
				)
				( pin "vss(29)"
					( attribute "PN" "184"
						( Origin gPackager )
					)
					( objectStatus "J6M1.184" )
				)
				( pin "vss(30)"
					( attribute "PN" "182"
						( Origin gPackager )
					)
					( objectStatus "J6M1.182" )
				)
				( pin "vss(31)"
					( attribute "PN" "180"
						( Origin gPackager )
					)
					( objectStatus "J6M1.180" )
				)
				( pin "vss(32)"
					( attribute "PN" "178"
						( Origin gPackager )
					)
					( objectStatus "J6M1.178" )
				)
				( pin "vss(33)"
					( attribute "PN" "176"
						( Origin gPackager )
					)
					( objectStatus "J6M1.176" )
				)
				( pin "vss(34)"
					( attribute "PN" "173"
						( Origin gPackager )
					)
					( objectStatus "J6M1.173" )
				)
				( pin "vss(35)"
					( attribute "PN" "171"
						( Origin gPackager )
					)
					( objectStatus "J6M1.171" )
				)
				( pin "vss(36)"
					( attribute "PN" "169"
						( Origin gPackager )
					)
					( objectStatus "J6M1.169" )
				)
				( pin "vss(37)"
					( attribute "PN" "167"
						( Origin gPackager )
					)
					( objectStatus "J6M1.167" )
				)
				( pin "vss(38)"
					( attribute "PN" "165"
						( Origin gPackager )
					)
					( objectStatus "J6M1.165" )
				)
				( pin "vss(39)"
					( attribute "PN" "162"
						( Origin gPackager )
					)
					( objectStatus "J6M1.162" )
				)
				( pin "vss(40)"
					( attribute "PN" "160"
						( Origin gPackager )
					)
					( objectStatus "J6M1.160" )
				)
				( pin "vss(41)"
					( attribute "PN" "158"
						( Origin gPackager )
					)
					( objectStatus "J6M1.158" )
				)
				( pin "vss(42)"
					( attribute "PN" "156"
						( Origin gPackager )
					)
					( objectStatus "J6M1.156" )
				)
				( pin "vss(43)"
					( attribute "PN" "154"
						( Origin gPackager )
					)
					( objectStatus "J6M1.154" )
				)
				( pin "vss(44)"
					( attribute "PN" "151"
						( Origin gPackager )
					)
					( objectStatus "J6M1.151" )
				)
				( pin "vss(45)"
					( attribute "PN" "149"
						( Origin gPackager )
					)
					( objectStatus "J6M1.149" )
				)
				( pin "vss(46)"
					( attribute "PN" "147"
						( Origin gPackager )
					)
					( objectStatus "J6M1.147" )
				)
				( pin "vss(47)"
					( attribute "PN" "138"
						( Origin gPackager )
					)
					( objectStatus "J6M1.138" )
				)
				( pin "vss(48)"
					( attribute "PN" "136"
						( Origin gPackager )
					)
					( objectStatus "J6M1.136" )
				)
				( pin "vss(49)"
					( attribute "PN" "134"
						( Origin gPackager )
					)
					( objectStatus "J6M1.134" )
				)
				( pin "vss(50)"
					( attribute "PN" "131"
						( Origin gPackager )
					)
					( objectStatus "J6M1.131" )
				)
				( pin "vss(51)"
					( attribute "PN" "129"
						( Origin gPackager )
					)
					( objectStatus "J6M1.129" )
				)
				( pin "vss(52)"
					( attribute "PN" "127"
						( Origin gPackager )
					)
					( objectStatus "J6M1.127" )
				)
				( pin "vss(53)"
					( attribute "PN" "125"
						( Origin gPackager )
					)
					( objectStatus "J6M1.125" )
				)
				( pin "vss(54)"
					( attribute "PN" "123"
						( Origin gPackager )
					)
					( objectStatus "J6M1.123" )
				)
				( pin "vss(55)"
					( attribute "PN" "120"
						( Origin gPackager )
					)
					( objectStatus "J6M1.120" )
				)
				( pin "vss(56)"
					( attribute "PN" "118"
						( Origin gPackager )
					)
					( objectStatus "J6M1.118" )
				)
				( pin "vss(57)"
					( attribute "PN" "116"
						( Origin gPackager )
					)
					( objectStatus "J6M1.116" )
				)
				( pin "vss(58)"
					( attribute "PN" "114"
						( Origin gPackager )
					)
					( objectStatus "J6M1.114" )
				)
				( pin "vss(59)"
					( attribute "PN" "112"
						( Origin gPackager )
					)
					( objectStatus "J6M1.112" )
				)
				( pin "vss(60)"
					( attribute "PN" "109"
						( Origin gPackager )
					)
					( objectStatus "J6M1.109" )
				)
				( pin "vss(61)"
					( attribute "PN" "107"
						( Origin gPackager )
					)
					( objectStatus "J6M1.107" )
				)
				( pin "vss(62)"
					( attribute "PN" "105"
						( Origin gPackager )
					)
					( objectStatus "J6M1.105" )
				)
				( pin "vss(63)"
					( attribute "PN" "103"
						( Origin gPackager )
					)
					( objectStatus "J6M1.103" )
				)
				( pin "vss(64)"
					( attribute "PN" "101"
						( Origin gPackager )
					)
					( objectStatus "J6M1.101" )
				)
				( pin "vss(65)"
					( attribute "PN" "98"
						( Origin gPackager )
					)
					( objectStatus "J6M1.98" )
				)
				( pin "vss(66)"
					( attribute "PN" "96"
						( Origin gPackager )
					)
					( objectStatus "J6M1.96" )
				)
				( pin "vss(67)"
					( attribute "PN" "94"
						( Origin gPackager )
					)
					( objectStatus "J6M1.94" )
				)
				( pin "vss(68)"
					( attribute "PN" "57"
						( Origin gPackager )
					)
					( objectStatus "J6M1.57" )
				)
				( pin "vss(69)"
					( attribute "PN" "55"
						( Origin gPackager )
					)
					( objectStatus "J6M1.55" )
				)
				( pin "vss(70)"
					( attribute "PN" "53"
						( Origin gPackager )
					)
					( objectStatus "J6M1.53" )
				)
				( pin "vss(71)"
					( attribute "PN" "50"
						( Origin gPackager )
					)
					( objectStatus "J6M1.50" )
				)
				( pin "vss(72)"
					( attribute "PN" "48"
						( Origin gPackager )
					)
					( objectStatus "J6M1.48" )
				)
				( pin "vss(73)"
					( attribute "PN" "46"
						( Origin gPackager )
					)
					( objectStatus "J6M1.46" )
				)
				( pin "vss(74)"
					( attribute "PN" "44"
						( Origin gPackager )
					)
					( objectStatus "J6M1.44" )
				)
				( pin "vss(75)"
					( attribute "PN" "42"
						( Origin gPackager )
					)
					( objectStatus "J6M1.42" )
				)
				( pin "vss(76)"
					( attribute "PN" "39"
						( Origin gPackager )
					)
					( objectStatus "J6M1.39" )
				)
				( pin "vss(77)"
					( attribute "PN" "37"
						( Origin gPackager )
					)
					( objectStatus "J6M1.37" )
				)
				( pin "vss(78)"
					( attribute "PN" "35"
						( Origin gPackager )
					)
					( objectStatus "J6M1.35" )
				)
				( pin "vss(79)"
					( attribute "PN" "33"
						( Origin gPackager )
					)
					( objectStatus "J6M1.33" )
				)
				( pin "vss(80)"
					( attribute "PN" "31"
						( Origin gPackager )
					)
					( objectStatus "J6M1.31" )
				)
				( pin "vss(81)"
					( attribute "PN" "28"
						( Origin gPackager )
					)
					( objectStatus "J6M1.28" )
				)
				( pin "vss(82)"
					( attribute "PN" "26"
						( Origin gPackager )
					)
					( objectStatus "J6M1.26" )
				)
				( pin "vss(83)"
					( attribute "PN" "24"
						( Origin gPackager )
					)
					( objectStatus "J6M1.24" )
				)
				( pin "vss(84)"
					( attribute "PN" "22"
						( Origin gPackager )
					)
					( objectStatus "J6M1.22" )
				)
				( pin "vss(85)"
					( attribute "PN" "20"
						( Origin gPackager )
					)
					( objectStatus "J6M1.20" )
				)
				( pin "vss(86)"
					( attribute "PN" "17"
						( Origin gPackager )
					)
					( objectStatus "J6M1.17" )
				)
				( pin "vss(87)"
					( attribute "PN" "15"
						( Origin gPackager )
					)
					( objectStatus "J6M1.15" )
				)
				( pin "vss(88)"
					( attribute "PN" "13"
						( Origin gPackager )
					)
					( objectStatus "J6M1.13" )
				)
				( pin "vss(89)"
					( attribute "PN" "11"
						( Origin gPackager )
					)
					( objectStatus "J6M1.11" )
				)
				( pin "vss(90)"
					( attribute "PN" "9"
						( Origin gPackager )
					)
					( objectStatus "J6M1.9" )
				)
				( pin "vss(91)"
					( attribute "PN" "6"
						( Origin gPackager )
					)
					( objectStatus "J6M1.6" )
				)
				( pin "vss(92)"
					( attribute "PN" "4"
						( Origin gPackager )
					)
					( objectStatus "J6M1.4" )
				)
				( pin "vss(93)"
					( attribute "PN" "2"
						( Origin gPackager )
					)
					( objectStatus "J6M1.2" )
				)
			)
			( gate "@baseboard_fab2_lib.baseboard_fab2(sch_1):page50_i46"
				( attribute "BOM_COST" "MEM"
					( Origin gFrontEnd )
				)
				( attribute "CDS_LIB" "mstr_sconn"
					( Origin gPackager )
				)
				( attribute "CDS_LOCATION" "J6M1"
					( Origin gPackager )
				)
				( attribute "CDS_SEC" "2"
					( Origin gPackager )
				)
				( attribute "LOCATION" "J6M1"
					( Origin gFrontEnd )
				)
				( attribute "MATERIAL" "SCONN"
					( Origin gFrontEnd )
				)
				( attribute "PACK_TYPE" "PIP"
					( Origin gFrontEnd )
				)
				( attribute "PART_NUMBER" "H44441-003"
					( Origin gFrontEnd )
				)
				( attribute "PHYS_PAGE" "50"
					( Origin gFrontEnd )
				)
				( attribute "ROOM" "DDR4_CH_D"
					( Origin gFrontEnd )
				)
				( attribute "ROT" "0"
					( Origin gFrontEnd )
				)
				( attribute "SEC" "2"
					( Origin gFrontEnd )
				)
				( attribute "SEC_TYPE" "PIP"
					( Origin gFrontEnd )
				)
				( attribute "VER" "2"
					( Origin gFrontEnd )
				)
				( attribute "XY" "(3400,3950)"
					( Origin gFrontEnd )
				)
				( attribute "CHIPS_PART_NAME" "SCONN288_H44441003"
					( Origin gPackager )
				)
				( attribute "CDS_PART_NAME" "SCONN288_H44441003_PIP-SCONN,HA"
					( Origin gPackager )
				)
				( objectStatus "J6M1" )
				( pin "dqs0n"
					( attribute "PN" "152"
						( Origin gPackager )
					)
					( objectStatus "J6M1.152" )
				)
				( pin "dqs0p"
					( attribute "PN" "153"
						( Origin gPackager )
					)
					( objectStatus "J6M1.153" )
				)
				( pin "dqs1n"
					( attribute "PN" "163"
						( Origin gPackager )
					)
					( objectStatus "J6M1.163" )
				)
				( pin "dqs1p"
					( attribute "PN" "164"
						( Origin gPackager )
					)
					( objectStatus "J6M1.164" )
				)
				( pin "dqs2n"
					( attribute "PN" "174"
						( Origin gPackager )
					)
					( objectStatus "J6M1.174" )
				)
				( pin "dqs2p"
					( attribute "PN" "175"
						( Origin gPackager )
					)
					( objectStatus "J6M1.175" )
				)
				( pin "dqs3n"
					( attribute "PN" "185"
						( Origin gPackager )
					)
					( objectStatus "J6M1.185" )
				)
				( pin "dqs3p"
					( attribute "PN" "186"
						( Origin gPackager )
					)
					( objectStatus "J6M1.186" )
				)
				( pin "dqs4n"
					( attribute "PN" "244"
						( Origin gPackager )
					)
					( objectStatus "J6M1.244" )
				)
				( pin "dqs4p"
					( attribute "PN" "245"
						( Origin gPackager )
					)
					( objectStatus "J6M1.245" )
				)
				( pin "dqs5n"
					( attribute "PN" "255"
						( Origin gPackager )
					)
					( objectStatus "J6M1.255" )
				)
				( pin "dqs5p"
					( attribute "PN" "256"
						( Origin gPackager )
					)
					( objectStatus "J6M1.256" )
				)
				( pin "dqs6n"
					( attribute "PN" "266"
						( Origin gPackager )
					)
					( objectStatus "J6M1.266" )
				)
				( pin "dqs6p"
					( attribute "PN" "267"
						( Origin gPackager )
					)
					( objectStatus "J6M1.267" )
				)
				( pin "dqs7n"
					( attribute "PN" "277"
						( Origin gPackager )
					)
					( objectStatus "J6M1.277" )
				)
				( pin "dqs7p"
					( attribute "PN" "278"
						( Origin gPackager )
					)
					( objectStatus "J6M1.278" )
				)
				( pin "dqs8n"
					( attribute "PN" "196"
						( Origin gPackager )
					)
					( objectStatus "J6M1.196" )
				)
				( pin "dqs8p"
					( attribute "PN" "197"
						( Origin gPackager )
					)
					( objectStatus "J6M1.197" )
				)
				( pin "dqs9n"
					( attribute "PN" "8"
						( Origin gPackager )
					)
					( objectStatus "J6M1.8" )
				)
				( pin "dqs9p"
					( attribute "PN" "7"
						( Origin gPackager )
					)
					( objectStatus "J6M1.7" )
				)
				( pin "dqs10n"
					( attribute "PN" "19"
						( Origin gPackager )
					)
					( objectStatus "J6M1.19" )
				)
				( pin "dqs10p"
					( attribute "PN" "18"
						( Origin gPackager )
					)
					( objectStatus "J6M1.18" )
				)
				( pin "dqs11n"
					( attribute "PN" "30"
						( Origin gPackager )
					)
					( objectStatus "J6M1.30" )
				)
				( pin "dqs11p"
					( attribute "PN" "29"
						( Origin gPackager )
					)
					( objectStatus "J6M1.29" )
				)
				( pin "dqs12n"
					( attribute "PN" "41"
						( Origin gPackager )
					)
					( objectStatus "J6M1.41" )
				)
				( pin "dqs12p"
					( attribute "PN" "40"
						( Origin gPackager )
					)
					( objectStatus "J6M1.40" )
				)
				( pin "dqs13n"
					( attribute "PN" "100"
						( Origin gPackager )
					)
					( objectStatus "J6M1.100" )
				)
				( pin "dqs13p"
					( attribute "PN" "99"
						( Origin gPackager )
					)
					( objectStatus "J6M1.99" )
				)
				( pin "dqs14n"
					( attribute "PN" "111"
						( Origin gPackager )
					)
					( objectStatus "J6M1.111" )
				)
				( pin "dqs14p"
					( attribute "PN" "110"
						( Origin gPackager )
					)
					( objectStatus "J6M1.110" )
				)
				( pin "dqs15n"
					( attribute "PN" "122"
						( Origin gPackager )
					)
					( objectStatus "J6M1.122" )
				)
				( pin "dqs15p"
					( attribute "PN" "121"
						( Origin gPackager )
					)
					( objectStatus "J6M1.121" )
				)
				( pin "dqs16n"
					( attribute "PN" "133"
						( Origin gPackager )
					)
					( objectStatus "J6M1.133" )
				)
				( pin "dqs16p"
					( attribute "PN" "132"
						( Origin gPackager )
					)
					( objectStatus "J6M1.132" )
				)
				( pin "dqs17n"
					( attribute "PN" "52"
						( Origin gPackager )
					)
					( objectStatus "J6M1.52" )
				)
				( pin "dqs17p"
					( attribute "PN" "51"
						( Origin gPackager )
					)
					( objectStatus "J6M1.51" )
				)
			)
			( gate "@baseboard_fab2_lib.baseboard_fab2(sch_1):page50_i50"
				( attribute "BOM_COST" "MEM"
					( Origin gFrontEnd )
				)
				( attribute "CDS_LIB" "mstr_sconn"
					( Origin gPackager )
				)
				( attribute "CDS_LOCATION" "J6M1"
					( Origin gPackager )
				)
				( attribute "CDS_SEC" "4"
					( Origin gPackager )
				)
				( attribute "LOCATION" "J6M1"
					( Origin gFrontEnd )
				)
				( attribute "MATERIAL" "SCONN"
					( Origin gFrontEnd )
				)
				( attribute "PACK_TYPE" "PIP"
					( Origin gFrontEnd )
				)
				( attribute "PART_NUMBER" "H44441-003"
					( Origin gFrontEnd )
				)
				( attribute "PHYS_PAGE" "50"
					( Origin gFrontEnd )
				)
				( attribute "ROOM" "DDR4_CH_D"
					( Origin gFrontEnd )
				)
				( attribute "ROT" "0"
					( Origin gFrontEnd )
				)
				( attribute "SEC" "4"
					( Origin gFrontEnd )
				)
				( attribute "SEC_TYPE" "PIP"
					( Origin gFrontEnd )
				)
				( attribute "VER" "4"
					( Origin gFrontEnd )
				)
				( attribute "XY" "(3400,1550)"
					( Origin gFrontEnd )
				)
				( attribute "CHIPS_PART_NAME" "SCONN288_H44441003"
					( Origin gPackager )
				)
				( attribute "CDS_PART_NAME" "SCONN288_H44441003_PIP-SCONN,HA"
					( Origin gPackager )
				)
				( objectStatus "J6M1" )
				( pin "\12v\(0)"
					( attribute "PN" "145"
						( Origin gPackager )
					)
					( objectStatus "J6M1.145" )
				)
				( pin "\12v\(1)"
					( attribute "PN" "1"
						( Origin gPackager )
					)
					( objectStatus "J6M1.1" )
				)
				( pin "vdd(0)"
					( attribute "PN" "236"
						( Origin gPackager )
					)
					( objectStatus "J6M1.236" )
				)
				( pin "vdd(1)"
					( attribute "PN" "233"
						( Origin gPackager )
					)
					( objectStatus "J6M1.233" )
				)
				( pin "vdd(2)"
					( attribute "PN" "231"
						( Origin gPackager )
					)
					( objectStatus "J6M1.231" )
				)
				( pin "vdd(3)"
					( attribute "PN" "229"
						( Origin gPackager )
					)
					( objectStatus "J6M1.229" )
				)
				( pin "vdd(4)"
					( attribute "PN" "226"
						( Origin gPackager )
					)
					( objectStatus "J6M1.226" )
				)
				( pin "vdd(5)"
					( attribute "PN" "223"
						( Origin gPackager )
					)
					( objectStatus "J6M1.223" )
				)
				( pin "vdd(6)"
					( attribute "PN" "220"
						( Origin gPackager )
					)
					( objectStatus "J6M1.220" )
				)
				( pin "vdd(7)"
					( attribute "PN" "217"
						( Origin gPackager )
					)
					( objectStatus "J6M1.217" )
				)
				( pin "vdd(8)"
					( attribute "PN" "215"
						( Origin gPackager )
					)
					( objectStatus "J6M1.215" )
				)
				( pin "vdd(9)"
					( attribute "PN" "212"
						( Origin gPackager )
					)
					( objectStatus "J6M1.212" )
				)
				( pin "vdd(10)"
					( attribute "PN" "209"
						( Origin gPackager )
					)
					( objectStatus "J6M1.209" )
				)
				( pin "vdd(11)"
					( attribute "PN" "206"
						( Origin gPackager )
					)
					( objectStatus "J6M1.206" )
				)
				( pin "vdd(12)"
					( attribute "PN" "204"
						( Origin gPackager )
					)
					( objectStatus "J6M1.204" )
				)
				( pin "vdd(13)"
					( attribute "PN" "92"
						( Origin gPackager )
					)
					( objectStatus "J6M1.92" )
				)
				( pin "vdd(14)"
					( attribute "PN" "90"
						( Origin gPackager )
					)
					( objectStatus "J6M1.90" )
				)
				( pin "vdd(15)"
					( attribute "PN" "88"
						( Origin gPackager )
					)
					( objectStatus "J6M1.88" )
				)
				( pin "vdd(16)"
					( attribute "PN" "85"
						( Origin gPackager )
					)
					( objectStatus "J6M1.85" )
				)
				( pin "vdd(17)"
					( attribute "PN" "83"
						( Origin gPackager )
					)
					( objectStatus "J6M1.83" )
				)
				( pin "vdd(18)"
					( attribute "PN" "80"
						( Origin gPackager )
					)
					( objectStatus "J6M1.80" )
				)
				( pin "vdd(19)"
					( attribute "PN" "76"
						( Origin gPackager )
					)
					( objectStatus "J6M1.76" )
				)
				( pin "vdd(20)"
					( attribute "PN" "73"
						( Origin gPackager )
					)
					( objectStatus "J6M1.73" )
				)
				( pin "vdd(21)"
					( attribute "PN" "70"
						( Origin gPackager )
					)
					( objectStatus "J6M1.70" )
				)
				( pin "vdd(22)"
					( attribute "PN" "67"
						( Origin gPackager )
					)
					( objectStatus "J6M1.67" )
				)
				( pin "vdd(23)"
					( attribute "PN" "64"
						( Origin gPackager )
					)
					( objectStatus "J6M1.64" )
				)
				( pin "vdd(24)"
					( attribute "PN" "61"
						( Origin gPackager )
					)
					( objectStatus "J6M1.61" )
				)
				( pin "vdd(25)"
					( attribute "PN" "59"
						( Origin gPackager )
					)
					( objectStatus "J6M1.59" )
				)
				( pin "vpp(0)"
					( attribute "PN" "287"
						( Origin gPackager )
					)
					( objectStatus "J6M1.287" )
				)
				( pin "vpp(1)"
					( attribute "PN" "286"
						( Origin gPackager )
					)
					( objectStatus "J6M1.286" )
				)
				( pin "vpp(2)"
					( attribute "PN" "288"
						( Origin gPackager )
					)
					( objectStatus "J6M1.288" )
				)
				( pin "vpp(3)"
					( attribute "PN" "143"
						( Origin gPackager )
					)
					( objectStatus "J6M1.143" )
				)
				( pin "vpp(4)"
					( attribute "PN" "142"
						( Origin gPackager )
					)
					( objectStatus "J6M1.142" )
				)
				( pin "vtt(0)"
					( attribute "PN" "221"
						( Origin gPackager )
					)
					( objectStatus "J6M1.221" )
				)
				( pin "vtt(1)"
					( attribute "PN" "77"
						( Origin gPackager )
					)
					( objectStatus "J6M1.77" )
				)
			)
			( gate "@baseboard_fab2_lib.baseboard_fab2(sch_1):page50_i158"
				( attribute "BOM_COST" "MEM"
					( Origin gFrontEnd )
				)
				( attribute "CDS_LIB" "mstr_sconn"
					( Origin gPackager )
				)
				( attribute "CDS_LOCATION" "J6M1"
					( Origin gPackager )
				)
				( attribute "CDS_SEC" "1"
					( Origin gPackager )
				)
				( attribute "LOCATION" "J6M1"
					( Origin gFrontEnd )
				)
				( attribute "MATERIAL" "SCONN"
					( Origin gFrontEnd )
				)
				( attribute "PACK_TYPE" "PIP"
					( Origin gFrontEnd )
				)
				( attribute "PART_NUMBER" "H44441-003"
					( Origin gFrontEnd )
				)
				( attribute "PHYS_PAGE" "50"
					( Origin gFrontEnd )
				)
				( attribute "ROOM" "DDR4_CH_D"
					( Origin gFrontEnd )
				)
				( attribute "ROT" "0"
					( Origin gFrontEnd )
				)
				( attribute "SEC" "1"
					( Origin gFrontEnd )
				)
				( attribute "SEC_TYPE" "PIP"
					( Origin gFrontEnd )
				)
				( attribute "VER" "1"
					( Origin gFrontEnd )
				)
				( attribute "XY" "(950,3100)"
					( Origin gFrontEnd )
				)
				( attribute "CHIPS_PART_NAME" "SCONN288_H44441003"
					( Origin gPackager )
				)
				( attribute "CDS_PART_NAME" "SCONN288_H44441003_PIP-SCONN,HA"
					( Origin gPackager )
				)
				( objectStatus "J6M1" )
				( pin "a0"
					( attribute "PN" "79"
						( Origin gPackager )
					)
					( objectStatus "J6M1.79" )
				)
				( pin "a1"
					( attribute "PN" "72"
						( Origin gPackager )
					)
					( objectStatus "J6M1.72" )
				)
				( pin "a2"
					( attribute "PN" "216"
						( Origin gPackager )
					)
					( objectStatus "J6M1.216" )
				)
				( pin "a3"
					( attribute "PN" "71"
						( Origin gPackager )
					)
					( objectStatus "J6M1.71" )
				)
				( pin "a4"
					( attribute "PN" "214"
						( Origin gPackager )
					)
					( objectStatus "J6M1.214" )
				)
				( pin "a5"
					( attribute "PN" "213"
						( Origin gPackager )
					)
					( objectStatus "J6M1.213" )
				)
				( pin "a6"
					( attribute "PN" "69"
						( Origin gPackager )
					)
					( objectStatus "J6M1.69" )
				)
				( pin "a7"
					( attribute "PN" "211"
						( Origin gPackager )
					)
					( objectStatus "J6M1.211" )
				)
				( pin "a8"
					( attribute "PN" "68"
						( Origin gPackager )
					)
					( objectStatus "J6M1.68" )
				)
				( pin "a9"
					( attribute "PN" "66"
						( Origin gPackager )
					)
					( objectStatus "J6M1.66" )
				)
				( pin "a10"
					( attribute "PN" "225"
						( Origin gPackager )
					)
					( objectStatus "J6M1.225" )
				)
				( pin "a11"
					( attribute "PN" "210"
						( Origin gPackager )
					)
					( objectStatus "J6M1.210" )
				)
				( pin "a12"
					( attribute "PN" "65"
						( Origin gPackager )
					)
					( objectStatus "J6M1.65" )
				)
				( pin "a13"
					( attribute "PN" "232"
						( Origin gPackager )
					)
					( objectStatus "J6M1.232" )
				)
				( pin "a14_we_n"
					( attribute "PN" "228"
						( Origin gPackager )
					)
					( objectStatus "J6M1.228" )
				)
				( pin "a15_cas_n"
					( attribute "PN" "86"
						( Origin gPackager )
					)
					( objectStatus "J6M1.86" )
				)
				( pin "a16_ras_n"
					( attribute "PN" "82"
						( Origin gPackager )
					)
					( objectStatus "J6M1.82" )
				)
				( pin "a17"
					( attribute "PN" "234"
						( Origin gPackager )
					)
					( objectStatus "J6M1.234" )
				)
				( pin "act_n"
					( attribute "PN" "62"
						( Origin gPackager )
					)
					( objectStatus "J6M1.62" )
				)
				( pin "alert_n"
					( attribute "PN" "208"
						( Origin gPackager )
					)
					( objectStatus "J6M1.208" )
				)
				( pin "ba(0)"
					( attribute "PN" "81"
						( Origin gPackager )
					)
					( objectStatus "J6M1.81" )
				)
				( pin "ba(1)"
					( attribute "PN" "224"
						( Origin gPackager )
					)
					( objectStatus "J6M1.224" )
				)
				( pin "bg(0)"
					( attribute "PN" "63"
						( Origin gPackager )
					)
					( objectStatus "J6M1.63" )
				)
				( pin "bg(1)"
					( attribute "PN" "207"
						( Origin gPackager )
					)
					( objectStatus "J6M1.207" )
				)
				( pin "c(2)"
					( attribute "PN" "235"
						( Origin gPackager )
					)
					( objectStatus "J6M1.235" )
				)
				( pin "cb(0)"
					( attribute "PN" "49"
						( Origin gPackager )
					)
					( objectStatus "J6M1.49" )
				)
				( pin "cb(1)"
					( attribute "PN" "194"
						( Origin gPackager )
					)
					( objectStatus "J6M1.194" )
				)
				( pin "cb(2)"
					( attribute "PN" "56"
						( Origin gPackager )
					)
					( objectStatus "J6M1.56" )
				)
				( pin "cb(3)"
					( attribute "PN" "201"
						( Origin gPackager )
					)
					( objectStatus "J6M1.201" )
				)
				( pin "cb(4)"
					( attribute "PN" "47"
						( Origin gPackager )
					)
					( objectStatus "J6M1.47" )
				)
				( pin "cb(5)"
					( attribute "PN" "192"
						( Origin gPackager )
					)
					( objectStatus "J6M1.192" )
				)
				( pin "cb(6)"
					( attribute "PN" "54"
						( Origin gPackager )
					)
					( objectStatus "J6M1.54" )
				)
				( pin "cb(7)"
					( attribute "PN" "199"
						( Origin gPackager )
					)
					( objectStatus "J6M1.199" )
				)
				( pin "ck0n"
					( attribute "PN" "75"
						( Origin gPackager )
					)
					( objectStatus "J6M1.75" )
				)
				( pin "ck0p"
					( attribute "PN" "74"
						( Origin gPackager )
					)
					( objectStatus "J6M1.74" )
				)
				( pin "ck1n"
					( attribute "PN" "219"
						( Origin gPackager )
					)
					( objectStatus "J6M1.219" )
				)
				( pin "ck1p"
					( attribute "PN" "218"
						( Origin gPackager )
					)
					( objectStatus "J6M1.218" )
				)
				( pin "cke(0)"
					( attribute "PN" "60"
						( Origin gPackager )
					)
					( objectStatus "J6M1.60" )
				)
				( pin "cke(1)"
					( attribute "PN" "203"
						( Origin gPackager )
					)
					( objectStatus "J6M1.203" )
				)
				( pin "dq(0)"
					( attribute "PN" "5"
						( Origin gPackager )
					)
					( objectStatus "J6M1.5" )
				)
				( pin "dq(1)"
					( attribute "PN" "150"
						( Origin gPackager )
					)
					( objectStatus "J6M1.150" )
				)
				( pin "dq(2)"
					( attribute "PN" "12"
						( Origin gPackager )
					)
					( objectStatus "J6M1.12" )
				)
				( pin "dq(3)"
					( attribute "PN" "157"
						( Origin gPackager )
					)
					( objectStatus "J6M1.157" )
				)
				( pin "dq(4)"
					( attribute "PN" "3"
						( Origin gPackager )
					)
					( objectStatus "J6M1.3" )
				)
				( pin "dq(5)"
					( attribute "PN" "148"
						( Origin gPackager )
					)
					( objectStatus "J6M1.148" )
				)
				( pin "dq(6)"
					( attribute "PN" "10"
						( Origin gPackager )
					)
					( objectStatus "J6M1.10" )
				)
				( pin "dq(7)"
					( attribute "PN" "155"
						( Origin gPackager )
					)
					( objectStatus "J6M1.155" )
				)
				( pin "dq(8)"
					( attribute "PN" "16"
						( Origin gPackager )
					)
					( objectStatus "J6M1.16" )
				)
				( pin "dq(9)"
					( attribute "PN" "161"
						( Origin gPackager )
					)
					( objectStatus "J6M1.161" )
				)
				( pin "dq(10)"
					( attribute "PN" "23"
						( Origin gPackager )
					)
					( objectStatus "J6M1.23" )
				)
				( pin "dq(11)"
					( attribute "PN" "168"
						( Origin gPackager )
					)
					( objectStatus "J6M1.168" )
				)
				( pin "dq(12)"
					( attribute "PN" "14"
						( Origin gPackager )
					)
					( objectStatus "J6M1.14" )
				)
				( pin "dq(13)"
					( attribute "PN" "159"
						( Origin gPackager )
					)
					( objectStatus "J6M1.159" )
				)
				( pin "dq(14)"
					( attribute "PN" "21"
						( Origin gPackager )
					)
					( objectStatus "J6M1.21" )
				)
				( pin "dq(15)"
					( attribute "PN" "166"
						( Origin gPackager )
					)
					( objectStatus "J6M1.166" )
				)
				( pin "dq(16)"
					( attribute "PN" "27"
						( Origin gPackager )
					)
					( objectStatus "J6M1.27" )
				)
				( pin "dq(17)"
					( attribute "PN" "172"
						( Origin gPackager )
					)
					( objectStatus "J6M1.172" )
				)
				( pin "dq(18)"
					( attribute "PN" "34"
						( Origin gPackager )
					)
					( objectStatus "J6M1.34" )
				)
				( pin "dq(19)"
					( attribute "PN" "179"
						( Origin gPackager )
					)
					( objectStatus "J6M1.179" )
				)
				( pin "dq(20)"
					( attribute "PN" "25"
						( Origin gPackager )
					)
					( objectStatus "J6M1.25" )
				)
				( pin "dq(21)"
					( attribute "PN" "170"
						( Origin gPackager )
					)
					( objectStatus "J6M1.170" )
				)
				( pin "dq(22)"
					( attribute "PN" "32"
						( Origin gPackager )
					)
					( objectStatus "J6M1.32" )
				)
				( pin "dq(23)"
					( attribute "PN" "177"
						( Origin gPackager )
					)
					( objectStatus "J6M1.177" )
				)
				( pin "dq(24)"
					( attribute "PN" "38"
						( Origin gPackager )
					)
					( objectStatus "J6M1.38" )
				)
				( pin "dq(25)"
					( attribute "PN" "183"
						( Origin gPackager )
					)
					( objectStatus "J6M1.183" )
				)
				( pin "dq(26)"
					( attribute "PN" "45"
						( Origin gPackager )
					)
					( objectStatus "J6M1.45" )
				)
				( pin "dq(27)"
					( attribute "PN" "190"
						( Origin gPackager )
					)
					( objectStatus "J6M1.190" )
				)
				( pin "dq(28)"
					( attribute "PN" "36"
						( Origin gPackager )
					)
					( objectStatus "J6M1.36" )
				)
				( pin "dq(29)"
					( attribute "PN" "181"
						( Origin gPackager )
					)
					( objectStatus "J6M1.181" )
				)
				( pin "dq(30)"
					( attribute "PN" "43"
						( Origin gPackager )
					)
					( objectStatus "J6M1.43" )
				)
				( pin "dq(31)"
					( attribute "PN" "188"
						( Origin gPackager )
					)
					( objectStatus "J6M1.188" )
				)
				( pin "dq(32)"
					( attribute "PN" "97"
						( Origin gPackager )
					)
					( objectStatus "J6M1.97" )
				)
				( pin "dq(33)"
					( attribute "PN" "242"
						( Origin gPackager )
					)
					( objectStatus "J6M1.242" )
				)
				( pin "dq(34)"
					( attribute "PN" "104"
						( Origin gPackager )
					)
					( objectStatus "J6M1.104" )
				)
				( pin "dq(35)"
					( attribute "PN" "249"
						( Origin gPackager )
					)
					( objectStatus "J6M1.249" )
				)
				( pin "dq(36)"
					( attribute "PN" "95"
						( Origin gPackager )
					)
					( objectStatus "J6M1.95" )
				)
				( pin "dq(37)"
					( attribute "PN" "240"
						( Origin gPackager )
					)
					( objectStatus "J6M1.240" )
				)
				( pin "dq(38)"
					( attribute "PN" "102"
						( Origin gPackager )
					)
					( objectStatus "J6M1.102" )
				)
				( pin "dq(39)"
					( attribute "PN" "247"
						( Origin gPackager )
					)
					( objectStatus "J6M1.247" )
				)
				( pin "dq(40)"
					( attribute "PN" "108"
						( Origin gPackager )
					)
					( objectStatus "J6M1.108" )
				)
				( pin "dq(41)"
					( attribute "PN" "253"
						( Origin gPackager )
					)
					( objectStatus "J6M1.253" )
				)
				( pin "dq(42)"
					( attribute "PN" "115"
						( Origin gPackager )
					)
					( objectStatus "J6M1.115" )
				)
				( pin "dq(43)"
					( attribute "PN" "260"
						( Origin gPackager )
					)
					( objectStatus "J6M1.260" )
				)
				( pin "dq(44)"
					( attribute "PN" "106"
						( Origin gPackager )
					)
					( objectStatus "J6M1.106" )
				)
				( pin "dq(45)"
					( attribute "PN" "251"
						( Origin gPackager )
					)
					( objectStatus "J6M1.251" )
				)
				( pin "dq(46)"
					( attribute "PN" "113"
						( Origin gPackager )
					)
					( objectStatus "J6M1.113" )
				)
				( pin "dq(47)"
					( attribute "PN" "258"
						( Origin gPackager )
					)
					( objectStatus "J6M1.258" )
				)
				( pin "dq(48)"
					( attribute "PN" "119"
						( Origin gPackager )
					)
					( objectStatus "J6M1.119" )
				)
				( pin "dq(49)"
					( attribute "PN" "264"
						( Origin gPackager )
					)
					( objectStatus "J6M1.264" )
				)
				( pin "dq(50)"
					( attribute "PN" "126"
						( Origin gPackager )
					)
					( objectStatus "J6M1.126" )
				)
				( pin "dq(51)"
					( attribute "PN" "271"
						( Origin gPackager )
					)
					( objectStatus "J6M1.271" )
				)
				( pin "dq(52)"
					( attribute "PN" "117"
						( Origin gPackager )
					)
					( objectStatus "J6M1.117" )
				)
				( pin "dq(53)"
					( attribute "PN" "262"
						( Origin gPackager )
					)
					( objectStatus "J6M1.262" )
				)
				( pin "dq(54)"
					( attribute "PN" "124"
						( Origin gPackager )
					)
					( objectStatus "J6M1.124" )
				)
				( pin "dq(55)"
					( attribute "PN" "269"
						( Origin gPackager )
					)
					( objectStatus "J6M1.269" )
				)
				( pin "dq(56)"
					( attribute "PN" "130"
						( Origin gPackager )
					)
					( objectStatus "J6M1.130" )
				)
				( pin "dq(57)"
					( attribute "PN" "275"
						( Origin gPackager )
					)
					( objectStatus "J6M1.275" )
				)
				( pin "dq(58)"
					( attribute "PN" "137"
						( Origin gPackager )
					)
					( objectStatus "J6M1.137" )
				)
				( pin "dq(59)"
					( attribute "PN" "282"
						( Origin gPackager )
					)
					( objectStatus "J6M1.282" )
				)
				( pin "dq(60)"
					( attribute "PN" "128"
						( Origin gPackager )
					)
					( objectStatus "J6M1.128" )
				)
				( pin "dq(61)"
					( attribute "PN" "273"
						( Origin gPackager )
					)
					( objectStatus "J6M1.273" )
				)
				( pin "dq(62)"
					( attribute "PN" "135"
						( Origin gPackager )
					)
					( objectStatus "J6M1.135" )
				)
				( pin "dq(63)"
					( attribute "PN" "280"
						( Origin gPackager )
					)
					( objectStatus "J6M1.280" )
				)
				( pin "event_n"
					( attribute "PN" "78"
						( Origin gPackager )
					)
					( objectStatus "J6M1.78" )
				)
				( pin "odt(0)"
					( attribute "PN" "87"
						( Origin gPackager )
					)
					( objectStatus "J6M1.87" )
				)
				( pin "odt(1)"
					( attribute "PN" "91"
						( Origin gPackager )
					)
					( objectStatus "J6M1.91" )
				)
				( pin "par"
					( attribute "PN" "222"
						( Origin gPackager )
					)
					( objectStatus "J6M1.222" )
				)
				( pin "reset_n"
					( attribute "PN" "58"
						( Origin gPackager )
					)
					( objectStatus "J6M1.58" )
				)
				( pin "rfu(0)"
					( attribute "PN" "205"
						( Origin gPackager )
					)
					( objectStatus "J6M1.205" )
				)
				( pin "rfu(1)"
					( attribute "PN" "227"
						( Origin gPackager )
					)
					( objectStatus "J6M1.227" )
				)
				( pin "rfu(2)"
					( attribute "PN" "144"
						( Origin gPackager )
					)
					( objectStatus "J6M1.144" )
				)
				( pin "s0_n"
					( attribute "PN" "84"
						( Origin gPackager )
					)
					( objectStatus "J6M1.84" )
				)
				( pin "s1_n"
					( attribute "PN" "89"
						( Origin gPackager )
					)
					( objectStatus "J6M1.89" )
				)
				( pin "s2_n_c(0)"
					( attribute "PN" "93"
						( Origin gPackager )
					)
					( objectStatus "J6M1.93" )
				)
				( pin "s3_n_c(1)"
					( attribute "PN" "237"
						( Origin gPackager )
					)
					( objectStatus "J6M1.237" )
				)
				( pin "sa(0)"
					( attribute "PN" "139"
						( Origin gPackager )
					)
					( objectStatus "J6M1.139" )
				)
				( pin "sa(1)"
					( attribute "PN" "140"
						( Origin gPackager )
					)
					( objectStatus "J6M1.140" )
				)
				( pin "sa(2)"
					( attribute "PN" "238"
						( Origin gPackager )
					)
					( objectStatus "J6M1.238" )
				)
				( pin "save_n_nc"
					( attribute "PN" "230"
						( Origin gPackager )
					)
					( objectStatus "J6M1.230" )
				)
				( pin "scl"
					( attribute "PN" "141"
						( Origin gPackager )
					)
					( objectStatus "J6M1.141" )
				)
				( pin "sda"
					( attribute "PN" "285"
						( Origin gPackager )
					)
					( objectStatus "J6M1.285" )
				)
				( pin "vddspd"
					( attribute "PN" "284"
						( Origin gPackager )
					)
					( objectStatus "J6M1.284" )
				)
				( pin "vrefca"
					( attribute "PN" "146"
						( Origin gPackager )
					)
					( objectStatus "J6M1.146" )
				)
			)
			( gate "@baseboard_fab2_lib.baseboard_fab2(sch_1):page50_i177"
				( attribute "BOM_COST" "MEM"
					( Origin gFrontEnd )
				)
				( attribute "CDS_LIB" "dev_discrete"
					( Origin gPackager )
				)
				( attribute "CDS_LOCATION" "C6M1"
					( Origin gPackager )
				)
				( attribute "CDS_SEC" "1"
					( Origin gPackager )
				)
				( attribute "LOCATION" "C6M1"
					( Origin gFrontEnd )
				)
				( attribute "MATERIAL" "X7R"
					( Origin gFrontEnd )
				)
				( attribute "PACK_TYPE" "0402V"
					( Origin gFrontEnd )
				)
				( attribute "PART_NUMBER" "A36096-045"
					( Origin gFrontEnd )
				)
				( attribute "PHYS_PAGE" "50"
					( Origin gFrontEnd )
				)
				( attribute "ROOM" "DDR4_CH_B"
					( Origin gFrontEnd )
				)
				( attribute "ROT" "2"
					( Origin gFrontEnd )
				)
				( attribute "SEC" "1"
					( Origin gPackager )
				)
				( attribute "TOLERANCE" "10%"
					( Origin gFrontEnd )
				)
				( attribute "VALUE" "0.01UF"
					( Origin gFrontEnd )
				)
				( attribute "VER" "1"
					( Origin gFrontEnd )
				)
				( attribute "VOLTAGE" "25V"
					( Units "uVoltage" "V" 1.000000)
					( Origin gFrontEnd )
				)
				( attribute "XY" "(-1200,1400)"
					( Origin gFrontEnd )
				)
				( attribute "CHIPS_PART_NAME" "CAP_A"
					( Origin gPackager )
				)
				( attribute "CDS_PART_NAME" "CAP_A_0402V-0.01UF,25V,10%,X7RA"
					( Origin gPackager )
				)
				( objectStatus "C6M1" )
				( pin "a"
					( attribute "PN" "1"
						( Origin gPackager )
					)
					( objectStatus "C6M1.1" )
				)
				( pin "b"
					( attribute "PN" "2"
						( Origin gPackager )
					)
					( objectStatus "C6M1.2" )
				)
			)
			( gate "@baseboard_fab2_lib.baseboard_fab2(sch_1):page51_i43"
				( attribute "BOM_COST" "MEM"
					( Origin gFrontEnd )
				)
				( attribute "CDS_LIB" "mstr_sconn"
					( Origin gPackager )
				)
				( attribute "CDS_LOCATION" "J4A2"
					( Origin gPackager )
				)
				( attribute "CDS_SEC" "3"
					( Origin gPackager )
				)
				( attribute "LOCATION" "J4A2"
					( Origin gFrontEnd )
				)
				( attribute "MATERIAL" "SCONN"
					( Origin gFrontEnd )
				)
				( attribute "PACK_TYPE" "PIP"
					( Origin gFrontEnd )
				)
				( attribute "PART_NUMBER" "H44441-004"
					( Origin gFrontEnd )
				)
				( attribute "PHYS_PAGE" "51"
					( Origin gFrontEnd )
				)
				( attribute "ROOM" "DDR4_CH_E"
					( Origin gFrontEnd )
				)
				( attribute "ROT" "0"
					( Origin gFrontEnd )
				)
				( attribute "SEC" "3"
					( Origin gFrontEnd )
				)
				( attribute "SEC_TYPE" "PIP"
					( Origin gFrontEnd )
				)
				( attribute "VER" "3"
					( Origin gFrontEnd )
				)
				( attribute "XY" "(1800,2500)"
					( Origin gFrontEnd )
				)
				( attribute "CHIPS_PART_NAME" "SCONN288_H44441004"
					( Origin gPackager )
				)
				( attribute "CDS_PART_NAME" "SCONN288_H44441004_PIP-SCONN,HA"
					( Origin gPackager )
				)
				( objectStatus "J4A2" )
				( pin "vss(0)"
					( attribute "PN" "283"
						( Origin gPackager )
					)
					( objectStatus "J4A2.283" )
				)
				( pin "vss(1)"
					( attribute "PN" "281"
						( Origin gPackager )
					)
					( objectStatus "J4A2.281" )
				)
				( pin "vss(2)"
					( attribute "PN" "279"
						( Origin gPackager )
					)
					( objectStatus "J4A2.279" )
				)
				( pin "vss(3)"
					( attribute "PN" "276"
						( Origin gPackager )
					)
					( objectStatus "J4A2.276" )
				)
				( pin "vss(4)"
					( attribute "PN" "274"
						( Origin gPackager )
					)
					( objectStatus "J4A2.274" )
				)
				( pin "vss(5)"
					( attribute "PN" "272"
						( Origin gPackager )
					)
					( objectStatus "J4A2.272" )
				)
				( pin "vss(6)"
					( attribute "PN" "270"
						( Origin gPackager )
					)
					( objectStatus "J4A2.270" )
				)
				( pin "vss(7)"
					( attribute "PN" "268"
						( Origin gPackager )
					)
					( objectStatus "J4A2.268" )
				)
				( pin "vss(8)"
					( attribute "PN" "265"
						( Origin gPackager )
					)
					( objectStatus "J4A2.265" )
				)
				( pin "vss(9)"
					( attribute "PN" "263"
						( Origin gPackager )
					)
					( objectStatus "J4A2.263" )
				)
				( pin "vss(10)"
					( attribute "PN" "261"
						( Origin gPackager )
					)
					( objectStatus "J4A2.261" )
				)
				( pin "vss(11)"
					( attribute "PN" "259"
						( Origin gPackager )
					)
					( objectStatus "J4A2.259" )
				)
				( pin "vss(12)"
					( attribute "PN" "257"
						( Origin gPackager )
					)
					( objectStatus "J4A2.257" )
				)
				( pin "vss(13)"
					( attribute "PN" "254"
						( Origin gPackager )
					)
					( objectStatus "J4A2.254" )
				)
				( pin "vss(14)"
					( attribute "PN" "252"
						( Origin gPackager )
					)
					( objectStatus "J4A2.252" )
				)
				( pin "vss(15)"
					( attribute "PN" "250"
						( Origin gPackager )
					)
					( objectStatus "J4A2.250" )
				)
				( pin "vss(16)"
					( attribute "PN" "248"
						( Origin gPackager )
					)
					( objectStatus "J4A2.248" )
				)
				( pin "vss(17)"
					( attribute "PN" "246"
						( Origin gPackager )
					)
					( objectStatus "J4A2.246" )
				)
				( pin "vss(18)"
					( attribute "PN" "243"
						( Origin gPackager )
					)
					( objectStatus "J4A2.243" )
				)
				( pin "vss(19)"
					( attribute "PN" "241"
						( Origin gPackager )
					)
					( objectStatus "J4A2.241" )
				)
				( pin "vss(20)"
					( attribute "PN" "239"
						( Origin gPackager )
					)
					( objectStatus "J4A2.239" )
				)
				( pin "vss(21)"
					( attribute "PN" "202"
						( Origin gPackager )
					)
					( objectStatus "J4A2.202" )
				)
				( pin "vss(22)"
					( attribute "PN" "200"
						( Origin gPackager )
					)
					( objectStatus "J4A2.200" )
				)
				( pin "vss(23)"
					( attribute "PN" "198"
						( Origin gPackager )
					)
					( objectStatus "J4A2.198" )
				)
				( pin "vss(24)"
					( attribute "PN" "195"
						( Origin gPackager )
					)
					( objectStatus "J4A2.195" )
				)
				( pin "vss(25)"
					( attribute "PN" "193"
						( Origin gPackager )
					)
					( objectStatus "J4A2.193" )
				)
				( pin "vss(26)"
					( attribute "PN" "191"
						( Origin gPackager )
					)
					( objectStatus "J4A2.191" )
				)
				( pin "vss(27)"
					( attribute "PN" "189"
						( Origin gPackager )
					)
					( objectStatus "J4A2.189" )
				)
				( pin "vss(28)"
					( attribute "PN" "187"
						( Origin gPackager )
					)
					( objectStatus "J4A2.187" )
				)
				( pin "vss(29)"
					( attribute "PN" "184"
						( Origin gPackager )
					)
					( objectStatus "J4A2.184" )
				)
				( pin "vss(30)"
					( attribute "PN" "182"
						( Origin gPackager )
					)
					( objectStatus "J4A2.182" )
				)
				( pin "vss(31)"
					( attribute "PN" "180"
						( Origin gPackager )
					)
					( objectStatus "J4A2.180" )
				)
				( pin "vss(32)"
					( attribute "PN" "178"
						( Origin gPackager )
					)
					( objectStatus "J4A2.178" )
				)
				( pin "vss(33)"
					( attribute "PN" "176"
						( Origin gPackager )
					)
					( objectStatus "J4A2.176" )
				)
				( pin "vss(34)"
					( attribute "PN" "173"
						( Origin gPackager )
					)
					( objectStatus "J4A2.173" )
				)
				( pin "vss(35)"
					( attribute "PN" "171"
						( Origin gPackager )
					)
					( objectStatus "J4A2.171" )
				)
				( pin "vss(36)"
					( attribute "PN" "169"
						( Origin gPackager )
					)
					( objectStatus "J4A2.169" )
				)
				( pin "vss(37)"
					( attribute "PN" "167"
						( Origin gPackager )
					)
					( objectStatus "J4A2.167" )
				)
				( pin "vss(38)"
					( attribute "PN" "165"
						( Origin gPackager )
					)
					( objectStatus "J4A2.165" )
				)
				( pin "vss(39)"
					( attribute "PN" "162"
						( Origin gPackager )
					)
					( objectStatus "J4A2.162" )
				)
				( pin "vss(40)"
					( attribute "PN" "160"
						( Origin gPackager )
					)
					( objectStatus "J4A2.160" )
				)
				( pin "vss(41)"
					( attribute "PN" "158"
						( Origin gPackager )
					)
					( objectStatus "J4A2.158" )
				)
				( pin "vss(42)"
					( attribute "PN" "156"
						( Origin gPackager )
					)
					( objectStatus "J4A2.156" )
				)
				( pin "vss(43)"
					( attribute "PN" "154"
						( Origin gPackager )
					)
					( objectStatus "J4A2.154" )
				)
				( pin "vss(44)"
					( attribute "PN" "151"
						( Origin gPackager )
					)
					( objectStatus "J4A2.151" )
				)
				( pin "vss(45)"
					( attribute "PN" "149"
						( Origin gPackager )
					)
					( objectStatus "J4A2.149" )
				)
				( pin "vss(46)"
					( attribute "PN" "147"
						( Origin gPackager )
					)
					( objectStatus "J4A2.147" )
				)
				( pin "vss(47)"
					( attribute "PN" "138"
						( Origin gPackager )
					)
					( objectStatus "J4A2.138" )
				)
				( pin "vss(48)"
					( attribute "PN" "136"
						( Origin gPackager )
					)
					( objectStatus "J4A2.136" )
				)
				( pin "vss(49)"
					( attribute "PN" "134"
						( Origin gPackager )
					)
					( objectStatus "J4A2.134" )
				)
				( pin "vss(50)"
					( attribute "PN" "131"
						( Origin gPackager )
					)
					( objectStatus "J4A2.131" )
				)
				( pin "vss(51)"
					( attribute "PN" "129"
						( Origin gPackager )
					)
					( objectStatus "J4A2.129" )
				)
				( pin "vss(52)"
					( attribute "PN" "127"
						( Origin gPackager )
					)
					( objectStatus "J4A2.127" )
				)
				( pin "vss(53)"
					( attribute "PN" "125"
						( Origin gPackager )
					)
					( objectStatus "J4A2.125" )
				)
				( pin "vss(54)"
					( attribute "PN" "123"
						( Origin gPackager )
					)
					( objectStatus "J4A2.123" )
				)
				( pin "vss(55)"
					( attribute "PN" "120"
						( Origin gPackager )
					)
					( objectStatus "J4A2.120" )
				)
				( pin "vss(56)"
					( attribute "PN" "118"
						( Origin gPackager )
					)
					( objectStatus "J4A2.118" )
				)
				( pin "vss(57)"
					( attribute "PN" "116"
						( Origin gPackager )
					)
					( objectStatus "J4A2.116" )
				)
				( pin "vss(58)"
					( attribute "PN" "114"
						( Origin gPackager )
					)
					( objectStatus "J4A2.114" )
				)
				( pin "vss(59)"
					( attribute "PN" "112"
						( Origin gPackager )
					)
					( objectStatus "J4A2.112" )
				)
				( pin "vss(60)"
					( attribute "PN" "109"
						( Origin gPackager )
					)
					( objectStatus "J4A2.109" )
				)
				( pin "vss(61)"
					( attribute "PN" "107"
						( Origin gPackager )
					)
					( objectStatus "J4A2.107" )
				)
				( pin "vss(62)"
					( attribute "PN" "105"
						( Origin gPackager )
					)
					( objectStatus "J4A2.105" )
				)
				( pin "vss(63)"
					( attribute "PN" "103"
						( Origin gPackager )
					)
					( objectStatus "J4A2.103" )
				)
				( pin "vss(64)"
					( attribute "PN" "101"
						( Origin gPackager )
					)
					( objectStatus "J4A2.101" )
				)
				( pin "vss(65)"
					( attribute "PN" "98"
						( Origin gPackager )
					)
					( objectStatus "J4A2.98" )
				)
				( pin "vss(66)"
					( attribute "PN" "96"
						( Origin gPackager )
					)
					( objectStatus "J4A2.96" )
				)
				( pin "vss(67)"
					( attribute "PN" "94"
						( Origin gPackager )
					)
					( objectStatus "J4A2.94" )
				)
				( pin "vss(68)"
					( attribute "PN" "57"
						( Origin gPackager )
					)
					( objectStatus "J4A2.57" )
				)
				( pin "vss(69)"
					( attribute "PN" "55"
						( Origin gPackager )
					)
					( objectStatus "J4A2.55" )
				)
				( pin "vss(70)"
					( attribute "PN" "53"
						( Origin gPackager )
					)
					( objectStatus "J4A2.53" )
				)
				( pin "vss(71)"
					( attribute "PN" "50"
						( Origin gPackager )
					)
					( objectStatus "J4A2.50" )
				)
				( pin "vss(72)"
					( attribute "PN" "48"
						( Origin gPackager )
					)
					( objectStatus "J4A2.48" )
				)
				( pin "vss(73)"
					( attribute "PN" "46"
						( Origin gPackager )
					)
					( objectStatus "J4A2.46" )
				)
				( pin "vss(74)"
					( attribute "PN" "44"
						( Origin gPackager )
					)
					( objectStatus "J4A2.44" )
				)
				( pin "vss(75)"
					( attribute "PN" "42"
						( Origin gPackager )
					)
					( objectStatus "J4A2.42" )
				)
				( pin "vss(76)"
					( attribute "PN" "39"
						( Origin gPackager )
					)
					( objectStatus "J4A2.39" )
				)
				( pin "vss(77)"
					( attribute "PN" "37"
						( Origin gPackager )
					)
					( objectStatus "J4A2.37" )
				)
				( pin "vss(78)"
					( attribute "PN" "35"
						( Origin gPackager )
					)
					( objectStatus "J4A2.35" )
				)
				( pin "vss(79)"
					( attribute "PN" "33"
						( Origin gPackager )
					)
					( objectStatus "J4A2.33" )
				)
				( pin "vss(80)"
					( attribute "PN" "31"
						( Origin gPackager )
					)
					( objectStatus "J4A2.31" )
				)
				( pin "vss(81)"
					( attribute "PN" "28"
						( Origin gPackager )
					)
					( objectStatus "J4A2.28" )
				)
				( pin "vss(82)"
					( attribute "PN" "26"
						( Origin gPackager )
					)
					( objectStatus "J4A2.26" )
				)
				( pin "vss(83)"
					( attribute "PN" "24"
						( Origin gPackager )
					)
					( objectStatus "J4A2.24" )
				)
				( pin "vss(84)"
					( attribute "PN" "22"
						( Origin gPackager )
					)
					( objectStatus "J4A2.22" )
				)
				( pin "vss(85)"
					( attribute "PN" "20"
						( Origin gPackager )
					)
					( objectStatus "J4A2.20" )
				)
				( pin "vss(86)"
					( attribute "PN" "17"
						( Origin gPackager )
					)
					( objectStatus "J4A2.17" )
				)
				( pin "vss(87)"
					( attribute "PN" "15"
						( Origin gPackager )
					)
					( objectStatus "J4A2.15" )
				)
				( pin "vss(88)"
					( attribute "PN" "13"
						( Origin gPackager )
					)
					( objectStatus "J4A2.13" )
				)
				( pin "vss(89)"
					( attribute "PN" "11"
						( Origin gPackager )
					)
					( objectStatus "J4A2.11" )
				)
				( pin "vss(90)"
					( attribute "PN" "9"
						( Origin gPackager )
					)
					( objectStatus "J4A2.9" )
				)
				( pin "vss(91)"
					( attribute "PN" "6"
						( Origin gPackager )
					)
					( objectStatus "J4A2.6" )
				)
				( pin "vss(92)"
					( attribute "PN" "4"
						( Origin gPackager )
					)
					( objectStatus "J4A2.4" )
				)
				( pin "vss(93)"
					( attribute "PN" "2"
						( Origin gPackager )
					)
					( objectStatus "J4A2.2" )
				)
			)
			( gate "@baseboard_fab2_lib.baseboard_fab2(sch_1):page51_i66"
				( attribute "BOM_COST" "MEM"
					( Origin gFrontEnd )
				)
				( attribute "CDS_LIB" "mstr_sconn"
					( Origin gPackager )
				)
				( attribute "CDS_LOCATION" "J4A2"
					( Origin gPackager )
				)
				( attribute "CDS_SEC" "2"
					( Origin gPackager )
				)
				( attribute "LOCATION" "J4A2"
					( Origin gFrontEnd )
				)
				( attribute "MATERIAL" "SCONN"
					( Origin gFrontEnd )
				)
				( attribute "PACK_TYPE" "PIP"
					( Origin gFrontEnd )
				)
				( attribute "PART_NUMBER" "H44441-004"
					( Origin gFrontEnd )
				)
				( attribute "PHYS_PAGE" "51"
					( Origin gFrontEnd )
				)
				( attribute "ROOM" "DDR4_CH_E"
					( Origin gFrontEnd )
				)
				( attribute "ROT" "0"
					( Origin gFrontEnd )
				)
				( attribute "SEC" "2"
					( Origin gFrontEnd )
				)
				( attribute "SEC_TYPE" "PIP"
					( Origin gFrontEnd )
				)
				( attribute "VER" "2"
					( Origin gFrontEnd )
				)
				( attribute "XY" "(0,4300)"
					( Origin gFrontEnd )
				)
				( attribute "CHIPS_PART_NAME" "SCONN288_H44441004"
					( Origin gPackager )
				)
				( attribute "CDS_PART_NAME" "SCONN288_H44441004_PIP-SCONN,HA"
					( Origin gPackager )
				)
				( objectStatus "J4A2" )
				( pin "dqs0n"
					( attribute "PN" "152"
						( Origin gPackager )
					)
					( objectStatus "J4A2.152" )
				)
				( pin "dqs0p"
					( attribute "PN" "153"
						( Origin gPackager )
					)
					( objectStatus "J4A2.153" )
				)
				( pin "dqs1n"
					( attribute "PN" "163"
						( Origin gPackager )
					)
					( objectStatus "J4A2.163" )
				)
				( pin "dqs1p"
					( attribute "PN" "164"
						( Origin gPackager )
					)
					( objectStatus "J4A2.164" )
				)
				( pin "dqs2n"
					( attribute "PN" "174"
						( Origin gPackager )
					)
					( objectStatus "J4A2.174" )
				)
				( pin "dqs2p"
					( attribute "PN" "175"
						( Origin gPackager )
					)
					( objectStatus "J4A2.175" )
				)
				( pin "dqs3n"
					( attribute "PN" "185"
						( Origin gPackager )
					)
					( objectStatus "J4A2.185" )
				)
				( pin "dqs3p"
					( attribute "PN" "186"
						( Origin gPackager )
					)
					( objectStatus "J4A2.186" )
				)
				( pin "dqs4n"
					( attribute "PN" "244"
						( Origin gPackager )
					)
					( objectStatus "J4A2.244" )
				)
				( pin "dqs4p"
					( attribute "PN" "245"
						( Origin gPackager )
					)
					( objectStatus "J4A2.245" )
				)
				( pin "dqs5n"
					( attribute "PN" "255"
						( Origin gPackager )
					)
					( objectStatus "J4A2.255" )
				)
				( pin "dqs5p"
					( attribute "PN" "256"
						( Origin gPackager )
					)
					( objectStatus "J4A2.256" )
				)
				( pin "dqs6n"
					( attribute "PN" "266"
						( Origin gPackager )
					)
					( objectStatus "J4A2.266" )
				)
				( pin "dqs6p"
					( attribute "PN" "267"
						( Origin gPackager )
					)
					( objectStatus "J4A2.267" )
				)
				( pin "dqs7n"
					( attribute "PN" "277"
						( Origin gPackager )
					)
					( objectStatus "J4A2.277" )
				)
				( pin "dqs7p"
					( attribute "PN" "278"
						( Origin gPackager )
					)
					( objectStatus "J4A2.278" )
				)
				( pin "dqs8n"
					( attribute "PN" "196"
						( Origin gPackager )
					)
					( objectStatus "J4A2.196" )
				)
				( pin "dqs8p"
					( attribute "PN" "197"
						( Origin gPackager )
					)
					( objectStatus "J4A2.197" )
				)
				( pin "dqs9n"
					( attribute "PN" "8"
						( Origin gPackager )
					)
					( objectStatus "J4A2.8" )
				)
				( pin "dqs9p"
					( attribute "PN" "7"
						( Origin gPackager )
					)
					( objectStatus "J4A2.7" )
				)
				( pin "dqs10n"
					( attribute "PN" "19"
						( Origin gPackager )
					)
					( objectStatus "J4A2.19" )
				)
				( pin "dqs10p"
					( attribute "PN" "18"
						( Origin gPackager )
					)
					( objectStatus "J4A2.18" )
				)
				( pin "dqs11n"
					( attribute "PN" "30"
						( Origin gPackager )
					)
					( objectStatus "J4A2.30" )
				)
				( pin "dqs11p"
					( attribute "PN" "29"
						( Origin gPackager )
					)
					( objectStatus "J4A2.29" )
				)
				( pin "dqs12n"
					( attribute "PN" "41"
						( Origin gPackager )
					)
					( objectStatus "J4A2.41" )
				)
				( pin "dqs12p"
					( attribute "PN" "40"
						( Origin gPackager )
					)
					( objectStatus "J4A2.40" )
				)
				( pin "dqs13n"
					( attribute "PN" "100"
						( Origin gPackager )
					)
					( objectStatus "J4A2.100" )
				)
				( pin "dqs13p"
					( attribute "PN" "99"
						( Origin gPackager )
					)
					( objectStatus "J4A2.99" )
				)
				( pin "dqs14n"
					( attribute "PN" "111"
						( Origin gPackager )
					)
					( objectStatus "J4A2.111" )
				)
				( pin "dqs14p"
					( attribute "PN" "110"
						( Origin gPackager )
					)
					( objectStatus "J4A2.110" )
				)
				( pin "dqs15n"
					( attribute "PN" "122"
						( Origin gPackager )
					)
					( objectStatus "J4A2.122" )
				)
				( pin "dqs15p"
					( attribute "PN" "121"
						( Origin gPackager )
					)
					( objectStatus "J4A2.121" )
				)
				( pin "dqs16n"
					( attribute "PN" "133"
						( Origin gPackager )
					)
					( objectStatus "J4A2.133" )
				)
				( pin "dqs16p"
					( attribute "PN" "132"
						( Origin gPackager )
					)
					( objectStatus "J4A2.132" )
				)
				( pin "dqs17n"
					( attribute "PN" "52"
						( Origin gPackager )
					)
					( objectStatus "J4A2.52" )
				)
				( pin "dqs17p"
					( attribute "PN" "51"
						( Origin gPackager )
					)
					( objectStatus "J4A2.51" )
				)
			)
			( gate "@baseboard_fab2_lib.baseboard_fab2(sch_1):page51_i111"
				( attribute "BOM_COST" "MEM"
					( Origin gFrontEnd )
				)
				( attribute "CDS_LIB" "mstr_sconn"
					( Origin gPackager )
				)
				( attribute "CDS_LOCATION" "J4A2"
					( Origin gPackager )
				)
				( attribute "CDS_SEC" "1"
					( Origin gPackager )
				)
				( attribute "LOCATION" "J4A2"
					( Origin gFrontEnd )
				)
				( attribute "MATERIAL" "SCONN"
					( Origin gFrontEnd )
				)
				( attribute "PACK_TYPE" "PIP"
					( Origin gFrontEnd )
				)
				( attribute "PART_NUMBER" "H44441-004"
					( Origin gFrontEnd )
				)
				( attribute "PHYS_PAGE" "51"
					( Origin gFrontEnd )
				)
				( attribute "ROOM" "DDR4_CH_E"
					( Origin gFrontEnd )
				)
				( attribute "ROT" "0"
					( Origin gFrontEnd )
				)
				( attribute "SEC" "1"
					( Origin gFrontEnd )
				)
				( attribute "SEC_TYPE" "PIP"
					( Origin gFrontEnd )
				)
				( attribute "VER" "1"
					( Origin gFrontEnd )
				)
				( attribute "XY" "(-2350,3250)"
					( Origin gFrontEnd )
				)
				( attribute "CHIPS_PART_NAME" "SCONN288_H44441004"
					( Origin gPackager )
				)
				( attribute "CDS_PART_NAME" "SCONN288_H44441004_PIP-SCONN,HA"
					( Origin gPackager )
				)
				( objectStatus "J4A2" )
				( pin "a0"
					( attribute "PN" "79"
						( Origin gPackager )
					)
					( objectStatus "J4A2.79" )
				)
				( pin "a1"
					( attribute "PN" "72"
						( Origin gPackager )
					)
					( objectStatus "J4A2.72" )
				)
				( pin "a2"
					( attribute "PN" "216"
						( Origin gPackager )
					)
					( objectStatus "J4A2.216" )
				)
				( pin "a3"
					( attribute "PN" "71"
						( Origin gPackager )
					)
					( objectStatus "J4A2.71" )
				)
				( pin "a4"
					( attribute "PN" "214"
						( Origin gPackager )
					)
					( objectStatus "J4A2.214" )
				)
				( pin "a5"
					( attribute "PN" "213"
						( Origin gPackager )
					)
					( objectStatus "J4A2.213" )
				)
				( pin "a6"
					( attribute "PN" "69"
						( Origin gPackager )
					)
					( objectStatus "J4A2.69" )
				)
				( pin "a7"
					( attribute "PN" "211"
						( Origin gPackager )
					)
					( objectStatus "J4A2.211" )
				)
				( pin "a8"
					( attribute "PN" "68"
						( Origin gPackager )
					)
					( objectStatus "J4A2.68" )
				)
				( pin "a9"
					( attribute "PN" "66"
						( Origin gPackager )
					)
					( objectStatus "J4A2.66" )
				)
				( pin "a10"
					( attribute "PN" "225"
						( Origin gPackager )
					)
					( objectStatus "J4A2.225" )
				)
				( pin "a11"
					( attribute "PN" "210"
						( Origin gPackager )
					)
					( objectStatus "J4A2.210" )
				)
				( pin "a12"
					( attribute "PN" "65"
						( Origin gPackager )
					)
					( objectStatus "J4A2.65" )
				)
				( pin "a13"
					( attribute "PN" "232"
						( Origin gPackager )
					)
					( objectStatus "J4A2.232" )
				)
				( pin "a14_we_n"
					( attribute "PN" "228"
						( Origin gPackager )
					)
					( objectStatus "J4A2.228" )
				)
				( pin "a15_cas_n"
					( attribute "PN" "86"
						( Origin gPackager )
					)
					( objectStatus "J4A2.86" )
				)
				( pin "a16_ras_n"
					( attribute "PN" "82"
						( Origin gPackager )
					)
					( objectStatus "J4A2.82" )
				)
				( pin "a17"
					( attribute "PN" "234"
						( Origin gPackager )
					)
					( objectStatus "J4A2.234" )
				)
				( pin "act_n"
					( attribute "PN" "62"
						( Origin gPackager )
					)
					( objectStatus "J4A2.62" )
				)
				( pin "alert_n"
					( attribute "PN" "208"
						( Origin gPackager )
					)
					( objectStatus "J4A2.208" )
				)
				( pin "ba(0)"
					( attribute "PN" "81"
						( Origin gPackager )
					)
					( objectStatus "J4A2.81" )
				)
				( pin "ba(1)"
					( attribute "PN" "224"
						( Origin gPackager )
					)
					( objectStatus "J4A2.224" )
				)
				( pin "bg(0)"
					( attribute "PN" "63"
						( Origin gPackager )
					)
					( objectStatus "J4A2.63" )
				)
				( pin "bg(1)"
					( attribute "PN" "207"
						( Origin gPackager )
					)
					( objectStatus "J4A2.207" )
				)
				( pin "c(2)"
					( attribute "PN" "235"
						( Origin gPackager )
					)
					( objectStatus "J4A2.235" )
				)
				( pin "cb(0)"
					( attribute "PN" "49"
						( Origin gPackager )
					)
					( objectStatus "J4A2.49" )
				)
				( pin "cb(1)"
					( attribute "PN" "194"
						( Origin gPackager )
					)
					( objectStatus "J4A2.194" )
				)
				( pin "cb(2)"
					( attribute "PN" "56"
						( Origin gPackager )
					)
					( objectStatus "J4A2.56" )
				)
				( pin "cb(3)"
					( attribute "PN" "201"
						( Origin gPackager )
					)
					( objectStatus "J4A2.201" )
				)
				( pin "cb(4)"
					( attribute "PN" "47"
						( Origin gPackager )
					)
					( objectStatus "J4A2.47" )
				)
				( pin "cb(5)"
					( attribute "PN" "192"
						( Origin gPackager )
					)
					( objectStatus "J4A2.192" )
				)
				( pin "cb(6)"
					( attribute "PN" "54"
						( Origin gPackager )
					)
					( objectStatus "J4A2.54" )
				)
				( pin "cb(7)"
					( attribute "PN" "199"
						( Origin gPackager )
					)
					( objectStatus "J4A2.199" )
				)
				( pin "ck0n"
					( attribute "PN" "75"
						( Origin gPackager )
					)
					( objectStatus "J4A2.75" )
				)
				( pin "ck0p"
					( attribute "PN" "74"
						( Origin gPackager )
					)
					( objectStatus "J4A2.74" )
				)
				( pin "ck1n"
					( attribute "PN" "219"
						( Origin gPackager )
					)
					( objectStatus "J4A2.219" )
				)
				( pin "ck1p"
					( attribute "PN" "218"
						( Origin gPackager )
					)
					( objectStatus "J4A2.218" )
				)
				( pin "cke(0)"
					( attribute "PN" "60"
						( Origin gPackager )
					)
					( objectStatus "J4A2.60" )
				)
				( pin "cke(1)"
					( attribute "PN" "203"
						( Origin gPackager )
					)
					( objectStatus "J4A2.203" )
				)
				( pin "dq(0)"
					( attribute "PN" "5"
						( Origin gPackager )
					)
					( objectStatus "J4A2.5" )
				)
				( pin "dq(1)"
					( attribute "PN" "150"
						( Origin gPackager )
					)
					( objectStatus "J4A2.150" )
				)
				( pin "dq(2)"
					( attribute "PN" "12"
						( Origin gPackager )
					)
					( objectStatus "J4A2.12" )
				)
				( pin "dq(3)"
					( attribute "PN" "157"
						( Origin gPackager )
					)
					( objectStatus "J4A2.157" )
				)
				( pin "dq(4)"
					( attribute "PN" "3"
						( Origin gPackager )
					)
					( objectStatus "J4A2.3" )
				)
				( pin "dq(5)"
					( attribute "PN" "148"
						( Origin gPackager )
					)
					( objectStatus "J4A2.148" )
				)
				( pin "dq(6)"
					( attribute "PN" "10"
						( Origin gPackager )
					)
					( objectStatus "J4A2.10" )
				)
				( pin "dq(7)"
					( attribute "PN" "155"
						( Origin gPackager )
					)
					( objectStatus "J4A2.155" )
				)
				( pin "dq(8)"
					( attribute "PN" "16"
						( Origin gPackager )
					)
					( objectStatus "J4A2.16" )
				)
				( pin "dq(9)"
					( attribute "PN" "161"
						( Origin gPackager )
					)
					( objectStatus "J4A2.161" )
				)
				( pin "dq(10)"
					( attribute "PN" "23"
						( Origin gPackager )
					)
					( objectStatus "J4A2.23" )
				)
				( pin "dq(11)"
					( attribute "PN" "168"
						( Origin gPackager )
					)
					( objectStatus "J4A2.168" )
				)
				( pin "dq(12)"
					( attribute "PN" "14"
						( Origin gPackager )
					)
					( objectStatus "J4A2.14" )
				)
				( pin "dq(13)"
					( attribute "PN" "159"
						( Origin gPackager )
					)
					( objectStatus "J4A2.159" )
				)
				( pin "dq(14)"
					( attribute "PN" "21"
						( Origin gPackager )
					)
					( objectStatus "J4A2.21" )
				)
				( pin "dq(15)"
					( attribute "PN" "166"
						( Origin gPackager )
					)
					( objectStatus "J4A2.166" )
				)
				( pin "dq(16)"
					( attribute "PN" "27"
						( Origin gPackager )
					)
					( objectStatus "J4A2.27" )
				)
				( pin "dq(17)"
					( attribute "PN" "172"
						( Origin gPackager )
					)
					( objectStatus "J4A2.172" )
				)
				( pin "dq(18)"
					( attribute "PN" "34"
						( Origin gPackager )
					)
					( objectStatus "J4A2.34" )
				)
				( pin "dq(19)"
					( attribute "PN" "179"
						( Origin gPackager )
					)
					( objectStatus "J4A2.179" )
				)
				( pin "dq(20)"
					( attribute "PN" "25"
						( Origin gPackager )
					)
					( objectStatus "J4A2.25" )
				)
				( pin "dq(21)"
					( attribute "PN" "170"
						( Origin gPackager )
					)
					( objectStatus "J4A2.170" )
				)
				( pin "dq(22)"
					( attribute "PN" "32"
						( Origin gPackager )
					)
					( objectStatus "J4A2.32" )
				)
				( pin "dq(23)"
					( attribute "PN" "177"
						( Origin gPackager )
					)
					( objectStatus "J4A2.177" )
				)
				( pin "dq(24)"
					( attribute "PN" "38"
						( Origin gPackager )
					)
					( objectStatus "J4A2.38" )
				)
				( pin "dq(25)"
					( attribute "PN" "183"
						( Origin gPackager )
					)
					( objectStatus "J4A2.183" )
				)
				( pin "dq(26)"
					( attribute "PN" "45"
						( Origin gPackager )
					)
					( objectStatus "J4A2.45" )
				)
				( pin "dq(27)"
					( attribute "PN" "190"
						( Origin gPackager )
					)
					( objectStatus "J4A2.190" )
				)
				( pin "dq(28)"
					( attribute "PN" "36"
						( Origin gPackager )
					)
					( objectStatus "J4A2.36" )
				)
				( pin "dq(29)"
					( attribute "PN" "181"
						( Origin gPackager )
					)
					( objectStatus "J4A2.181" )
				)
				( pin "dq(30)"
					( attribute "PN" "43"
						( Origin gPackager )
					)
					( objectStatus "J4A2.43" )
				)
				( pin "dq(31)"
					( attribute "PN" "188"
						( Origin gPackager )
					)
					( objectStatus "J4A2.188" )
				)
				( pin "dq(32)"
					( attribute "PN" "97"
						( Origin gPackager )
					)
					( objectStatus "J4A2.97" )
				)
				( pin "dq(33)"
					( attribute "PN" "242"
						( Origin gPackager )
					)
					( objectStatus "J4A2.242" )
				)
				( pin "dq(34)"
					( attribute "PN" "104"
						( Origin gPackager )
					)
					( objectStatus "J4A2.104" )
				)
				( pin "dq(35)"
					( attribute "PN" "249"
						( Origin gPackager )
					)
					( objectStatus "J4A2.249" )
				)
				( pin "dq(36)"
					( attribute "PN" "95"
						( Origin gPackager )
					)
					( objectStatus "J4A2.95" )
				)
				( pin "dq(37)"
					( attribute "PN" "240"
						( Origin gPackager )
					)
					( objectStatus "J4A2.240" )
				)
				( pin "dq(38)"
					( attribute "PN" "102"
						( Origin gPackager )
					)
					( objectStatus "J4A2.102" )
				)
				( pin "dq(39)"
					( attribute "PN" "247"
						( Origin gPackager )
					)
					( objectStatus "J4A2.247" )
				)
				( pin "dq(40)"
					( attribute "PN" "108"
						( Origin gPackager )
					)
					( objectStatus "J4A2.108" )
				)
				( pin "dq(41)"
					( attribute "PN" "253"
						( Origin gPackager )
					)
					( objectStatus "J4A2.253" )
				)
				( pin "dq(42)"
					( attribute "PN" "115"
						( Origin gPackager )
					)
					( objectStatus "J4A2.115" )
				)
				( pin "dq(43)"
					( attribute "PN" "260"
						( Origin gPackager )
					)
					( objectStatus "J4A2.260" )
				)
				( pin "dq(44)"
					( attribute "PN" "106"
						( Origin gPackager )
					)
					( objectStatus "J4A2.106" )
				)
				( pin "dq(45)"
					( attribute "PN" "251"
						( Origin gPackager )
					)
					( objectStatus "J4A2.251" )
				)
				( pin "dq(46)"
					( attribute "PN" "113"
						( Origin gPackager )
					)
					( objectStatus "J4A2.113" )
				)
				( pin "dq(47)"
					( attribute "PN" "258"
						( Origin gPackager )
					)
					( objectStatus "J4A2.258" )
				)
				( pin "dq(48)"
					( attribute "PN" "119"
						( Origin gPackager )
					)
					( objectStatus "J4A2.119" )
				)
				( pin "dq(49)"
					( attribute "PN" "264"
						( Origin gPackager )
					)
					( objectStatus "J4A2.264" )
				)
				( pin "dq(50)"
					( attribute "PN" "126"
						( Origin gPackager )
					)
					( objectStatus "J4A2.126" )
				)
				( pin "dq(51)"
					( attribute "PN" "271"
						( Origin gPackager )
					)
					( objectStatus "J4A2.271" )
				)
				( pin "dq(52)"
					( attribute "PN" "117"
						( Origin gPackager )
					)
					( objectStatus "J4A2.117" )
				)
				( pin "dq(53)"
					( attribute "PN" "262"
						( Origin gPackager )
					)
					( objectStatus "J4A2.262" )
				)
				( pin "dq(54)"
					( attribute "PN" "124"
						( Origin gPackager )
					)
					( objectStatus "J4A2.124" )
				)
				( pin "dq(55)"
					( attribute "PN" "269"
						( Origin gPackager )
					)
					( objectStatus "J4A2.269" )
				)
				( pin "dq(56)"
					( attribute "PN" "130"
						( Origin gPackager )
					)
					( objectStatus "J4A2.130" )
				)
				( pin "dq(57)"
					( attribute "PN" "275"
						( Origin gPackager )
					)
					( objectStatus "J4A2.275" )
				)
				( pin "dq(58)"
					( attribute "PN" "137"
						( Origin gPackager )
					)
					( objectStatus "J4A2.137" )
				)
				( pin "dq(59)"
					( attribute "PN" "282"
						( Origin gPackager )
					)
					( objectStatus "J4A2.282" )
				)
				( pin "dq(60)"
					( attribute "PN" "128"
						( Origin gPackager )
					)
					( objectStatus "J4A2.128" )
				)
				( pin "dq(61)"
					( attribute "PN" "273"
						( Origin gPackager )
					)
					( objectStatus "J4A2.273" )
				)
				( pin "dq(62)"
					( attribute "PN" "135"
						( Origin gPackager )
					)
					( objectStatus "J4A2.135" )
				)
				( pin "dq(63)"
					( attribute "PN" "280"
						( Origin gPackager )
					)
					( objectStatus "J4A2.280" )
				)
				( pin "event_n"
					( attribute "PN" "78"
						( Origin gPackager )
					)
					( objectStatus "J4A2.78" )
				)
				( pin "odt(0)"
					( attribute "PN" "87"
						( Origin gPackager )
					)
					( objectStatus "J4A2.87" )
				)
				( pin "odt(1)"
					( attribute "PN" "91"
						( Origin gPackager )
					)
					( objectStatus "J4A2.91" )
				)
				( pin "par"
					( attribute "PN" "222"
						( Origin gPackager )
					)
					( objectStatus "J4A2.222" )
				)
				( pin "reset_n"
					( attribute "PN" "58"
						( Origin gPackager )
					)
					( objectStatus "J4A2.58" )
				)
				( pin "rfu(0)"
					( attribute "PN" "205"
						( Origin gPackager )
					)
					( objectStatus "J4A2.205" )
				)
				( pin "rfu(1)"
					( attribute "PN" "227"
						( Origin gPackager )
					)
					( objectStatus "J4A2.227" )
				)
				( pin "rfu(2)"
					( attribute "PN" "144"
						( Origin gPackager )
					)
					( objectStatus "J4A2.144" )
				)
				( pin "s0_n"
					( attribute "PN" "84"
						( Origin gPackager )
					)
					( objectStatus "J4A2.84" )
				)
				( pin "s1_n"
					( attribute "PN" "89"
						( Origin gPackager )
					)
					( objectStatus "J4A2.89" )
				)
				( pin "s2_n_c(0)"
					( attribute "PN" "93"
						( Origin gPackager )
					)
					( objectStatus "J4A2.93" )
				)
				( pin "s3_n_c(1)"
					( attribute "PN" "237"
						( Origin gPackager )
					)
					( objectStatus "J4A2.237" )
				)
				( pin "sa(0)"
					( attribute "PN" "139"
						( Origin gPackager )
					)
					( objectStatus "J4A2.139" )
				)
				( pin "sa(1)"
					( attribute "PN" "140"
						( Origin gPackager )
					)
					( objectStatus "J4A2.140" )
				)
				( pin "sa(2)"
					( attribute "PN" "238"
						( Origin gPackager )
					)
					( objectStatus "J4A2.238" )
				)
				( pin "save_n_nc"
					( attribute "PN" "230"
						( Origin gPackager )
					)
					( objectStatus "J4A2.230" )
				)
				( pin "scl"
					( attribute "PN" "141"
						( Origin gPackager )
					)
					( objectStatus "J4A2.141" )
				)
				( pin "sda"
					( attribute "PN" "285"
						( Origin gPackager )
					)
					( objectStatus "J4A2.285" )
				)
				( pin "vddspd"
					( attribute "PN" "284"
						( Origin gPackager )
					)
					( objectStatus "J4A2.284" )
				)
				( pin "vrefca"
					( attribute "PN" "146"
						( Origin gPackager )
					)
					( objectStatus "J4A2.146" )
				)
			)
			( gate "@baseboard_fab2_lib.baseboard_fab2(sch_1):page51_i167"
				( attribute "BOM_COST" "MEM"
					( Origin gFrontEnd )
				)
				( attribute "CDS_LIB" "mstr_sconn"
					( Origin gPackager )
				)
				( attribute "CDS_LOCATION" "J4A2"
					( Origin gPackager )
				)
				( attribute "CDS_SEC" "4"
					( Origin gPackager )
				)
				( attribute "LOCATION" "J4A2"
					( Origin gFrontEnd )
				)
				( attribute "MATERIAL" "SCONN"
					( Origin gFrontEnd )
				)
				( attribute "PACK_TYPE" "PIP"
					( Origin gFrontEnd )
				)
				( attribute "PART_NUMBER" "H44441-004"
					( Origin gFrontEnd )
				)
				( attribute "PHYS_PAGE" "51"
					( Origin gFrontEnd )
				)
				( attribute "ROOM" "DDR4_CH_E"
					( Origin gFrontEnd )
				)
				( attribute "ROT" "0"
					( Origin gFrontEnd )
				)
				( attribute "SEC" "4"
					( Origin gFrontEnd )
				)
				( attribute "SEC_TYPE" "PIP"
					( Origin gFrontEnd )
				)
				( attribute "VER" "4"
					( Origin gFrontEnd )
				)
				( attribute "XY" "(-150,2050)"
					( Origin gFrontEnd )
				)
				( attribute "CHIPS_PART_NAME" "SCONN288_H44441004"
					( Origin gPackager )
				)
				( attribute "CDS_PART_NAME" "SCONN288_H44441004_PIP-SCONN,HA"
					( Origin gPackager )
				)
				( objectStatus "J4A2" )
				( pin "\12v\(0)"
					( attribute "PN" "145"
						( Origin gPackager )
					)
					( objectStatus "J4A2.145" )
				)
				( pin "\12v\(1)"
					( attribute "PN" "1"
						( Origin gPackager )
					)
					( objectStatus "J4A2.1" )
				)
				( pin "vdd(0)"
					( attribute "PN" "236"
						( Origin gPackager )
					)
					( objectStatus "J4A2.236" )
				)
				( pin "vdd(1)"
					( attribute "PN" "233"
						( Origin gPackager )
					)
					( objectStatus "J4A2.233" )
				)
				( pin "vdd(2)"
					( attribute "PN" "231"
						( Origin gPackager )
					)
					( objectStatus "J4A2.231" )
				)
				( pin "vdd(3)"
					( attribute "PN" "229"
						( Origin gPackager )
					)
					( objectStatus "J4A2.229" )
				)
				( pin "vdd(4)"
					( attribute "PN" "226"
						( Origin gPackager )
					)
					( objectStatus "J4A2.226" )
				)
				( pin "vdd(5)"
					( attribute "PN" "223"
						( Origin gPackager )
					)
					( objectStatus "J4A2.223" )
				)
				( pin "vdd(6)"
					( attribute "PN" "220"
						( Origin gPackager )
					)
					( objectStatus "J4A2.220" )
				)
				( pin "vdd(7)"
					( attribute "PN" "217"
						( Origin gPackager )
					)
					( objectStatus "J4A2.217" )
				)
				( pin "vdd(8)"
					( attribute "PN" "215"
						( Origin gPackager )
					)
					( objectStatus "J4A2.215" )
				)
				( pin "vdd(9)"
					( attribute "PN" "212"
						( Origin gPackager )
					)
					( objectStatus "J4A2.212" )
				)
				( pin "vdd(10)"
					( attribute "PN" "209"
						( Origin gPackager )
					)
					( objectStatus "J4A2.209" )
				)
				( pin "vdd(11)"
					( attribute "PN" "206"
						( Origin gPackager )
					)
					( objectStatus "J4A2.206" )
				)
				( pin "vdd(12)"
					( attribute "PN" "204"
						( Origin gPackager )
					)
					( objectStatus "J4A2.204" )
				)
				( pin "vdd(13)"
					( attribute "PN" "92"
						( Origin gPackager )
					)
					( objectStatus "J4A2.92" )
				)
				( pin "vdd(14)"
					( attribute "PN" "90"
						( Origin gPackager )
					)
					( objectStatus "J4A2.90" )
				)
				( pin "vdd(15)"
					( attribute "PN" "88"
						( Origin gPackager )
					)
					( objectStatus "J4A2.88" )
				)
				( pin "vdd(16)"
					( attribute "PN" "85"
						( Origin gPackager )
					)
					( objectStatus "J4A2.85" )
				)
				( pin "vdd(17)"
					( attribute "PN" "83"
						( Origin gPackager )
					)
					( objectStatus "J4A2.83" )
				)
				( pin "vdd(18)"
					( attribute "PN" "80"
						( Origin gPackager )
					)
					( objectStatus "J4A2.80" )
				)
				( pin "vdd(19)"
					( attribute "PN" "76"
						( Origin gPackager )
					)
					( objectStatus "J4A2.76" )
				)
				( pin "vdd(20)"
					( attribute "PN" "73"
						( Origin gPackager )
					)
					( objectStatus "J4A2.73" )
				)
				( pin "vdd(21)"
					( attribute "PN" "70"
						( Origin gPackager )
					)
					( objectStatus "J4A2.70" )
				)
				( pin "vdd(22)"
					( attribute "PN" "67"
						( Origin gPackager )
					)
					( objectStatus "J4A2.67" )
				)
				( pin "vdd(23)"
					( attribute "PN" "64"
						( Origin gPackager )
					)
					( objectStatus "J4A2.64" )
				)
				( pin "vdd(24)"
					( attribute "PN" "61"
						( Origin gPackager )
					)
					( objectStatus "J4A2.61" )
				)
				( pin "vdd(25)"
					( attribute "PN" "59"
						( Origin gPackager )
					)
					( objectStatus "J4A2.59" )
				)
				( pin "vpp(0)"
					( attribute "PN" "287"
						( Origin gPackager )
					)
					( objectStatus "J4A2.287" )
				)
				( pin "vpp(1)"
					( attribute "PN" "286"
						( Origin gPackager )
					)
					( objectStatus "J4A2.286" )
				)
				( pin "vpp(2)"
					( attribute "PN" "288"
						( Origin gPackager )
					)
					( objectStatus "J4A2.288" )
				)
				( pin "vpp(3)"
					( attribute "PN" "143"
						( Origin gPackager )
					)
					( objectStatus "J4A2.143" )
				)
				( pin "vpp(4)"
					( attribute "PN" "142"
						( Origin gPackager )
					)
					( objectStatus "J4A2.142" )
				)
				( pin "vtt(0)"
					( attribute "PN" "221"
						( Origin gPackager )
					)
					( objectStatus "J4A2.221" )
				)
				( pin "vtt(1)"
					( attribute "PN" "77"
						( Origin gPackager )
					)
					( objectStatus "J4A2.77" )
				)
			)
			( gate "@baseboard_fab2_lib.baseboard_fab2(sch_1):page51_i175"
				( attribute "BOM_COST" "MEM"
					( Origin gFrontEnd )
				)
				( attribute "CDS_LIB" "dev_discrete"
					( Origin gPackager )
				)
				( attribute "CDS_LOCATION" "C6L6"
					( Origin gPackager )
				)
				( attribute "CDS_SEC" "1"
					( Origin gPackager )
				)
				( attribute "LOCATION" "C6L6"
					( Origin gFrontEnd )
				)
				( attribute "MATERIAL" "X7R"
					( Origin gFrontEnd )
				)
				( attribute "PACK_TYPE" "0402V"
					( Origin gFrontEnd )
				)
				( attribute "PART_NUMBER" "A36096-045"
					( Origin gFrontEnd )
				)
				( attribute "PHYS_PAGE" "51"
					( Origin gFrontEnd )
				)
				( attribute "ROOM" "DDR4_CH_E"
					( Origin gFrontEnd )
				)
				( attribute "ROT" "2"
					( Origin gFrontEnd )
				)
				( attribute "SEC" "1"
					( Origin gPackager )
				)
				( attribute "TOLERANCE" "10%"
					( Origin gFrontEnd )
				)
				( attribute "VALUE" "0.01UF"
					( Origin gFrontEnd )
				)
				( attribute "VER" "1"
					( Origin gFrontEnd )
				)
				( attribute "VOLTAGE" "25V"
					( Units "uVoltage" "V" 1.000000)
					( Origin gFrontEnd )
				)
				( attribute "XY" "(-4650,1550)"
					( Origin gFrontEnd )
				)
				( attribute "CHIPS_PART_NAME" "CAP_A"
					( Origin gPackager )
				)
				( attribute "CDS_PART_NAME" "CAP_A_0402V-0.01UF,25V,10%,X7RA"
					( Origin gPackager )
				)
				( objectStatus "C6L6" )
				( pin "a"
					( attribute "PN" "1"
						( Origin gPackager )
					)
					( objectStatus "C6L6.1" )
				)
				( pin "b"
					( attribute "PN" "2"
						( Origin gPackager )
					)
					( objectStatus "C6L6.2" )
				)
			)
			( gate "@baseboard_fab2_lib.baseboard_fab2(sch_1):page52_i3"
				( attribute "BOM_COST" "MEM"
					( Origin gFrontEnd )
				)
				( attribute "CDS_LIB" "dev_discrete"
					( Origin gPackager )
				)
				( attribute "CDS_LOCATION" "C4A18"
					( Origin gPackager )
				)
				( attribute "CDS_SEC" "1"
					( Origin gPackager )
				)
				( attribute "LOCATION" "C4A18"
					( Origin gFrontEnd )
				)
				( attribute "MATERIAL" "X7R"
					( Origin gFrontEnd )
				)
				( attribute "PACK_TYPE" "0402V"
					( Origin gFrontEnd )
				)
				( attribute "PART_NUMBER" "A36096-045"
					( Origin gFrontEnd )
				)
				( attribute "PHYS_PAGE" "52"
					( Origin gFrontEnd )
				)
				( attribute "ROOM" "DDR4_CH_E"
					( Origin gFrontEnd )
				)
				( attribute "ROT" "2"
					( Origin gFrontEnd )
				)
				( attribute "SEC" "1"
					( Origin gPackager )
				)
				( attribute "TOLERANCE" "10%"
					( Origin gFrontEnd )
				)
				( attribute "VALUE" "0.01UF"
					( Origin gFrontEnd )
				)
				( attribute "VER" "1"
					( Origin gFrontEnd )
				)
				( attribute "VOLTAGE" "25V"
					( Units "uVoltage" "V" 1.000000)
					( Origin gFrontEnd )
				)
				( attribute "XY" "(-3025,1150)"
					( Origin gFrontEnd )
				)
				( attribute "CHIPS_PART_NAME" "CAP_A"
					( Origin gPackager )
				)
				( attribute "CDS_PART_NAME" "CAP_A_0402V-0.01UF,25V,10%,X7RA"
					( Origin gPackager )
				)
				( objectStatus "C4A18" )
				( pin "a"
					( attribute "PN" "1"
						( Origin gPackager )
					)
					( objectStatus "C4A18.1" )
				)
				( pin "b"
					( attribute "PN" "2"
						( Origin gPackager )
					)
					( objectStatus "C4A18.2" )
				)
			)
			( gate "@baseboard_fab2_lib.baseboard_fab2(sch_1):page52_i12"
				( attribute "BOM_COST" "MEM"
					( Origin gFrontEnd )
				)
				( attribute "CDS_LIB" "mstr_sconn"
					( Origin gPackager )
				)
				( attribute "CDS_LOCATION" "J6L2"
					( Origin gPackager )
				)
				( attribute "CDS_SEC" "1"
					( Origin gPackager )
				)
				( attribute "LOCATION" "J6L2"
					( Origin gFrontEnd )
				)
				( attribute "MATERIAL" "SCONN"
					( Origin gFrontEnd )
				)
				( attribute "PACK_TYPE" "PIP"
					( Origin gFrontEnd )
				)
				( attribute "PART_NUMBER" "H44441-003"
					( Origin gFrontEnd )
				)
				( attribute "PHYS_PAGE" "52"
					( Origin gFrontEnd )
				)
				( attribute "ROOM" "DDR4_CH_E"
					( Origin gFrontEnd )
				)
				( attribute "ROT" "0"
					( Origin gFrontEnd )
				)
				( attribute "SEC" "1"
					( Origin gFrontEnd )
				)
				( attribute "SEC_TYPE" "PIP"
					( Origin gFrontEnd )
				)
				( attribute "VER" "1"
					( Origin gFrontEnd )
				)
				( attribute "XY" "(-725,2850)"
					( Origin gFrontEnd )
				)
				( attribute "CHIPS_PART_NAME" "SCONN288_H44441003"
					( Origin gPackager )
				)
				( attribute "CDS_PART_NAME" "SCONN288_H44441003_PIP-SCONN,HA"
					( Origin gPackager )
				)
				( objectStatus "J6L2" )
				( pin "a0"
					( attribute "PN" "79"
						( Origin gPackager )
					)
					( objectStatus "J6L2.79" )
				)
				( pin "a1"
					( attribute "PN" "72"
						( Origin gPackager )
					)
					( objectStatus "J6L2.72" )
				)
				( pin "a2"
					( attribute "PN" "216"
						( Origin gPackager )
					)
					( objectStatus "J6L2.216" )
				)
				( pin "a3"
					( attribute "PN" "71"
						( Origin gPackager )
					)
					( objectStatus "J6L2.71" )
				)
				( pin "a4"
					( attribute "PN" "214"
						( Origin gPackager )
					)
					( objectStatus "J6L2.214" )
				)
				( pin "a5"
					( attribute "PN" "213"
						( Origin gPackager )
					)
					( objectStatus "J6L2.213" )
				)
				( pin "a6"
					( attribute "PN" "69"
						( Origin gPackager )
					)
					( objectStatus "J6L2.69" )
				)
				( pin "a7"
					( attribute "PN" "211"
						( Origin gPackager )
					)
					( objectStatus "J6L2.211" )
				)
				( pin "a8"
					( attribute "PN" "68"
						( Origin gPackager )
					)
					( objectStatus "J6L2.68" )
				)
				( pin "a9"
					( attribute "PN" "66"
						( Origin gPackager )
					)
					( objectStatus "J6L2.66" )
				)
				( pin "a10"
					( attribute "PN" "225"
						( Origin gPackager )
					)
					( objectStatus "J6L2.225" )
				)
				( pin "a11"
					( attribute "PN" "210"
						( Origin gPackager )
					)
					( objectStatus "J6L2.210" )
				)
				( pin "a12"
					( attribute "PN" "65"
						( Origin gPackager )
					)
					( objectStatus "J6L2.65" )
				)
				( pin "a13"
					( attribute "PN" "232"
						( Origin gPackager )
					)
					( objectStatus "J6L2.232" )
				)
				( pin "a14_we_n"
					( attribute "PN" "228"
						( Origin gPackager )
					)
					( objectStatus "J6L2.228" )
				)
				( pin "a15_cas_n"
					( attribute "PN" "86"
						( Origin gPackager )
					)
					( objectStatus "J6L2.86" )
				)
				( pin "a16_ras_n"
					( attribute "PN" "82"
						( Origin gPackager )
					)
					( objectStatus "J6L2.82" )
				)
				( pin "a17"
					( attribute "PN" "234"
						( Origin gPackager )
					)
					( objectStatus "J6L2.234" )
				)
				( pin "act_n"
					( attribute "PN" "62"
						( Origin gPackager )
					)
					( objectStatus "J6L2.62" )
				)
				( pin "alert_n"
					( attribute "PN" "208"
						( Origin gPackager )
					)
					( objectStatus "J6L2.208" )
				)
				( pin "ba(0)"
					( attribute "PN" "81"
						( Origin gPackager )
					)
					( objectStatus "J6L2.81" )
				)
				( pin "ba(1)"
					( attribute "PN" "224"
						( Origin gPackager )
					)
					( objectStatus "J6L2.224" )
				)
				( pin "bg(0)"
					( attribute "PN" "63"
						( Origin gPackager )
					)
					( objectStatus "J6L2.63" )
				)
				( pin "bg(1)"
					( attribute "PN" "207"
						( Origin gPackager )
					)
					( objectStatus "J6L2.207" )
				)
				( pin "c(2)"
					( attribute "PN" "235"
						( Origin gPackager )
					)
					( objectStatus "J6L2.235" )
				)
				( pin "cb(0)"
					( attribute "PN" "49"
						( Origin gPackager )
					)
					( objectStatus "J6L2.49" )
				)
				( pin "cb(1)"
					( attribute "PN" "194"
						( Origin gPackager )
					)
					( objectStatus "J6L2.194" )
				)
				( pin "cb(2)"
					( attribute "PN" "56"
						( Origin gPackager )
					)
					( objectStatus "J6L2.56" )
				)
				( pin "cb(3)"
					( attribute "PN" "201"
						( Origin gPackager )
					)
					( objectStatus "J6L2.201" )
				)
				( pin "cb(4)"
					( attribute "PN" "47"
						( Origin gPackager )
					)
					( objectStatus "J6L2.47" )
				)
				( pin "cb(5)"
					( attribute "PN" "192"
						( Origin gPackager )
					)
					( objectStatus "J6L2.192" )
				)
				( pin "cb(6)"
					( attribute "PN" "54"
						( Origin gPackager )
					)
					( objectStatus "J6L2.54" )
				)
				( pin "cb(7)"
					( attribute "PN" "199"
						( Origin gPackager )
					)
					( objectStatus "J6L2.199" )
				)
				( pin "ck0n"
					( attribute "PN" "75"
						( Origin gPackager )
					)
					( objectStatus "J6L2.75" )
				)
				( pin "ck0p"
					( attribute "PN" "74"
						( Origin gPackager )
					)
					( objectStatus "J6L2.74" )
				)
				( pin "ck1n"
					( attribute "PN" "219"
						( Origin gPackager )
					)
					( objectStatus "J6L2.219" )
				)
				( pin "ck1p"
					( attribute "PN" "218"
						( Origin gPackager )
					)
					( objectStatus "J6L2.218" )
				)
				( pin "cke(0)"
					( attribute "PN" "60"
						( Origin gPackager )
					)
					( objectStatus "J6L2.60" )
				)
				( pin "cke(1)"
					( attribute "PN" "203"
						( Origin gPackager )
					)
					( objectStatus "J6L2.203" )
				)
				( pin "dq(0)"
					( attribute "PN" "5"
						( Origin gPackager )
					)
					( objectStatus "J6L2.5" )
				)
				( pin "dq(1)"
					( attribute "PN" "150"
						( Origin gPackager )
					)
					( objectStatus "J6L2.150" )
				)
				( pin "dq(2)"
					( attribute "PN" "12"
						( Origin gPackager )
					)
					( objectStatus "J6L2.12" )
				)
				( pin "dq(3)"
					( attribute "PN" "157"
						( Origin gPackager )
					)
					( objectStatus "J6L2.157" )
				)
				( pin "dq(4)"
					( attribute "PN" "3"
						( Origin gPackager )
					)
					( objectStatus "J6L2.3" )
				)
				( pin "dq(5)"
					( attribute "PN" "148"
						( Origin gPackager )
					)
					( objectStatus "J6L2.148" )
				)
				( pin "dq(6)"
					( attribute "PN" "10"
						( Origin gPackager )
					)
					( objectStatus "J6L2.10" )
				)
				( pin "dq(7)"
					( attribute "PN" "155"
						( Origin gPackager )
					)
					( objectStatus "J6L2.155" )
				)
				( pin "dq(8)"
					( attribute "PN" "16"
						( Origin gPackager )
					)
					( objectStatus "J6L2.16" )
				)
				( pin "dq(9)"
					( attribute "PN" "161"
						( Origin gPackager )
					)
					( objectStatus "J6L2.161" )
				)
				( pin "dq(10)"
					( attribute "PN" "23"
						( Origin gPackager )
					)
					( objectStatus "J6L2.23" )
				)
				( pin "dq(11)"
					( attribute "PN" "168"
						( Origin gPackager )
					)
					( objectStatus "J6L2.168" )
				)
				( pin "dq(12)"
					( attribute "PN" "14"
						( Origin gPackager )
					)
					( objectStatus "J6L2.14" )
				)
				( pin "dq(13)"
					( attribute "PN" "159"
						( Origin gPackager )
					)
					( objectStatus "J6L2.159" )
				)
				( pin "dq(14)"
					( attribute "PN" "21"
						( Origin gPackager )
					)
					( objectStatus "J6L2.21" )
				)
				( pin "dq(15)"
					( attribute "PN" "166"
						( Origin gPackager )
					)
					( objectStatus "J6L2.166" )
				)
				( pin "dq(16)"
					( attribute "PN" "27"
						( Origin gPackager )
					)
					( objectStatus "J6L2.27" )
				)
				( pin "dq(17)"
					( attribute "PN" "172"
						( Origin gPackager )
					)
					( objectStatus "J6L2.172" )
				)
				( pin "dq(18)"
					( attribute "PN" "34"
						( Origin gPackager )
					)
					( objectStatus "J6L2.34" )
				)
				( pin "dq(19)"
					( attribute "PN" "179"
						( Origin gPackager )
					)
					( objectStatus "J6L2.179" )
				)
				( pin "dq(20)"
					( attribute "PN" "25"
						( Origin gPackager )
					)
					( objectStatus "J6L2.25" )
				)
				( pin "dq(21)"
					( attribute "PN" "170"
						( Origin gPackager )
					)
					( objectStatus "J6L2.170" )
				)
				( pin "dq(22)"
					( attribute "PN" "32"
						( Origin gPackager )
					)
					( objectStatus "J6L2.32" )
				)
				( pin "dq(23)"
					( attribute "PN" "177"
						( Origin gPackager )
					)
					( objectStatus "J6L2.177" )
				)
				( pin "dq(24)"
					( attribute "PN" "38"
						( Origin gPackager )
					)
					( objectStatus "J6L2.38" )
				)
				( pin "dq(25)"
					( attribute "PN" "183"
						( Origin gPackager )
					)
					( objectStatus "J6L2.183" )
				)
				( pin "dq(26)"
					( attribute "PN" "45"
						( Origin gPackager )
					)
					( objectStatus "J6L2.45" )
				)
				( pin "dq(27)"
					( attribute "PN" "190"
						( Origin gPackager )
					)
					( objectStatus "J6L2.190" )
				)
				( pin "dq(28)"
					( attribute "PN" "36"
						( Origin gPackager )
					)
					( objectStatus "J6L2.36" )
				)
				( pin "dq(29)"
					( attribute "PN" "181"
						( Origin gPackager )
					)
					( objectStatus "J6L2.181" )
				)
				( pin "dq(30)"
					( attribute "PN" "43"
						( Origin gPackager )
					)
					( objectStatus "J6L2.43" )
				)
				( pin "dq(31)"
					( attribute "PN" "188"
						( Origin gPackager )
					)
					( objectStatus "J6L2.188" )
				)
				( pin "dq(32)"
					( attribute "PN" "97"
						( Origin gPackager )
					)
					( objectStatus "J6L2.97" )
				)
				( pin "dq(33)"
					( attribute "PN" "242"
						( Origin gPackager )
					)
					( objectStatus "J6L2.242" )
				)
				( pin "dq(34)"
					( attribute "PN" "104"
						( Origin gPackager )
					)
					( objectStatus "J6L2.104" )
				)
				( pin "dq(35)"
					( attribute "PN" "249"
						( Origin gPackager )
					)
					( objectStatus "J6L2.249" )
				)
				( pin "dq(36)"
					( attribute "PN" "95"
						( Origin gPackager )
					)
					( objectStatus "J6L2.95" )
				)
				( pin "dq(37)"
					( attribute "PN" "240"
						( Origin gPackager )
					)
					( objectStatus "J6L2.240" )
				)
				( pin "dq(38)"
					( attribute "PN" "102"
						( Origin gPackager )
					)
					( objectStatus "J6L2.102" )
				)
				( pin "dq(39)"
					( attribute "PN" "247"
						( Origin gPackager )
					)
					( objectStatus "J6L2.247" )
				)
				( pin "dq(40)"
					( attribute "PN" "108"
						( Origin gPackager )
					)
					( objectStatus "J6L2.108" )
				)
				( pin "dq(41)"
					( attribute "PN" "253"
						( Origin gPackager )
					)
					( objectStatus "J6L2.253" )
				)
				( pin "dq(42)"
					( attribute "PN" "115"
						( Origin gPackager )
					)
					( objectStatus "J6L2.115" )
				)
				( pin "dq(43)"
					( attribute "PN" "260"
						( Origin gPackager )
					)
					( objectStatus "J6L2.260" )
				)
				( pin "dq(44)"
					( attribute "PN" "106"
						( Origin gPackager )
					)
					( objectStatus "J6L2.106" )
				)
				( pin "dq(45)"
					( attribute "PN" "251"
						( Origin gPackager )
					)
					( objectStatus "J6L2.251" )
				)
				( pin "dq(46)"
					( attribute "PN" "113"
						( Origin gPackager )
					)
					( objectStatus "J6L2.113" )
				)
				( pin "dq(47)"
					( attribute "PN" "258"
						( Origin gPackager )
					)
					( objectStatus "J6L2.258" )
				)
				( pin "dq(48)"
					( attribute "PN" "119"
						( Origin gPackager )
					)
					( objectStatus "J6L2.119" )
				)
				( pin "dq(49)"
					( attribute "PN" "264"
						( Origin gPackager )
					)
					( objectStatus "J6L2.264" )
				)
				( pin "dq(50)"
					( attribute "PN" "126"
						( Origin gPackager )
					)
					( objectStatus "J6L2.126" )
				)
				( pin "dq(51)"
					( attribute "PN" "271"
						( Origin gPackager )
					)
					( objectStatus "J6L2.271" )
				)
				( pin "dq(52)"
					( attribute "PN" "117"
						( Origin gPackager )
					)
					( objectStatus "J6L2.117" )
				)
				( pin "dq(53)"
					( attribute "PN" "262"
						( Origin gPackager )
					)
					( objectStatus "J6L2.262" )
				)
				( pin "dq(54)"
					( attribute "PN" "124"
						( Origin gPackager )
					)
					( objectStatus "J6L2.124" )
				)
				( pin "dq(55)"
					( attribute "PN" "269"
						( Origin gPackager )
					)
					( objectStatus "J6L2.269" )
				)
				( pin "dq(56)"
					( attribute "PN" "130"
						( Origin gPackager )
					)
					( objectStatus "J6L2.130" )
				)
				( pin "dq(57)"
					( attribute "PN" "275"
						( Origin gPackager )
					)
					( objectStatus "J6L2.275" )
				)
				( pin "dq(58)"
					( attribute "PN" "137"
						( Origin gPackager )
					)
					( objectStatus "J6L2.137" )
				)
				( pin "dq(59)"
					( attribute "PN" "282"
						( Origin gPackager )
					)
					( objectStatus "J6L2.282" )
				)
				( pin "dq(60)"
					( attribute "PN" "128"
						( Origin gPackager )
					)
					( objectStatus "J6L2.128" )
				)
				( pin "dq(61)"
					( attribute "PN" "273"
						( Origin gPackager )
					)
					( objectStatus "J6L2.273" )
				)
				( pin "dq(62)"
					( attribute "PN" "135"
						( Origin gPackager )
					)
					( objectStatus "J6L2.135" )
				)
				( pin "dq(63)"
					( attribute "PN" "280"
						( Origin gPackager )
					)
					( objectStatus "J6L2.280" )
				)
				( pin "event_n"
					( attribute "PN" "78"
						( Origin gPackager )
					)
					( objectStatus "J6L2.78" )
				)
				( pin "odt(0)"
					( attribute "PN" "87"
						( Origin gPackager )
					)
					( objectStatus "J6L2.87" )
				)
				( pin "odt(1)"
					( attribute "PN" "91"
						( Origin gPackager )
					)
					( objectStatus "J6L2.91" )
				)
				( pin "par"
					( attribute "PN" "222"
						( Origin gPackager )
					)
					( objectStatus "J6L2.222" )
				)
				( pin "reset_n"
					( attribute "PN" "58"
						( Origin gPackager )
					)
					( objectStatus "J6L2.58" )
				)
				( pin "rfu(0)"
					( attribute "PN" "205"
						( Origin gPackager )
					)
					( objectStatus "J6L2.205" )
				)
				( pin "rfu(1)"
					( attribute "PN" "227"
						( Origin gPackager )
					)
					( objectStatus "J6L2.227" )
				)
				( pin "rfu(2)"
					( attribute "PN" "144"
						( Origin gPackager )
					)
					( objectStatus "J6L2.144" )
				)
				( pin "s0_n"
					( attribute "PN" "84"
						( Origin gPackager )
					)
					( objectStatus "J6L2.84" )
				)
				( pin "s1_n"
					( attribute "PN" "89"
						( Origin gPackager )
					)
					( objectStatus "J6L2.89" )
				)
				( pin "s2_n_c(0)"
					( attribute "PN" "93"
						( Origin gPackager )
					)
					( objectStatus "J6L2.93" )
				)
				( pin "s3_n_c(1)"
					( attribute "PN" "237"
						( Origin gPackager )
					)
					( objectStatus "J6L2.237" )
				)
				( pin "sa(0)"
					( attribute "PN" "139"
						( Origin gPackager )
					)
					( objectStatus "J6L2.139" )
				)
				( pin "sa(1)"
					( attribute "PN" "140"
						( Origin gPackager )
					)
					( objectStatus "J6L2.140" )
				)
				( pin "sa(2)"
					( attribute "PN" "238"
						( Origin gPackager )
					)
					( objectStatus "J6L2.238" )
				)
				( pin "save_n_nc"
					( attribute "PN" "230"
						( Origin gPackager )
					)
					( objectStatus "J6L2.230" )
				)
				( pin "scl"
					( attribute "PN" "141"
						( Origin gPackager )
					)
					( objectStatus "J6L2.141" )
				)
				( pin "sda"
					( attribute "PN" "285"
						( Origin gPackager )
					)
					( objectStatus "J6L2.285" )
				)
				( pin "vddspd"
					( attribute "PN" "284"
						( Origin gPackager )
					)
					( objectStatus "J6L2.284" )
				)
				( pin "vrefca"
					( attribute "PN" "146"
						( Origin gPackager )
					)
					( objectStatus "J6L2.146" )
				)
			)
			( gate "@baseboard_fab2_lib.baseboard_fab2(sch_1):page52_i55"
				( attribute "BOM_COST" "MEM"
					( Origin gFrontEnd )
				)
				( attribute "CDS_LIB" "mstr_sconn"
					( Origin gPackager )
				)
				( attribute "CDS_LOCATION" "J6L2"
					( Origin gPackager )
				)
				( attribute "CDS_SEC" "4"
					( Origin gPackager )
				)
				( attribute "LOCATION" "J6L2"
					( Origin gFrontEnd )
				)
				( attribute "MATERIAL" "SCONN"
					( Origin gFrontEnd )
				)
				( attribute "PACK_TYPE" "PIP"
					( Origin gFrontEnd )
				)
				( attribute "PART_NUMBER" "H44441-003"
					( Origin gFrontEnd )
				)
				( attribute "PHYS_PAGE" "52"
					( Origin gFrontEnd )
				)
				( attribute "ROOM" "DDR4_CH_E"
					( Origin gFrontEnd )
				)
				( attribute "ROT" "0"
					( Origin gFrontEnd )
				)
				( attribute "SEC" "4"
					( Origin gFrontEnd )
				)
				( attribute "SEC_TYPE" "PIP"
					( Origin gFrontEnd )
				)
				( attribute "VER" "4"
					( Origin gFrontEnd )
				)
				( attribute "XY" "(1475,1650)"
					( Origin gFrontEnd )
				)
				( attribute "CHIPS_PART_NAME" "SCONN288_H44441003"
					( Origin gPackager )
				)
				( attribute "CDS_PART_NAME" "SCONN288_H44441003_PIP-SCONN,HA"
					( Origin gPackager )
				)
				( objectStatus "J6L2" )
				( pin "\12v\(0)"
					( attribute "PN" "145"
						( Origin gPackager )
					)
					( objectStatus "J6L2.145" )
				)
				( pin "\12v\(1)"
					( attribute "PN" "1"
						( Origin gPackager )
					)
					( objectStatus "J6L2.1" )
				)
				( pin "vdd(0)"
					( attribute "PN" "236"
						( Origin gPackager )
					)
					( objectStatus "J6L2.236" )
				)
				( pin "vdd(1)"
					( attribute "PN" "233"
						( Origin gPackager )
					)
					( objectStatus "J6L2.233" )
				)
				( pin "vdd(2)"
					( attribute "PN" "231"
						( Origin gPackager )
					)
					( objectStatus "J6L2.231" )
				)
				( pin "vdd(3)"
					( attribute "PN" "229"
						( Origin gPackager )
					)
					( objectStatus "J6L2.229" )
				)
				( pin "vdd(4)"
					( attribute "PN" "226"
						( Origin gPackager )
					)
					( objectStatus "J6L2.226" )
				)
				( pin "vdd(5)"
					( attribute "PN" "223"
						( Origin gPackager )
					)
					( objectStatus "J6L2.223" )
				)
				( pin "vdd(6)"
					( attribute "PN" "220"
						( Origin gPackager )
					)
					( objectStatus "J6L2.220" )
				)
				( pin "vdd(7)"
					( attribute "PN" "217"
						( Origin gPackager )
					)
					( objectStatus "J6L2.217" )
				)
				( pin "vdd(8)"
					( attribute "PN" "215"
						( Origin gPackager )
					)
					( objectStatus "J6L2.215" )
				)
				( pin "vdd(9)"
					( attribute "PN" "212"
						( Origin gPackager )
					)
					( objectStatus "J6L2.212" )
				)
				( pin "vdd(10)"
					( attribute "PN" "209"
						( Origin gPackager )
					)
					( objectStatus "J6L2.209" )
				)
				( pin "vdd(11)"
					( attribute "PN" "206"
						( Origin gPackager )
					)
					( objectStatus "J6L2.206" )
				)
				( pin "vdd(12)"
					( attribute "PN" "204"
						( Origin gPackager )
					)
					( objectStatus "J6L2.204" )
				)
				( pin "vdd(13)"
					( attribute "PN" "92"
						( Origin gPackager )
					)
					( objectStatus "J6L2.92" )
				)
				( pin "vdd(14)"
					( attribute "PN" "90"
						( Origin gPackager )
					)
					( objectStatus "J6L2.90" )
				)
				( pin "vdd(15)"
					( attribute "PN" "88"
						( Origin gPackager )
					)
					( objectStatus "J6L2.88" )
				)
				( pin "vdd(16)"
					( attribute "PN" "85"
						( Origin gPackager )
					)
					( objectStatus "J6L2.85" )
				)
				( pin "vdd(17)"
					( attribute "PN" "83"
						( Origin gPackager )
					)
					( objectStatus "J6L2.83" )
				)
				( pin "vdd(18)"
					( attribute "PN" "80"
						( Origin gPackager )
					)
					( objectStatus "J6L2.80" )
				)
				( pin "vdd(19)"
					( attribute "PN" "76"
						( Origin gPackager )
					)
					( objectStatus "J6L2.76" )
				)
				( pin "vdd(20)"
					( attribute "PN" "73"
						( Origin gPackager )
					)
					( objectStatus "J6L2.73" )
				)
				( pin "vdd(21)"
					( attribute "PN" "70"
						( Origin gPackager )
					)
					( objectStatus "J6L2.70" )
				)
				( pin "vdd(22)"
					( attribute "PN" "67"
						( Origin gPackager )
					)
					( objectStatus "J6L2.67" )
				)
				( pin "vdd(23)"
					( attribute "PN" "64"
						( Origin gPackager )
					)
					( objectStatus "J6L2.64" )
				)
				( pin "vdd(24)"
					( attribute "PN" "61"
						( Origin gPackager )
					)
					( objectStatus "J6L2.61" )
				)
				( pin "vdd(25)"
					( attribute "PN" "59"
						( Origin gPackager )
					)
					( objectStatus "J6L2.59" )
				)
				( pin "vpp(0)"
					( attribute "PN" "287"
						( Origin gPackager )
					)
					( objectStatus "J6L2.287" )
				)
				( pin "vpp(1)"
					( attribute "PN" "286"
						( Origin gPackager )
					)
					( objectStatus "J6L2.286" )
				)
				( pin "vpp(2)"
					( attribute "PN" "288"
						( Origin gPackager )
					)
					( objectStatus "J6L2.288" )
				)
				( pin "vpp(3)"
					( attribute "PN" "143"
						( Origin gPackager )
					)
					( objectStatus "J6L2.143" )
				)
				( pin "vpp(4)"
					( attribute "PN" "142"
						( Origin gPackager )
					)
					( objectStatus "J6L2.142" )
				)
				( pin "vtt(0)"
					( attribute "PN" "221"
						( Origin gPackager )
					)
					( objectStatus "J6L2.221" )
				)
				( pin "vtt(1)"
					( attribute "PN" "77"
						( Origin gPackager )
					)
					( objectStatus "J6L2.77" )
				)
			)
			( gate "@baseboard_fab2_lib.baseboard_fab2(sch_1):page52_i100"
				( attribute "BOM_COST" "MEM"
					( Origin gFrontEnd )
				)
				( attribute "CDS_LIB" "mstr_sconn"
					( Origin gPackager )
				)
				( attribute "CDS_LOCATION" "J6L2"
					( Origin gPackager )
				)
				( attribute "CDS_SEC" "2"
					( Origin gPackager )
				)
				( attribute "LOCATION" "J6L2"
					( Origin gFrontEnd )
				)
				( attribute "MATERIAL" "SCONN"
					( Origin gFrontEnd )
				)
				( attribute "PACK_TYPE" "PIP"
					( Origin gFrontEnd )
				)
				( attribute "PART_NUMBER" "H44441-003"
					( Origin gFrontEnd )
				)
				( attribute "PHYS_PAGE" "52"
					( Origin gFrontEnd )
				)
				( attribute "ROOM" "DDR4_CH_E"
					( Origin gFrontEnd )
				)
				( attribute "ROT" "0"
					( Origin gFrontEnd )
				)
				( attribute "SEC" "2"
					( Origin gFrontEnd )
				)
				( attribute "SEC_TYPE" "PIP"
					( Origin gFrontEnd )
				)
				( attribute "VER" "2"
					( Origin gFrontEnd )
				)
				( attribute "XY" "(1625,3900)"
					( Origin gFrontEnd )
				)
				( attribute "CHIPS_PART_NAME" "SCONN288_H44441003"
					( Origin gPackager )
				)
				( attribute "CDS_PART_NAME" "SCONN288_H44441003_PIP-SCONN,HA"
					( Origin gPackager )
				)
				( objectStatus "J6L2" )
				( pin "dqs0n"
					( attribute "PN" "152"
						( Origin gPackager )
					)
					( objectStatus "J6L2.152" )
				)
				( pin "dqs0p"
					( attribute "PN" "153"
						( Origin gPackager )
					)
					( objectStatus "J6L2.153" )
				)
				( pin "dqs1n"
					( attribute "PN" "163"
						( Origin gPackager )
					)
					( objectStatus "J6L2.163" )
				)
				( pin "dqs1p"
					( attribute "PN" "164"
						( Origin gPackager )
					)
					( objectStatus "J6L2.164" )
				)
				( pin "dqs2n"
					( attribute "PN" "174"
						( Origin gPackager )
					)
					( objectStatus "J6L2.174" )
				)
				( pin "dqs2p"
					( attribute "PN" "175"
						( Origin gPackager )
					)
					( objectStatus "J6L2.175" )
				)
				( pin "dqs3n"
					( attribute "PN" "185"
						( Origin gPackager )
					)
					( objectStatus "J6L2.185" )
				)
				( pin "dqs3p"
					( attribute "PN" "186"
						( Origin gPackager )
					)
					( objectStatus "J6L2.186" )
				)
				( pin "dqs4n"
					( attribute "PN" "244"
						( Origin gPackager )
					)
					( objectStatus "J6L2.244" )
				)
				( pin "dqs4p"
					( attribute "PN" "245"
						( Origin gPackager )
					)
					( objectStatus "J6L2.245" )
				)
				( pin "dqs5n"
					( attribute "PN" "255"
						( Origin gPackager )
					)
					( objectStatus "J6L2.255" )
				)
				( pin "dqs5p"
					( attribute "PN" "256"
						( Origin gPackager )
					)
					( objectStatus "J6L2.256" )
				)
				( pin "dqs6n"
					( attribute "PN" "266"
						( Origin gPackager )
					)
					( objectStatus "J6L2.266" )
				)
				( pin "dqs6p"
					( attribute "PN" "267"
						( Origin gPackager )
					)
					( objectStatus "J6L2.267" )
				)
				( pin "dqs7n"
					( attribute "PN" "277"
						( Origin gPackager )
					)
					( objectStatus "J6L2.277" )
				)
				( pin "dqs7p"
					( attribute "PN" "278"
						( Origin gPackager )
					)
					( objectStatus "J6L2.278" )
				)
				( pin "dqs8n"
					( attribute "PN" "196"
						( Origin gPackager )
					)
					( objectStatus "J6L2.196" )
				)
				( pin "dqs8p"
					( attribute "PN" "197"
						( Origin gPackager )
					)
					( objectStatus "J6L2.197" )
				)
				( pin "dqs9n"
					( attribute "PN" "8"
						( Origin gPackager )
					)
					( objectStatus "J6L2.8" )
				)
				( pin "dqs9p"
					( attribute "PN" "7"
						( Origin gPackager )
					)
					( objectStatus "J6L2.7" )
				)
				( pin "dqs10n"
					( attribute "PN" "19"
						( Origin gPackager )
					)
					( objectStatus "J6L2.19" )
				)
				( pin "dqs10p"
					( attribute "PN" "18"
						( Origin gPackager )
					)
					( objectStatus "J6L2.18" )
				)
				( pin "dqs11n"
					( attribute "PN" "30"
						( Origin gPackager )
					)
					( objectStatus "J6L2.30" )
				)
				( pin "dqs11p"
					( attribute "PN" "29"
						( Origin gPackager )
					)
					( objectStatus "J6L2.29" )
				)
				( pin "dqs12n"
					( attribute "PN" "41"
						( Origin gPackager )
					)
					( objectStatus "J6L2.41" )
				)
				( pin "dqs12p"
					( attribute "PN" "40"
						( Origin gPackager )
					)
					( objectStatus "J6L2.40" )
				)
				( pin "dqs13n"
					( attribute "PN" "100"
						( Origin gPackager )
					)
					( objectStatus "J6L2.100" )
				)
				( pin "dqs13p"
					( attribute "PN" "99"
						( Origin gPackager )
					)
					( objectStatus "J6L2.99" )
				)
				( pin "dqs14n"
					( attribute "PN" "111"
						( Origin gPackager )
					)
					( objectStatus "J6L2.111" )
				)
				( pin "dqs14p"
					( attribute "PN" "110"
						( Origin gPackager )
					)
					( objectStatus "J6L2.110" )
				)
				( pin "dqs15n"
					( attribute "PN" "122"
						( Origin gPackager )
					)
					( objectStatus "J6L2.122" )
				)
				( pin "dqs15p"
					( attribute "PN" "121"
						( Origin gPackager )
					)
					( objectStatus "J6L2.121" )
				)
				( pin "dqs16n"
					( attribute "PN" "133"
						( Origin gPackager )
					)
					( objectStatus "J6L2.133" )
				)
				( pin "dqs16p"
					( attribute "PN" "132"
						( Origin gPackager )
					)
					( objectStatus "J6L2.132" )
				)
				( pin "dqs17n"
					( attribute "PN" "52"
						( Origin gPackager )
					)
					( objectStatus "J6L2.52" )
				)
				( pin "dqs17p"
					( attribute "PN" "51"
						( Origin gPackager )
					)
					( objectStatus "J6L2.51" )
				)
			)
			( gate "@baseboard_fab2_lib.baseboard_fab2(sch_1):page52_i138"
				( attribute "BOM_COST" "MEM"
					( Origin gFrontEnd )
				)
				( attribute "CDS_LIB" "mstr_sconn"
					( Origin gPackager )
				)
				( attribute "CDS_LOCATION" "J6L2"
					( Origin gPackager )
				)
				( attribute "CDS_SEC" "3"
					( Origin gPackager )
				)
				( attribute "LOCATION" "J6L2"
					( Origin gFrontEnd )
				)
				( attribute "MATERIAL" "SCONN"
					( Origin gFrontEnd )
				)
				( attribute "PACK_TYPE" "PIP"
					( Origin gFrontEnd )
				)
				( attribute "PART_NUMBER" "H44441-003"
					( Origin gFrontEnd )
				)
				( attribute "PHYS_PAGE" "52"
					( Origin gFrontEnd )
				)
				( attribute "ROOM" "DDR4_CH_E"
					( Origin gFrontEnd )
				)
				( attribute "ROT" "0"
					( Origin gFrontEnd )
				)
				( attribute "SEC" "3"
					( Origin gFrontEnd )
				)
				( attribute "SEC_TYPE" "PIP"
					( Origin gFrontEnd )
				)
				( attribute "VER" "3"
					( Origin gFrontEnd )
				)
				( attribute "XY" "(3425,2100)"
					( Origin gFrontEnd )
				)
				( attribute "CHIPS_PART_NAME" "SCONN288_H44441003"
					( Origin gPackager )
				)
				( attribute "CDS_PART_NAME" "SCONN288_H44441003_PIP-SCONN,HA"
					( Origin gPackager )
				)
				( objectStatus "J6L2" )
				( pin "vss(0)"
					( attribute "PN" "283"
						( Origin gPackager )
					)
					( objectStatus "J6L2.283" )
				)
				( pin "vss(1)"
					( attribute "PN" "281"
						( Origin gPackager )
					)
					( objectStatus "J6L2.281" )
				)
				( pin "vss(2)"
					( attribute "PN" "279"
						( Origin gPackager )
					)
					( objectStatus "J6L2.279" )
				)
				( pin "vss(3)"
					( attribute "PN" "276"
						( Origin gPackager )
					)
					( objectStatus "J6L2.276" )
				)
				( pin "vss(4)"
					( attribute "PN" "274"
						( Origin gPackager )
					)
					( objectStatus "J6L2.274" )
				)
				( pin "vss(5)"
					( attribute "PN" "272"
						( Origin gPackager )
					)
					( objectStatus "J6L2.272" )
				)
				( pin "vss(6)"
					( attribute "PN" "270"
						( Origin gPackager )
					)
					( objectStatus "J6L2.270" )
				)
				( pin "vss(7)"
					( attribute "PN" "268"
						( Origin gPackager )
					)
					( objectStatus "J6L2.268" )
				)
				( pin "vss(8)"
					( attribute "PN" "265"
						( Origin gPackager )
					)
					( objectStatus "J6L2.265" )
				)
				( pin "vss(9)"
					( attribute "PN" "263"
						( Origin gPackager )
					)
					( objectStatus "J6L2.263" )
				)
				( pin "vss(10)"
					( attribute "PN" "261"
						( Origin gPackager )
					)
					( objectStatus "J6L2.261" )
				)
				( pin "vss(11)"
					( attribute "PN" "259"
						( Origin gPackager )
					)
					( objectStatus "J6L2.259" )
				)
				( pin "vss(12)"
					( attribute "PN" "257"
						( Origin gPackager )
					)
					( objectStatus "J6L2.257" )
				)
				( pin "vss(13)"
					( attribute "PN" "254"
						( Origin gPackager )
					)
					( objectStatus "J6L2.254" )
				)
				( pin "vss(14)"
					( attribute "PN" "252"
						( Origin gPackager )
					)
					( objectStatus "J6L2.252" )
				)
				( pin "vss(15)"
					( attribute "PN" "250"
						( Origin gPackager )
					)
					( objectStatus "J6L2.250" )
				)
				( pin "vss(16)"
					( attribute "PN" "248"
						( Origin gPackager )
					)
					( objectStatus "J6L2.248" )
				)
				( pin "vss(17)"
					( attribute "PN" "246"
						( Origin gPackager )
					)
					( objectStatus "J6L2.246" )
				)
				( pin "vss(18)"
					( attribute "PN" "243"
						( Origin gPackager )
					)
					( objectStatus "J6L2.243" )
				)
				( pin "vss(19)"
					( attribute "PN" "241"
						( Origin gPackager )
					)
					( objectStatus "J6L2.241" )
				)
				( pin "vss(20)"
					( attribute "PN" "239"
						( Origin gPackager )
					)
					( objectStatus "J6L2.239" )
				)
				( pin "vss(21)"
					( attribute "PN" "202"
						( Origin gPackager )
					)
					( objectStatus "J6L2.202" )
				)
				( pin "vss(22)"
					( attribute "PN" "200"
						( Origin gPackager )
					)
					( objectStatus "J6L2.200" )
				)
				( pin "vss(23)"
					( attribute "PN" "198"
						( Origin gPackager )
					)
					( objectStatus "J6L2.198" )
				)
				( pin "vss(24)"
					( attribute "PN" "195"
						( Origin gPackager )
					)
					( objectStatus "J6L2.195" )
				)
				( pin "vss(25)"
					( attribute "PN" "193"
						( Origin gPackager )
					)
					( objectStatus "J6L2.193" )
				)
				( pin "vss(26)"
					( attribute "PN" "191"
						( Origin gPackager )
					)
					( objectStatus "J6L2.191" )
				)
				( pin "vss(27)"
					( attribute "PN" "189"
						( Origin gPackager )
					)
					( objectStatus "J6L2.189" )
				)
				( pin "vss(28)"
					( attribute "PN" "187"
						( Origin gPackager )
					)
					( objectStatus "J6L2.187" )
				)
				( pin "vss(29)"
					( attribute "PN" "184"
						( Origin gPackager )
					)
					( objectStatus "J6L2.184" )
				)
				( pin "vss(30)"
					( attribute "PN" "182"
						( Origin gPackager )
					)
					( objectStatus "J6L2.182" )
				)
				( pin "vss(31)"
					( attribute "PN" "180"
						( Origin gPackager )
					)
					( objectStatus "J6L2.180" )
				)
				( pin "vss(32)"
					( attribute "PN" "178"
						( Origin gPackager )
					)
					( objectStatus "J6L2.178" )
				)
				( pin "vss(33)"
					( attribute "PN" "176"
						( Origin gPackager )
					)
					( objectStatus "J6L2.176" )
				)
				( pin "vss(34)"
					( attribute "PN" "173"
						( Origin gPackager )
					)
					( objectStatus "J6L2.173" )
				)
				( pin "vss(35)"
					( attribute "PN" "171"
						( Origin gPackager )
					)
					( objectStatus "J6L2.171" )
				)
				( pin "vss(36)"
					( attribute "PN" "169"
						( Origin gPackager )
					)
					( objectStatus "J6L2.169" )
				)
				( pin "vss(37)"
					( attribute "PN" "167"
						( Origin gPackager )
					)
					( objectStatus "J6L2.167" )
				)
				( pin "vss(38)"
					( attribute "PN" "165"
						( Origin gPackager )
					)
					( objectStatus "J6L2.165" )
				)
				( pin "vss(39)"
					( attribute "PN" "162"
						( Origin gPackager )
					)
					( objectStatus "J6L2.162" )
				)
				( pin "vss(40)"
					( attribute "PN" "160"
						( Origin gPackager )
					)
					( objectStatus "J6L2.160" )
				)
				( pin "vss(41)"
					( attribute "PN" "158"
						( Origin gPackager )
					)
					( objectStatus "J6L2.158" )
				)
				( pin "vss(42)"
					( attribute "PN" "156"
						( Origin gPackager )
					)
					( objectStatus "J6L2.156" )
				)
				( pin "vss(43)"
					( attribute "PN" "154"
						( Origin gPackager )
					)
					( objectStatus "J6L2.154" )
				)
				( pin "vss(44)"
					( attribute "PN" "151"
						( Origin gPackager )
					)
					( objectStatus "J6L2.151" )
				)
				( pin "vss(45)"
					( attribute "PN" "149"
						( Origin gPackager )
					)
					( objectStatus "J6L2.149" )
				)
				( pin "vss(46)"
					( attribute "PN" "147"
						( Origin gPackager )
					)
					( objectStatus "J6L2.147" )
				)
				( pin "vss(47)"
					( attribute "PN" "138"
						( Origin gPackager )
					)
					( objectStatus "J6L2.138" )
				)
				( pin "vss(48)"
					( attribute "PN" "136"
						( Origin gPackager )
					)
					( objectStatus "J6L2.136" )
				)
				( pin "vss(49)"
					( attribute "PN" "134"
						( Origin gPackager )
					)
					( objectStatus "J6L2.134" )
				)
				( pin "vss(50)"
					( attribute "PN" "131"
						( Origin gPackager )
					)
					( objectStatus "J6L2.131" )
				)
				( pin "vss(51)"
					( attribute "PN" "129"
						( Origin gPackager )
					)
					( objectStatus "J6L2.129" )
				)
				( pin "vss(52)"
					( attribute "PN" "127"
						( Origin gPackager )
					)
					( objectStatus "J6L2.127" )
				)
				( pin "vss(53)"
					( attribute "PN" "125"
						( Origin gPackager )
					)
					( objectStatus "J6L2.125" )
				)
				( pin "vss(54)"
					( attribute "PN" "123"
						( Origin gPackager )
					)
					( objectStatus "J6L2.123" )
				)
				( pin "vss(55)"
					( attribute "PN" "120"
						( Origin gPackager )
					)
					( objectStatus "J6L2.120" )
				)
				( pin "vss(56)"
					( attribute "PN" "118"
						( Origin gPackager )
					)
					( objectStatus "J6L2.118" )
				)
				( pin "vss(57)"
					( attribute "PN" "116"
						( Origin gPackager )
					)
					( objectStatus "J6L2.116" )
				)
				( pin "vss(58)"
					( attribute "PN" "114"
						( Origin gPackager )
					)
					( objectStatus "J6L2.114" )
				)
				( pin "vss(59)"
					( attribute "PN" "112"
						( Origin gPackager )
					)
					( objectStatus "J6L2.112" )
				)
				( pin "vss(60)"
					( attribute "PN" "109"
						( Origin gPackager )
					)
					( objectStatus "J6L2.109" )
				)
				( pin "vss(61)"
					( attribute "PN" "107"
						( Origin gPackager )
					)
					( objectStatus "J6L2.107" )
				)
				( pin "vss(62)"
					( attribute "PN" "105"
						( Origin gPackager )
					)
					( objectStatus "J6L2.105" )
				)
				( pin "vss(63)"
					( attribute "PN" "103"
						( Origin gPackager )
					)
					( objectStatus "J6L2.103" )
				)
				( pin "vss(64)"
					( attribute "PN" "101"
						( Origin gPackager )
					)
					( objectStatus "J6L2.101" )
				)
				( pin "vss(65)"
					( attribute "PN" "98"
						( Origin gPackager )
					)
					( objectStatus "J6L2.98" )
				)
				( pin "vss(66)"
					( attribute "PN" "96"
						( Origin gPackager )
					)
					( objectStatus "J6L2.96" )
				)
				( pin "vss(67)"
					( attribute "PN" "94"
						( Origin gPackager )
					)
					( objectStatus "J6L2.94" )
				)
				( pin "vss(68)"
					( attribute "PN" "57"
						( Origin gPackager )
					)
					( objectStatus "J6L2.57" )
				)
				( pin "vss(69)"
					( attribute "PN" "55"
						( Origin gPackager )
					)
					( objectStatus "J6L2.55" )
				)
				( pin "vss(70)"
					( attribute "PN" "53"
						( Origin gPackager )
					)
					( objectStatus "J6L2.53" )
				)
				( pin "vss(71)"
					( attribute "PN" "50"
						( Origin gPackager )
					)
					( objectStatus "J6L2.50" )
				)
				( pin "vss(72)"
					( attribute "PN" "48"
						( Origin gPackager )
					)
					( objectStatus "J6L2.48" )
				)
				( pin "vss(73)"
					( attribute "PN" "46"
						( Origin gPackager )
					)
					( objectStatus "J6L2.46" )
				)
				( pin "vss(74)"
					( attribute "PN" "44"
						( Origin gPackager )
					)
					( objectStatus "J6L2.44" )
				)
				( pin "vss(75)"
					( attribute "PN" "42"
						( Origin gPackager )
					)
					( objectStatus "J6L2.42" )
				)
				( pin "vss(76)"
					( attribute "PN" "39"
						( Origin gPackager )
					)
					( objectStatus "J6L2.39" )
				)
				( pin "vss(77)"
					( attribute "PN" "37"
						( Origin gPackager )
					)
					( objectStatus "J6L2.37" )
				)
				( pin "vss(78)"
					( attribute "PN" "35"
						( Origin gPackager )
					)
					( objectStatus "J6L2.35" )
				)
				( pin "vss(79)"
					( attribute "PN" "33"
						( Origin gPackager )
					)
					( objectStatus "J6L2.33" )
				)
				( pin "vss(80)"
					( attribute "PN" "31"
						( Origin gPackager )
					)
					( objectStatus "J6L2.31" )
				)
				( pin "vss(81)"
					( attribute "PN" "28"
						( Origin gPackager )
					)
					( objectStatus "J6L2.28" )
				)
				( pin "vss(82)"
					( attribute "PN" "26"
						( Origin gPackager )
					)
					( objectStatus "J6L2.26" )
				)
				( pin "vss(83)"
					( attribute "PN" "24"
						( Origin gPackager )
					)
					( objectStatus "J6L2.24" )
				)
				( pin "vss(84)"
					( attribute "PN" "22"
						( Origin gPackager )
					)
					( objectStatus "J6L2.22" )
				)
				( pin "vss(85)"
					( attribute "PN" "20"
						( Origin gPackager )
					)
					( objectStatus "J6L2.20" )
				)
				( pin "vss(86)"
					( attribute "PN" "17"
						( Origin gPackager )
					)
					( objectStatus "J6L2.17" )
				)
				( pin "vss(87)"
					( attribute "PN" "15"
						( Origin gPackager )
					)
					( objectStatus "J6L2.15" )
				)
				( pin "vss(88)"
					( attribute "PN" "13"
						( Origin gPackager )
					)
					( objectStatus "J6L2.13" )
				)
				( pin "vss(89)"
					( attribute "PN" "11"
						( Origin gPackager )
					)
					( objectStatus "J6L2.11" )
				)
				( pin "vss(90)"
					( attribute "PN" "9"
						( Origin gPackager )
					)
					( objectStatus "J6L2.9" )
				)
				( pin "vss(91)"
					( attribute "PN" "6"
						( Origin gPackager )
					)
					( objectStatus "J6L2.6" )
				)
				( pin "vss(92)"
					( attribute "PN" "4"
						( Origin gPackager )
					)
					( objectStatus "J6L2.4" )
				)
				( pin "vss(93)"
					( attribute "PN" "2"
						( Origin gPackager )
					)
					( objectStatus "J6L2.2" )
				)
			)
			( gate "@baseboard_fab2_lib.baseboard_fab2(sch_1):page53_i43"
				( attribute "BOM_COST" "MEM"
					( Origin gFrontEnd )
				)
				( attribute "CDS_LIB" "mstr_sconn"
					( Origin gPackager )
				)
				( attribute "CDS_LOCATION" "J4A1"
					( Origin gPackager )
				)
				( attribute "CDS_SEC" "3"
					( Origin gPackager )
				)
				( attribute "LOCATION" "J4A1"
					( Origin gFrontEnd )
				)
				( attribute "MATERIAL" "SCONN"
					( Origin gFrontEnd )
				)
				( attribute "PACK_TYPE" "PIP"
					( Origin gFrontEnd )
				)
				( attribute "PART_NUMBER" "H44441-004"
					( Origin gFrontEnd )
				)
				( attribute "PHYS_PAGE" "53"
					( Origin gFrontEnd )
				)
				( attribute "ROOM" "DDR4_CH_F"
					( Origin gFrontEnd )
				)
				( attribute "ROT" "0"
					( Origin gFrontEnd )
				)
				( attribute "SEC" "3"
					( Origin gFrontEnd )
				)
				( attribute "SEC_TYPE" "PIP"
					( Origin gFrontEnd )
				)
				( attribute "VER" "3"
					( Origin gFrontEnd )
				)
				( attribute "XY" "(1750,2400)"
					( Origin gFrontEnd )
				)
				( attribute "CHIPS_PART_NAME" "SCONN288_H44441004"
					( Origin gPackager )
				)
				( attribute "CDS_PART_NAME" "SCONN288_H44441004_PIP-SCONN,HA"
					( Origin gPackager )
				)
				( objectStatus "J4A1" )
				( pin "vss(0)"
					( attribute "PN" "283"
						( Origin gPackager )
					)
					( objectStatus "J4A1.283" )
				)
				( pin "vss(1)"
					( attribute "PN" "281"
						( Origin gPackager )
					)
					( objectStatus "J4A1.281" )
				)
				( pin "vss(2)"
					( attribute "PN" "279"
						( Origin gPackager )
					)
					( objectStatus "J4A1.279" )
				)
				( pin "vss(3)"
					( attribute "PN" "276"
						( Origin gPackager )
					)
					( objectStatus "J4A1.276" )
				)
				( pin "vss(4)"
					( attribute "PN" "274"
						( Origin gPackager )
					)
					( objectStatus "J4A1.274" )
				)
				( pin "vss(5)"
					( attribute "PN" "272"
						( Origin gPackager )
					)
					( objectStatus "J4A1.272" )
				)
				( pin "vss(6)"
					( attribute "PN" "270"
						( Origin gPackager )
					)
					( objectStatus "J4A1.270" )
				)
				( pin "vss(7)"
					( attribute "PN" "268"
						( Origin gPackager )
					)
					( objectStatus "J4A1.268" )
				)
				( pin "vss(8)"
					( attribute "PN" "265"
						( Origin gPackager )
					)
					( objectStatus "J4A1.265" )
				)
				( pin "vss(9)"
					( attribute "PN" "263"
						( Origin gPackager )
					)
					( objectStatus "J4A1.263" )
				)
				( pin "vss(10)"
					( attribute "PN" "261"
						( Origin gPackager )
					)
					( objectStatus "J4A1.261" )
				)
				( pin "vss(11)"
					( attribute "PN" "259"
						( Origin gPackager )
					)
					( objectStatus "J4A1.259" )
				)
				( pin "vss(12)"
					( attribute "PN" "257"
						( Origin gPackager )
					)
					( objectStatus "J4A1.257" )
				)
				( pin "vss(13)"
					( attribute "PN" "254"
						( Origin gPackager )
					)
					( objectStatus "J4A1.254" )
				)
				( pin "vss(14)"
					( attribute "PN" "252"
						( Origin gPackager )
					)
					( objectStatus "J4A1.252" )
				)
				( pin "vss(15)"
					( attribute "PN" "250"
						( Origin gPackager )
					)
					( objectStatus "J4A1.250" )
				)
				( pin "vss(16)"
					( attribute "PN" "248"
						( Origin gPackager )
					)
					( objectStatus "J4A1.248" )
				)
				( pin "vss(17)"
					( attribute "PN" "246"
						( Origin gPackager )
					)
					( objectStatus "J4A1.246" )
				)
				( pin "vss(18)"
					( attribute "PN" "243"
						( Origin gPackager )
					)
					( objectStatus "J4A1.243" )
				)
				( pin "vss(19)"
					( attribute "PN" "241"
						( Origin gPackager )
					)
					( objectStatus "J4A1.241" )
				)
				( pin "vss(20)"
					( attribute "PN" "239"
						( Origin gPackager )
					)
					( objectStatus "J4A1.239" )
				)
				( pin "vss(21)"
					( attribute "PN" "202"
						( Origin gPackager )
					)
					( objectStatus "J4A1.202" )
				)
				( pin "vss(22)"
					( attribute "PN" "200"
						( Origin gPackager )
					)
					( objectStatus "J4A1.200" )
				)
				( pin "vss(23)"
					( attribute "PN" "198"
						( Origin gPackager )
					)
					( objectStatus "J4A1.198" )
				)
				( pin "vss(24)"
					( attribute "PN" "195"
						( Origin gPackager )
					)
					( objectStatus "J4A1.195" )
				)
				( pin "vss(25)"
					( attribute "PN" "193"
						( Origin gPackager )
					)
					( objectStatus "J4A1.193" )
				)
				( pin "vss(26)"
					( attribute "PN" "191"
						( Origin gPackager )
					)
					( objectStatus "J4A1.191" )
				)
				( pin "vss(27)"
					( attribute "PN" "189"
						( Origin gPackager )
					)
					( objectStatus "J4A1.189" )
				)
				( pin "vss(28)"
					( attribute "PN" "187"
						( Origin gPackager )
					)
					( objectStatus "J4A1.187" )
				)
				( pin "vss(29)"
					( attribute "PN" "184"
						( Origin gPackager )
					)
					( objectStatus "J4A1.184" )
				)
				( pin "vss(30)"
					( attribute "PN" "182"
						( Origin gPackager )
					)
					( objectStatus "J4A1.182" )
				)
				( pin "vss(31)"
					( attribute "PN" "180"
						( Origin gPackager )
					)
					( objectStatus "J4A1.180" )
				)
				( pin "vss(32)"
					( attribute "PN" "178"
						( Origin gPackager )
					)
					( objectStatus "J4A1.178" )
				)
				( pin "vss(33)"
					( attribute "PN" "176"
						( Origin gPackager )
					)
					( objectStatus "J4A1.176" )
				)
				( pin "vss(34)"
					( attribute "PN" "173"
						( Origin gPackager )
					)
					( objectStatus "J4A1.173" )
				)
				( pin "vss(35)"
					( attribute "PN" "171"
						( Origin gPackager )
					)
					( objectStatus "J4A1.171" )
				)
				( pin "vss(36)"
					( attribute "PN" "169"
						( Origin gPackager )
					)
					( objectStatus "J4A1.169" )
				)
				( pin "vss(37)"
					( attribute "PN" "167"
						( Origin gPackager )
					)
					( objectStatus "J4A1.167" )
				)
				( pin "vss(38)"
					( attribute "PN" "165"
						( Origin gPackager )
					)
					( objectStatus "J4A1.165" )
				)
				( pin "vss(39)"
					( attribute "PN" "162"
						( Origin gPackager )
					)
					( objectStatus "J4A1.162" )
				)
				( pin "vss(40)"
					( attribute "PN" "160"
						( Origin gPackager )
					)
					( objectStatus "J4A1.160" )
				)
				( pin "vss(41)"
					( attribute "PN" "158"
						( Origin gPackager )
					)
					( objectStatus "J4A1.158" )
				)
				( pin "vss(42)"
					( attribute "PN" "156"
						( Origin gPackager )
					)
					( objectStatus "J4A1.156" )
				)
				( pin "vss(43)"
					( attribute "PN" "154"
						( Origin gPackager )
					)
					( objectStatus "J4A1.154" )
				)
				( pin "vss(44)"
					( attribute "PN" "151"
						( Origin gPackager )
					)
					( objectStatus "J4A1.151" )
				)
				( pin "vss(45)"
					( attribute "PN" "149"
						( Origin gPackager )
					)
					( objectStatus "J4A1.149" )
				)
				( pin "vss(46)"
					( attribute "PN" "147"
						( Origin gPackager )
					)
					( objectStatus "J4A1.147" )
				)
				( pin "vss(47)"
					( attribute "PN" "138"
						( Origin gPackager )
					)
					( objectStatus "J4A1.138" )
				)
				( pin "vss(48)"
					( attribute "PN" "136"
						( Origin gPackager )
					)
					( objectStatus "J4A1.136" )
				)
				( pin "vss(49)"
					( attribute "PN" "134"
						( Origin gPackager )
					)
					( objectStatus "J4A1.134" )
				)
				( pin "vss(50)"
					( attribute "PN" "131"
						( Origin gPackager )
					)
					( objectStatus "J4A1.131" )
				)
				( pin "vss(51)"
					( attribute "PN" "129"
						( Origin gPackager )
					)
					( objectStatus "J4A1.129" )
				)
				( pin "vss(52)"
					( attribute "PN" "127"
						( Origin gPackager )
					)
					( objectStatus "J4A1.127" )
				)
				( pin "vss(53)"
					( attribute "PN" "125"
						( Origin gPackager )
					)
					( objectStatus "J4A1.125" )
				)
				( pin "vss(54)"
					( attribute "PN" "123"
						( Origin gPackager )
					)
					( objectStatus "J4A1.123" )
				)
				( pin "vss(55)"
					( attribute "PN" "120"
						( Origin gPackager )
					)
					( objectStatus "J4A1.120" )
				)
				( pin "vss(56)"
					( attribute "PN" "118"
						( Origin gPackager )
					)
					( objectStatus "J4A1.118" )
				)
				( pin "vss(57)"
					( attribute "PN" "116"
						( Origin gPackager )
					)
					( objectStatus "J4A1.116" )
				)
				( pin "vss(58)"
					( attribute "PN" "114"
						( Origin gPackager )
					)
					( objectStatus "J4A1.114" )
				)
				( pin "vss(59)"
					( attribute "PN" "112"
						( Origin gPackager )
					)
					( objectStatus "J4A1.112" )
				)
				( pin "vss(60)"
					( attribute "PN" "109"
						( Origin gPackager )
					)
					( objectStatus "J4A1.109" )
				)
				( pin "vss(61)"
					( attribute "PN" "107"
						( Origin gPackager )
					)
					( objectStatus "J4A1.107" )
				)
				( pin "vss(62)"
					( attribute "PN" "105"
						( Origin gPackager )
					)
					( objectStatus "J4A1.105" )
				)
				( pin "vss(63)"
					( attribute "PN" "103"
						( Origin gPackager )
					)
					( objectStatus "J4A1.103" )
				)
				( pin "vss(64)"
					( attribute "PN" "101"
						( Origin gPackager )
					)
					( objectStatus "J4A1.101" )
				)
				( pin "vss(65)"
					( attribute "PN" "98"
						( Origin gPackager )
					)
					( objectStatus "J4A1.98" )
				)
				( pin "vss(66)"
					( attribute "PN" "96"
						( Origin gPackager )
					)
					( objectStatus "J4A1.96" )
				)
				( pin "vss(67)"
					( attribute "PN" "94"
						( Origin gPackager )
					)
					( objectStatus "J4A1.94" )
				)
				( pin "vss(68)"
					( attribute "PN" "57"
						( Origin gPackager )
					)
					( objectStatus "J4A1.57" )
				)
				( pin "vss(69)"
					( attribute "PN" "55"
						( Origin gPackager )
					)
					( objectStatus "J4A1.55" )
				)
				( pin "vss(70)"
					( attribute "PN" "53"
						( Origin gPackager )
					)
					( objectStatus "J4A1.53" )
				)
				( pin "vss(71)"
					( attribute "PN" "50"
						( Origin gPackager )
					)
					( objectStatus "J4A1.50" )
				)
				( pin "vss(72)"
					( attribute "PN" "48"
						( Origin gPackager )
					)
					( objectStatus "J4A1.48" )
				)
				( pin "vss(73)"
					( attribute "PN" "46"
						( Origin gPackager )
					)
					( objectStatus "J4A1.46" )
				)
				( pin "vss(74)"
					( attribute "PN" "44"
						( Origin gPackager )
					)
					( objectStatus "J4A1.44" )
				)
				( pin "vss(75)"
					( attribute "PN" "42"
						( Origin gPackager )
					)
					( objectStatus "J4A1.42" )
				)
				( pin "vss(76)"
					( attribute "PN" "39"
						( Origin gPackager )
					)
					( objectStatus "J4A1.39" )
				)
				( pin "vss(77)"
					( attribute "PN" "37"
						( Origin gPackager )
					)
					( objectStatus "J4A1.37" )
				)
				( pin "vss(78)"
					( attribute "PN" "35"
						( Origin gPackager )
					)
					( objectStatus "J4A1.35" )
				)
				( pin "vss(79)"
					( attribute "PN" "33"
						( Origin gPackager )
					)
					( objectStatus "J4A1.33" )
				)
				( pin "vss(80)"
					( attribute "PN" "31"
						( Origin gPackager )
					)
					( objectStatus "J4A1.31" )
				)
				( pin "vss(81)"
					( attribute "PN" "28"
						( Origin gPackager )
					)
					( objectStatus "J4A1.28" )
				)
				( pin "vss(82)"
					( attribute "PN" "26"
						( Origin gPackager )
					)
					( objectStatus "J4A1.26" )
				)
				( pin "vss(83)"
					( attribute "PN" "24"
						( Origin gPackager )
					)
					( objectStatus "J4A1.24" )
				)
				( pin "vss(84)"
					( attribute "PN" "22"
						( Origin gPackager )
					)
					( objectStatus "J4A1.22" )
				)
				( pin "vss(85)"
					( attribute "PN" "20"
						( Origin gPackager )
					)
					( objectStatus "J4A1.20" )
				)
				( pin "vss(86)"
					( attribute "PN" "17"
						( Origin gPackager )
					)
					( objectStatus "J4A1.17" )
				)
				( pin "vss(87)"
					( attribute "PN" "15"
						( Origin gPackager )
					)
					( objectStatus "J4A1.15" )
				)
				( pin "vss(88)"
					( attribute "PN" "13"
						( Origin gPackager )
					)
					( objectStatus "J4A1.13" )
				)
				( pin "vss(89)"
					( attribute "PN" "11"
						( Origin gPackager )
					)
					( objectStatus "J4A1.11" )
				)
				( pin "vss(90)"
					( attribute "PN" "9"
						( Origin gPackager )
					)
					( objectStatus "J4A1.9" )
				)
				( pin "vss(91)"
					( attribute "PN" "6"
						( Origin gPackager )
					)
					( objectStatus "J4A1.6" )
				)
				( pin "vss(92)"
					( attribute "PN" "4"
						( Origin gPackager )
					)
					( objectStatus "J4A1.4" )
				)
				( pin "vss(93)"
					( attribute "PN" "2"
						( Origin gPackager )
					)
					( objectStatus "J4A1.2" )
				)
			)
			( gate "@baseboard_fab2_lib.baseboard_fab2(sch_1):page53_i66"
				( attribute "BOM_COST" "MEM"
					( Origin gFrontEnd )
				)
				( attribute "CDS_LIB" "mstr_sconn"
					( Origin gPackager )
				)
				( attribute "CDS_LOCATION" "J4A1"
					( Origin gPackager )
				)
				( attribute "CDS_SEC" "2"
					( Origin gPackager )
				)
				( attribute "LOCATION" "J4A1"
					( Origin gFrontEnd )
				)
				( attribute "MATERIAL" "SCONN"
					( Origin gFrontEnd )
				)
				( attribute "PACK_TYPE" "PIP"
					( Origin gFrontEnd )
				)
				( attribute "PART_NUMBER" "H44441-004"
					( Origin gFrontEnd )
				)
				( attribute "PHYS_PAGE" "53"
					( Origin gFrontEnd )
				)
				( attribute "ROOM" "DDR4_CH_F"
					( Origin gFrontEnd )
				)
				( attribute "ROT" "0"
					( Origin gFrontEnd )
				)
				( attribute "SEC" "2"
					( Origin gFrontEnd )
				)
				( attribute "SEC_TYPE" "PIP"
					( Origin gFrontEnd )
				)
				( attribute "VER" "2"
					( Origin gFrontEnd )
				)
				( attribute "XY" "(-50,4350)"
					( Origin gFrontEnd )
				)
				( attribute "CHIPS_PART_NAME" "SCONN288_H44441004"
					( Origin gPackager )
				)
				( attribute "CDS_PART_NAME" "SCONN288_H44441004_PIP-SCONN,HA"
					( Origin gPackager )
				)
				( objectStatus "J4A1" )
				( pin "dqs0n"
					( attribute "PN" "152"
						( Origin gPackager )
					)
					( objectStatus "J4A1.152" )
				)
				( pin "dqs0p"
					( attribute "PN" "153"
						( Origin gPackager )
					)
					( objectStatus "J4A1.153" )
				)
				( pin "dqs1n"
					( attribute "PN" "163"
						( Origin gPackager )
					)
					( objectStatus "J4A1.163" )
				)
				( pin "dqs1p"
					( attribute "PN" "164"
						( Origin gPackager )
					)
					( objectStatus "J4A1.164" )
				)
				( pin "dqs2n"
					( attribute "PN" "174"
						( Origin gPackager )
					)
					( objectStatus "J4A1.174" )
				)
				( pin "dqs2p"
					( attribute "PN" "175"
						( Origin gPackager )
					)
					( objectStatus "J4A1.175" )
				)
				( pin "dqs3n"
					( attribute "PN" "185"
						( Origin gPackager )
					)
					( objectStatus "J4A1.185" )
				)
				( pin "dqs3p"
					( attribute "PN" "186"
						( Origin gPackager )
					)
					( objectStatus "J4A1.186" )
				)
				( pin "dqs4n"
					( attribute "PN" "244"
						( Origin gPackager )
					)
					( objectStatus "J4A1.244" )
				)
				( pin "dqs4p"
					( attribute "PN" "245"
						( Origin gPackager )
					)
					( objectStatus "J4A1.245" )
				)
				( pin "dqs5n"
					( attribute "PN" "255"
						( Origin gPackager )
					)
					( objectStatus "J4A1.255" )
				)
				( pin "dqs5p"
					( attribute "PN" "256"
						( Origin gPackager )
					)
					( objectStatus "J4A1.256" )
				)
				( pin "dqs6n"
					( attribute "PN" "266"
						( Origin gPackager )
					)
					( objectStatus "J4A1.266" )
				)
				( pin "dqs6p"
					( attribute "PN" "267"
						( Origin gPackager )
					)
					( objectStatus "J4A1.267" )
				)
				( pin "dqs7n"
					( attribute "PN" "277"
						( Origin gPackager )
					)
					( objectStatus "J4A1.277" )
				)
				( pin "dqs7p"
					( attribute "PN" "278"
						( Origin gPackager )
					)
					( objectStatus "J4A1.278" )
				)
				( pin "dqs8n"
					( attribute "PN" "196"
						( Origin gPackager )
					)
					( objectStatus "J4A1.196" )
				)
				( pin "dqs8p"
					( attribute "PN" "197"
						( Origin gPackager )
					)
					( objectStatus "J4A1.197" )
				)
				( pin "dqs9n"
					( attribute "PN" "8"
						( Origin gPackager )
					)
					( objectStatus "J4A1.8" )
				)
				( pin "dqs9p"
					( attribute "PN" "7"
						( Origin gPackager )
					)
					( objectStatus "J4A1.7" )
				)
				( pin "dqs10n"
					( attribute "PN" "19"
						( Origin gPackager )
					)
					( objectStatus "J4A1.19" )
				)
				( pin "dqs10p"
					( attribute "PN" "18"
						( Origin gPackager )
					)
					( objectStatus "J4A1.18" )
				)
				( pin "dqs11n"
					( attribute "PN" "30"
						( Origin gPackager )
					)
					( objectStatus "J4A1.30" )
				)
				( pin "dqs11p"
					( attribute "PN" "29"
						( Origin gPackager )
					)
					( objectStatus "J4A1.29" )
				)
				( pin "dqs12n"
					( attribute "PN" "41"
						( Origin gPackager )
					)
					( objectStatus "J4A1.41" )
				)
				( pin "dqs12p"
					( attribute "PN" "40"
						( Origin gPackager )
					)
					( objectStatus "J4A1.40" )
				)
				( pin "dqs13n"
					( attribute "PN" "100"
						( Origin gPackager )
					)
					( objectStatus "J4A1.100" )
				)
				( pin "dqs13p"
					( attribute "PN" "99"
						( Origin gPackager )
					)
					( objectStatus "J4A1.99" )
				)
				( pin "dqs14n"
					( attribute "PN" "111"
						( Origin gPackager )
					)
					( objectStatus "J4A1.111" )
				)
				( pin "dqs14p"
					( attribute "PN" "110"
						( Origin gPackager )
					)
					( objectStatus "J4A1.110" )
				)
				( pin "dqs15n"
					( attribute "PN" "122"
						( Origin gPackager )
					)
					( objectStatus "J4A1.122" )
				)
				( pin "dqs15p"
					( attribute "PN" "121"
						( Origin gPackager )
					)
					( objectStatus "J4A1.121" )
				)
				( pin "dqs16n"
					( attribute "PN" "133"
						( Origin gPackager )
					)
					( objectStatus "J4A1.133" )
				)
				( pin "dqs16p"
					( attribute "PN" "132"
						( Origin gPackager )
					)
					( objectStatus "J4A1.132" )
				)
				( pin "dqs17n"
					( attribute "PN" "52"
						( Origin gPackager )
					)
					( objectStatus "J4A1.52" )
				)
				( pin "dqs17p"
					( attribute "PN" "51"
						( Origin gPackager )
					)
					( objectStatus "J4A1.51" )
				)
			)
			( gate "@baseboard_fab2_lib.baseboard_fab2(sch_1):page53_i111"
				( attribute "BOM_COST" "MEM"
					( Origin gFrontEnd )
				)
				( attribute "CDS_LIB" "mstr_sconn"
					( Origin gPackager )
				)
				( attribute "CDS_LOCATION" "J4A1"
					( Origin gPackager )
				)
				( attribute "CDS_SEC" "1"
					( Origin gPackager )
				)
				( attribute "LOCATION" "J4A1"
					( Origin gFrontEnd )
				)
				( attribute "MATERIAL" "SCONN"
					( Origin gFrontEnd )
				)
				( attribute "PACK_TYPE" "PIP"
					( Origin gFrontEnd )
				)
				( attribute "PART_NUMBER" "H44441-004"
					( Origin gFrontEnd )
				)
				( attribute "PHYS_PAGE" "53"
					( Origin gFrontEnd )
				)
				( attribute "ROOM" "DDR4_CH_F"
					( Origin gFrontEnd )
				)
				( attribute "ROT" "0"
					( Origin gFrontEnd )
				)
				( attribute "SEC" "1"
					( Origin gFrontEnd )
				)
				( attribute "SEC_TYPE" "PIP"
					( Origin gFrontEnd )
				)
				( attribute "VER" "1"
					( Origin gFrontEnd )
				)
				( attribute "XY" "(-2300,2825)"
					( Origin gFrontEnd )
				)
				( attribute "CHIPS_PART_NAME" "SCONN288_H44441004"
					( Origin gPackager )
				)
				( attribute "CDS_PART_NAME" "SCONN288_H44441004_PIP-SCONN,HA"
					( Origin gPackager )
				)
				( objectStatus "J4A1" )
				( pin "a0"
					( attribute "PN" "79"
						( Origin gPackager )
					)
					( objectStatus "J4A1.79" )
				)
				( pin "a1"
					( attribute "PN" "72"
						( Origin gPackager )
					)
					( objectStatus "J4A1.72" )
				)
				( pin "a2"
					( attribute "PN" "216"
						( Origin gPackager )
					)
					( objectStatus "J4A1.216" )
				)
				( pin "a3"
					( attribute "PN" "71"
						( Origin gPackager )
					)
					( objectStatus "J4A1.71" )
				)
				( pin "a4"
					( attribute "PN" "214"
						( Origin gPackager )
					)
					( objectStatus "J4A1.214" )
				)
				( pin "a5"
					( attribute "PN" "213"
						( Origin gPackager )
					)
					( objectStatus "J4A1.213" )
				)
				( pin "a6"
					( attribute "PN" "69"
						( Origin gPackager )
					)
					( objectStatus "J4A1.69" )
				)
				( pin "a7"
					( attribute "PN" "211"
						( Origin gPackager )
					)
					( objectStatus "J4A1.211" )
				)
				( pin "a8"
					( attribute "PN" "68"
						( Origin gPackager )
					)
					( objectStatus "J4A1.68" )
				)
				( pin "a9"
					( attribute "PN" "66"
						( Origin gPackager )
					)
					( objectStatus "J4A1.66" )
				)
				( pin "a10"
					( attribute "PN" "225"
						( Origin gPackager )
					)
					( objectStatus "J4A1.225" )
				)
				( pin "a11"
					( attribute "PN" "210"
						( Origin gPackager )
					)
					( objectStatus "J4A1.210" )
				)
				( pin "a12"
					( attribute "PN" "65"
						( Origin gPackager )
					)
					( objectStatus "J4A1.65" )
				)
				( pin "a13"
					( attribute "PN" "232"
						( Origin gPackager )
					)
					( objectStatus "J4A1.232" )
				)
				( pin "a14_we_n"
					( attribute "PN" "228"
						( Origin gPackager )
					)
					( objectStatus "J4A1.228" )
				)
				( pin "a15_cas_n"
					( attribute "PN" "86"
						( Origin gPackager )
					)
					( objectStatus "J4A1.86" )
				)
				( pin "a16_ras_n"
					( attribute "PN" "82"
						( Origin gPackager )
					)
					( objectStatus "J4A1.82" )
				)
				( pin "a17"
					( attribute "PN" "234"
						( Origin gPackager )
					)
					( objectStatus "J4A1.234" )
				)
				( pin "act_n"
					( attribute "PN" "62"
						( Origin gPackager )
					)
					( objectStatus "J4A1.62" )
				)
				( pin "alert_n"
					( attribute "PN" "208"
						( Origin gPackager )
					)
					( objectStatus "J4A1.208" )
				)
				( pin "ba(0)"
					( attribute "PN" "81"
						( Origin gPackager )
					)
					( objectStatus "J4A1.81" )
				)
				( pin "ba(1)"
					( attribute "PN" "224"
						( Origin gPackager )
					)
					( objectStatus "J4A1.224" )
				)
				( pin "bg(0)"
					( attribute "PN" "63"
						( Origin gPackager )
					)
					( objectStatus "J4A1.63" )
				)
				( pin "bg(1)"
					( attribute "PN" "207"
						( Origin gPackager )
					)
					( objectStatus "J4A1.207" )
				)
				( pin "c(2)"
					( attribute "PN" "235"
						( Origin gPackager )
					)
					( objectStatus "J4A1.235" )
				)
				( pin "cb(0)"
					( attribute "PN" "49"
						( Origin gPackager )
					)
					( objectStatus "J4A1.49" )
				)
				( pin "cb(1)"
					( attribute "PN" "194"
						( Origin gPackager )
					)
					( objectStatus "J4A1.194" )
				)
				( pin "cb(2)"
					( attribute "PN" "56"
						( Origin gPackager )
					)
					( objectStatus "J4A1.56" )
				)
				( pin "cb(3)"
					( attribute "PN" "201"
						( Origin gPackager )
					)
					( objectStatus "J4A1.201" )
				)
				( pin "cb(4)"
					( attribute "PN" "47"
						( Origin gPackager )
					)
					( objectStatus "J4A1.47" )
				)
				( pin "cb(5)"
					( attribute "PN" "192"
						( Origin gPackager )
					)
					( objectStatus "J4A1.192" )
				)
				( pin "cb(6)"
					( attribute "PN" "54"
						( Origin gPackager )
					)
					( objectStatus "J4A1.54" )
				)
				( pin "cb(7)"
					( attribute "PN" "199"
						( Origin gPackager )
					)
					( objectStatus "J4A1.199" )
				)
				( pin "ck0n"
					( attribute "PN" "75"
						( Origin gPackager )
					)
					( objectStatus "J4A1.75" )
				)
				( pin "ck0p"
					( attribute "PN" "74"
						( Origin gPackager )
					)
					( objectStatus "J4A1.74" )
				)
				( pin "ck1n"
					( attribute "PN" "219"
						( Origin gPackager )
					)
					( objectStatus "J4A1.219" )
				)
				( pin "ck1p"
					( attribute "PN" "218"
						( Origin gPackager )
					)
					( objectStatus "J4A1.218" )
				)
				( pin "cke(0)"
					( attribute "PN" "60"
						( Origin gPackager )
					)
					( objectStatus "J4A1.60" )
				)
				( pin "cke(1)"
					( attribute "PN" "203"
						( Origin gPackager )
					)
					( objectStatus "J4A1.203" )
				)
				( pin "dq(0)"
					( attribute "PN" "5"
						( Origin gPackager )
					)
					( objectStatus "J4A1.5" )
				)
				( pin "dq(1)"
					( attribute "PN" "150"
						( Origin gPackager )
					)
					( objectStatus "J4A1.150" )
				)
				( pin "dq(2)"
					( attribute "PN" "12"
						( Origin gPackager )
					)
					( objectStatus "J4A1.12" )
				)
				( pin "dq(3)"
					( attribute "PN" "157"
						( Origin gPackager )
					)
					( objectStatus "J4A1.157" )
				)
				( pin "dq(4)"
					( attribute "PN" "3"
						( Origin gPackager )
					)
					( objectStatus "J4A1.3" )
				)
				( pin "dq(5)"
					( attribute "PN" "148"
						( Origin gPackager )
					)
					( objectStatus "J4A1.148" )
				)
				( pin "dq(6)"
					( attribute "PN" "10"
						( Origin gPackager )
					)
					( objectStatus "J4A1.10" )
				)
				( pin "dq(7)"
					( attribute "PN" "155"
						( Origin gPackager )
					)
					( objectStatus "J4A1.155" )
				)
				( pin "dq(8)"
					( attribute "PN" "16"
						( Origin gPackager )
					)
					( objectStatus "J4A1.16" )
				)
				( pin "dq(9)"
					( attribute "PN" "161"
						( Origin gPackager )
					)
					( objectStatus "J4A1.161" )
				)
				( pin "dq(10)"
					( attribute "PN" "23"
						( Origin gPackager )
					)
					( objectStatus "J4A1.23" )
				)
				( pin "dq(11)"
					( attribute "PN" "168"
						( Origin gPackager )
					)
					( objectStatus "J4A1.168" )
				)
				( pin "dq(12)"
					( attribute "PN" "14"
						( Origin gPackager )
					)
					( objectStatus "J4A1.14" )
				)
				( pin "dq(13)"
					( attribute "PN" "159"
						( Origin gPackager )
					)
					( objectStatus "J4A1.159" )
				)
				( pin "dq(14)"
					( attribute "PN" "21"
						( Origin gPackager )
					)
					( objectStatus "J4A1.21" )
				)
				( pin "dq(15)"
					( attribute "PN" "166"
						( Origin gPackager )
					)
					( objectStatus "J4A1.166" )
				)
				( pin "dq(16)"
					( attribute "PN" "27"
						( Origin gPackager )
					)
					( objectStatus "J4A1.27" )
				)
				( pin "dq(17)"
					( attribute "PN" "172"
						( Origin gPackager )
					)
					( objectStatus "J4A1.172" )
				)
				( pin "dq(18)"
					( attribute "PN" "34"
						( Origin gPackager )
					)
					( objectStatus "J4A1.34" )
				)
				( pin "dq(19)"
					( attribute "PN" "179"
						( Origin gPackager )
					)
					( objectStatus "J4A1.179" )
				)
				( pin "dq(20)"
					( attribute "PN" "25"
						( Origin gPackager )
					)
					( objectStatus "J4A1.25" )
				)
				( pin "dq(21)"
					( attribute "PN" "170"
						( Origin gPackager )
					)
					( objectStatus "J4A1.170" )
				)
				( pin "dq(22)"
					( attribute "PN" "32"
						( Origin gPackager )
					)
					( objectStatus "J4A1.32" )
				)
				( pin "dq(23)"
					( attribute "PN" "177"
						( Origin gPackager )
					)
					( objectStatus "J4A1.177" )
				)
				( pin "dq(24)"
					( attribute "PN" "38"
						( Origin gPackager )
					)
					( objectStatus "J4A1.38" )
				)
				( pin "dq(25)"
					( attribute "PN" "183"
						( Origin gPackager )
					)
					( objectStatus "J4A1.183" )
				)
				( pin "dq(26)"
					( attribute "PN" "45"
						( Origin gPackager )
					)
					( objectStatus "J4A1.45" )
				)
				( pin "dq(27)"
					( attribute "PN" "190"
						( Origin gPackager )
					)
					( objectStatus "J4A1.190" )
				)
				( pin "dq(28)"
					( attribute "PN" "36"
						( Origin gPackager )
					)
					( objectStatus "J4A1.36" )
				)
				( pin "dq(29)"
					( attribute "PN" "181"
						( Origin gPackager )
					)
					( objectStatus "J4A1.181" )
				)
				( pin "dq(30)"
					( attribute "PN" "43"
						( Origin gPackager )
					)
					( objectStatus "J4A1.43" )
				)
				( pin "dq(31)"
					( attribute "PN" "188"
						( Origin gPackager )
					)
					( objectStatus "J4A1.188" )
				)
				( pin "dq(32)"
					( attribute "PN" "97"
						( Origin gPackager )
					)
					( objectStatus "J4A1.97" )
				)
				( pin "dq(33)"
					( attribute "PN" "242"
						( Origin gPackager )
					)
					( objectStatus "J4A1.242" )
				)
				( pin "dq(34)"
					( attribute "PN" "104"
						( Origin gPackager )
					)
					( objectStatus "J4A1.104" )
				)
				( pin "dq(35)"
					( attribute "PN" "249"
						( Origin gPackager )
					)
					( objectStatus "J4A1.249" )
				)
				( pin "dq(36)"
					( attribute "PN" "95"
						( Origin gPackager )
					)
					( objectStatus "J4A1.95" )
				)
				( pin "dq(37)"
					( attribute "PN" "240"
						( Origin gPackager )
					)
					( objectStatus "J4A1.240" )
				)
				( pin "dq(38)"
					( attribute "PN" "102"
						( Origin gPackager )
					)
					( objectStatus "J4A1.102" )
				)
				( pin "dq(39)"
					( attribute "PN" "247"
						( Origin gPackager )
					)
					( objectStatus "J4A1.247" )
				)
				( pin "dq(40)"
					( attribute "PN" "108"
						( Origin gPackager )
					)
					( objectStatus "J4A1.108" )
				)
				( pin "dq(41)"
					( attribute "PN" "253"
						( Origin gPackager )
					)
					( objectStatus "J4A1.253" )
				)
				( pin "dq(42)"
					( attribute "PN" "115"
						( Origin gPackager )
					)
					( objectStatus "J4A1.115" )
				)
				( pin "dq(43)"
					( attribute "PN" "260"
						( Origin gPackager )
					)
					( objectStatus "J4A1.260" )
				)
				( pin "dq(44)"
					( attribute "PN" "106"
						( Origin gPackager )
					)
					( objectStatus "J4A1.106" )
				)
				( pin "dq(45)"
					( attribute "PN" "251"
						( Origin gPackager )
					)
					( objectStatus "J4A1.251" )
				)
				( pin "dq(46)"
					( attribute "PN" "113"
						( Origin gPackager )
					)
					( objectStatus "J4A1.113" )
				)
				( pin "dq(47)"
					( attribute "PN" "258"
						( Origin gPackager )
					)
					( objectStatus "J4A1.258" )
				)
				( pin "dq(48)"
					( attribute "PN" "119"
						( Origin gPackager )
					)
					( objectStatus "J4A1.119" )
				)
				( pin "dq(49)"
					( attribute "PN" "264"
						( Origin gPackager )
					)
					( objectStatus "J4A1.264" )
				)
				( pin "dq(50)"
					( attribute "PN" "126"
						( Origin gPackager )
					)
					( objectStatus "J4A1.126" )
				)
				( pin "dq(51)"
					( attribute "PN" "271"
						( Origin gPackager )
					)
					( objectStatus "J4A1.271" )
				)
				( pin "dq(52)"
					( attribute "PN" "117"
						( Origin gPackager )
					)
					( objectStatus "J4A1.117" )
				)
				( pin "dq(53)"
					( attribute "PN" "262"
						( Origin gPackager )
					)
					( objectStatus "J4A1.262" )
				)
				( pin "dq(54)"
					( attribute "PN" "124"
						( Origin gPackager )
					)
					( objectStatus "J4A1.124" )
				)
				( pin "dq(55)"
					( attribute "PN" "269"
						( Origin gPackager )
					)
					( objectStatus "J4A1.269" )
				)
				( pin "dq(56)"
					( attribute "PN" "130"
						( Origin gPackager )
					)
					( objectStatus "J4A1.130" )
				)
				( pin "dq(57)"
					( attribute "PN" "275"
						( Origin gPackager )
					)
					( objectStatus "J4A1.275" )
				)
				( pin "dq(58)"
					( attribute "PN" "137"
						( Origin gPackager )
					)
					( objectStatus "J4A1.137" )
				)
				( pin "dq(59)"
					( attribute "PN" "282"
						( Origin gPackager )
					)
					( objectStatus "J4A1.282" )
				)
				( pin "dq(60)"
					( attribute "PN" "128"
						( Origin gPackager )
					)
					( objectStatus "J4A1.128" )
				)
				( pin "dq(61)"
					( attribute "PN" "273"
						( Origin gPackager )
					)
					( objectStatus "J4A1.273" )
				)
				( pin "dq(62)"
					( attribute "PN" "135"
						( Origin gPackager )
					)
					( objectStatus "J4A1.135" )
				)
				( pin "dq(63)"
					( attribute "PN" "280"
						( Origin gPackager )
					)
					( objectStatus "J4A1.280" )
				)
				( pin "event_n"
					( attribute "PN" "78"
						( Origin gPackager )
					)
					( objectStatus "J4A1.78" )
				)
				( pin "odt(0)"
					( attribute "PN" "87"
						( Origin gPackager )
					)
					( objectStatus "J4A1.87" )
				)
				( pin "odt(1)"
					( attribute "PN" "91"
						( Origin gPackager )
					)
					( objectStatus "J4A1.91" )
				)
				( pin "par"
					( attribute "PN" "222"
						( Origin gPackager )
					)
					( objectStatus "J4A1.222" )
				)
				( pin "reset_n"
					( attribute "PN" "58"
						( Origin gPackager )
					)
					( objectStatus "J4A1.58" )
				)
				( pin "rfu(0)"
					( attribute "PN" "205"
						( Origin gPackager )
					)
					( objectStatus "J4A1.205" )
				)
				( pin "rfu(1)"
					( attribute "PN" "227"
						( Origin gPackager )
					)
					( objectStatus "J4A1.227" )
				)
				( pin "rfu(2)"
					( attribute "PN" "144"
						( Origin gPackager )
					)
					( objectStatus "J4A1.144" )
				)
				( pin "s0_n"
					( attribute "PN" "84"
						( Origin gPackager )
					)
					( objectStatus "J4A1.84" )
				)
				( pin "s1_n"
					( attribute "PN" "89"
						( Origin gPackager )
					)
					( objectStatus "J4A1.89" )
				)
				( pin "s2_n_c(0)"
					( attribute "PN" "93"
						( Origin gPackager )
					)
					( objectStatus "J4A1.93" )
				)
				( pin "s3_n_c(1)"
					( attribute "PN" "237"
						( Origin gPackager )
					)
					( objectStatus "J4A1.237" )
				)
				( pin "sa(0)"
					( attribute "PN" "139"
						( Origin gPackager )
					)
					( objectStatus "J4A1.139" )
				)
				( pin "sa(1)"
					( attribute "PN" "140"
						( Origin gPackager )
					)
					( objectStatus "J4A1.140" )
				)
				( pin "sa(2)"
					( attribute "PN" "238"
						( Origin gPackager )
					)
					( objectStatus "J4A1.238" )
				)
				( pin "save_n_nc"
					( attribute "PN" "230"
						( Origin gPackager )
					)
					( objectStatus "J4A1.230" )
				)
				( pin "scl"
					( attribute "PN" "141"
						( Origin gPackager )
					)
					( objectStatus "J4A1.141" )
				)
				( pin "sda"
					( attribute "PN" "285"
						( Origin gPackager )
					)
					( objectStatus "J4A1.285" )
				)
				( pin "vddspd"
					( attribute "PN" "284"
						( Origin gPackager )
					)
					( objectStatus "J4A1.284" )
				)
				( pin "vrefca"
					( attribute "PN" "146"
						( Origin gPackager )
					)
					( objectStatus "J4A1.146" )
				)
			)
			( gate "@baseboard_fab2_lib.baseboard_fab2(sch_1):page53_i171"
				( attribute "BOM_COST" "MEM"
					( Origin gFrontEnd )
				)
				( attribute "CDS_LIB" "mstr_sconn"
					( Origin gPackager )
				)
				( attribute "CDS_LOCATION" "J4A1"
					( Origin gPackager )
				)
				( attribute "CDS_SEC" "4"
					( Origin gPackager )
				)
				( attribute "LOCATION" "J4A1"
					( Origin gFrontEnd )
				)
				( attribute "MATERIAL" "SCONN"
					( Origin gFrontEnd )
				)
				( attribute "PACK_TYPE" "PIP"
					( Origin gFrontEnd )
				)
				( attribute "PART_NUMBER" "H44441-004"
					( Origin gFrontEnd )
				)
				( attribute "PHYS_PAGE" "53"
					( Origin gFrontEnd )
				)
				( attribute "ROOM" "DDR4_CH_F"
					( Origin gFrontEnd )
				)
				( attribute "ROT" "0"
					( Origin gFrontEnd )
				)
				( attribute "SEC" "4"
					( Origin gFrontEnd )
				)
				( attribute "SEC_TYPE" "PIP"
					( Origin gFrontEnd )
				)
				( attribute "VER" "4"
					( Origin gFrontEnd )
				)
				( attribute "XY" "(-250,2050)"
					( Origin gFrontEnd )
				)
				( attribute "CHIPS_PART_NAME" "SCONN288_H44441004"
					( Origin gPackager )
				)
				( attribute "CDS_PART_NAME" "SCONN288_H44441004_PIP-SCONN,HA"
					( Origin gPackager )
				)
				( objectStatus "J4A1" )
				( pin "\12v\(0)"
					( attribute "PN" "145"
						( Origin gPackager )
					)
					( objectStatus "J4A1.145" )
				)
				( pin "\12v\(1)"
					( attribute "PN" "1"
						( Origin gPackager )
					)
					( objectStatus "J4A1.1" )
				)
				( pin "vdd(0)"
					( attribute "PN" "236"
						( Origin gPackager )
					)
					( objectStatus "J4A1.236" )
				)
				( pin "vdd(1)"
					( attribute "PN" "233"
						( Origin gPackager )
					)
					( objectStatus "J4A1.233" )
				)
				( pin "vdd(2)"
					( attribute "PN" "231"
						( Origin gPackager )
					)
					( objectStatus "J4A1.231" )
				)
				( pin "vdd(3)"
					( attribute "PN" "229"
						( Origin gPackager )
					)
					( objectStatus "J4A1.229" )
				)
				( pin "vdd(4)"
					( attribute "PN" "226"
						( Origin gPackager )
					)
					( objectStatus "J4A1.226" )
				)
				( pin "vdd(5)"
					( attribute "PN" "223"
						( Origin gPackager )
					)
					( objectStatus "J4A1.223" )
				)
				( pin "vdd(6)"
					( attribute "PN" "220"
						( Origin gPackager )
					)
					( objectStatus "J4A1.220" )
				)
				( pin "vdd(7)"
					( attribute "PN" "217"
						( Origin gPackager )
					)
					( objectStatus "J4A1.217" )
				)
				( pin "vdd(8)"
					( attribute "PN" "215"
						( Origin gPackager )
					)
					( objectStatus "J4A1.215" )
				)
				( pin "vdd(9)"
					( attribute "PN" "212"
						( Origin gPackager )
					)
					( objectStatus "J4A1.212" )
				)
				( pin "vdd(10)"
					( attribute "PN" "209"
						( Origin gPackager )
					)
					( objectStatus "J4A1.209" )
				)
				( pin "vdd(11)"
					( attribute "PN" "206"
						( Origin gPackager )
					)
					( objectStatus "J4A1.206" )
				)
				( pin "vdd(12)"
					( attribute "PN" "204"
						( Origin gPackager )
					)
					( objectStatus "J4A1.204" )
				)
				( pin "vdd(13)"
					( attribute "PN" "92"
						( Origin gPackager )
					)
					( objectStatus "J4A1.92" )
				)
				( pin "vdd(14)"
					( attribute "PN" "90"
						( Origin gPackager )
					)
					( objectStatus "J4A1.90" )
				)
				( pin "vdd(15)"
					( attribute "PN" "88"
						( Origin gPackager )
					)
					( objectStatus "J4A1.88" )
				)
				( pin "vdd(16)"
					( attribute "PN" "85"
						( Origin gPackager )
					)
					( objectStatus "J4A1.85" )
				)
				( pin "vdd(17)"
					( attribute "PN" "83"
						( Origin gPackager )
					)
					( objectStatus "J4A1.83" )
				)
				( pin "vdd(18)"
					( attribute "PN" "80"
						( Origin gPackager )
					)
					( objectStatus "J4A1.80" )
				)
				( pin "vdd(19)"
					( attribute "PN" "76"
						( Origin gPackager )
					)
					( objectStatus "J4A1.76" )
				)
				( pin "vdd(20)"
					( attribute "PN" "73"
						( Origin gPackager )
					)
					( objectStatus "J4A1.73" )
				)
				( pin "vdd(21)"
					( attribute "PN" "70"
						( Origin gPackager )
					)
					( objectStatus "J4A1.70" )
				)
				( pin "vdd(22)"
					( attribute "PN" "67"
						( Origin gPackager )
					)
					( objectStatus "J4A1.67" )
				)
				( pin "vdd(23)"
					( attribute "PN" "64"
						( Origin gPackager )
					)
					( objectStatus "J4A1.64" )
				)
				( pin "vdd(24)"
					( attribute "PN" "61"
						( Origin gPackager )
					)
					( objectStatus "J4A1.61" )
				)
				( pin "vdd(25)"
					( attribute "PN" "59"
						( Origin gPackager )
					)
					( objectStatus "J4A1.59" )
				)
				( pin "vpp(0)"
					( attribute "PN" "287"
						( Origin gPackager )
					)
					( objectStatus "J4A1.287" )
				)
				( pin "vpp(1)"
					( attribute "PN" "286"
						( Origin gPackager )
					)
					( objectStatus "J4A1.286" )
				)
				( pin "vpp(2)"
					( attribute "PN" "288"
						( Origin gPackager )
					)
					( objectStatus "J4A1.288" )
				)
				( pin "vpp(3)"
					( attribute "PN" "143"
						( Origin gPackager )
					)
					( objectStatus "J4A1.143" )
				)
				( pin "vpp(4)"
					( attribute "PN" "142"
						( Origin gPackager )
					)
					( objectStatus "J4A1.142" )
				)
				( pin "vtt(0)"
					( attribute "PN" "221"
						( Origin gPackager )
					)
					( objectStatus "J4A1.221" )
				)
				( pin "vtt(1)"
					( attribute "PN" "77"
						( Origin gPackager )
					)
					( objectStatus "J4A1.77" )
				)
			)
			( gate "@baseboard_fab2_lib.baseboard_fab2(sch_1):page53_i178"
				( attribute "BOM_COST" "MEM"
					( Origin gFrontEnd )
				)
				( attribute "CDS_LIB" "dev_discrete"
					( Origin gPackager )
				)
				( attribute "CDS_LOCATION" "C6L1"
					( Origin gPackager )
				)
				( attribute "CDS_SEC" "1"
					( Origin gPackager )
				)
				( attribute "LOCATION" "C6L1"
					( Origin gFrontEnd )
				)
				( attribute "MATERIAL" "X7R"
					( Origin gFrontEnd )
				)
				( attribute "PACK_TYPE" "0402V"
					( Origin gFrontEnd )
				)
				( attribute "PART_NUMBER" "A36096-045"
					( Origin gFrontEnd )
				)
				( attribute "PHYS_PAGE" "53"
					( Origin gFrontEnd )
				)
				( attribute "ROOM" "DDR4_CH_F"
					( Origin gFrontEnd )
				)
				( attribute "ROT" "2"
					( Origin gFrontEnd )
				)
				( attribute "SEC" "1"
					( Origin gPackager )
				)
				( attribute "TOLERANCE" "10%"
					( Origin gFrontEnd )
				)
				( attribute "VALUE" "0.01UF"
					( Origin gFrontEnd )
				)
				( attribute "VER" "1"
					( Origin gFrontEnd )
				)
				( attribute "VOLTAGE" "25V"
					( Units "uVoltage" "V" 1.000000)
					( Origin gFrontEnd )
				)
				( attribute "XY" "(-4500,1125)"
					( Origin gFrontEnd )
				)
				( attribute "CHIPS_PART_NAME" "CAP_A"
					( Origin gPackager )
				)
				( attribute "CDS_PART_NAME" "CAP_A_0402V-0.01UF,25V,10%,X7RA"
					( Origin gPackager )
				)
				( objectStatus "C6L1" )
				( pin "a"
					( attribute "PN" "1"
						( Origin gPackager )
					)
					( objectStatus "C6L1.1" )
				)
				( pin "b"
					( attribute "PN" "2"
						( Origin gPackager )
					)
					( objectStatus "C6L1.2" )
				)
			)
			( gate "@baseboard_fab2_lib.baseboard_fab2(sch_1):page54_i43"
				( attribute "BOM_COST" "MEM"
					( Origin gFrontEnd )
				)
				( attribute "CDS_LIB" "mstr_sconn"
					( Origin gPackager )
				)
				( attribute "CDS_LOCATION" "J6L1"
					( Origin gPackager )
				)
				( attribute "CDS_SEC" "3"
					( Origin gPackager )
				)
				( attribute "LOCATION" "J6L1"
					( Origin gFrontEnd )
				)
				( attribute "MATERIAL" "SCONN"
					( Origin gFrontEnd )
				)
				( attribute "PACK_TYPE" "PIP"
					( Origin gFrontEnd )
				)
				( attribute "PART_NUMBER" "H44441-003"
					( Origin gFrontEnd )
				)
				( attribute "PHYS_PAGE" "54"
					( Origin gFrontEnd )
				)
				( attribute "ROOM" "DDR4_CH_F1"
					( Origin gFrontEnd )
				)
				( attribute "ROT" "0"
					( Origin gFrontEnd )
				)
				( attribute "SEC" "3"
					( Origin gFrontEnd )
				)
				( attribute "SEC_TYPE" "PIP"
					( Origin gFrontEnd )
				)
				( attribute "VER" "3"
					( Origin gFrontEnd )
				)
				( attribute "XY" "(1800,2550)"
					( Origin gFrontEnd )
				)
				( attribute "CHIPS_PART_NAME" "SCONN288_H44441003"
					( Origin gPackager )
				)
				( attribute "CDS_PART_NAME" "SCONN288_H44441003_PIP-SCONN,HA"
					( Origin gPackager )
				)
				( objectStatus "J6L1" )
				( pin "vss(0)"
					( attribute "PN" "283"
						( Origin gPackager )
					)
					( objectStatus "J6L1.283" )
				)
				( pin "vss(1)"
					( attribute "PN" "281"
						( Origin gPackager )
					)
					( objectStatus "J6L1.281" )
				)
				( pin "vss(2)"
					( attribute "PN" "279"
						( Origin gPackager )
					)
					( objectStatus "J6L1.279" )
				)
				( pin "vss(3)"
					( attribute "PN" "276"
						( Origin gPackager )
					)
					( objectStatus "J6L1.276" )
				)
				( pin "vss(4)"
					( attribute "PN" "274"
						( Origin gPackager )
					)
					( objectStatus "J6L1.274" )
				)
				( pin "vss(5)"
					( attribute "PN" "272"
						( Origin gPackager )
					)
					( objectStatus "J6L1.272" )
				)
				( pin "vss(6)"
					( attribute "PN" "270"
						( Origin gPackager )
					)
					( objectStatus "J6L1.270" )
				)
				( pin "vss(7)"
					( attribute "PN" "268"
						( Origin gPackager )
					)
					( objectStatus "J6L1.268" )
				)
				( pin "vss(8)"
					( attribute "PN" "265"
						( Origin gPackager )
					)
					( objectStatus "J6L1.265" )
				)
				( pin "vss(9)"
					( attribute "PN" "263"
						( Origin gPackager )
					)
					( objectStatus "J6L1.263" )
				)
				( pin "vss(10)"
					( attribute "PN" "261"
						( Origin gPackager )
					)
					( objectStatus "J6L1.261" )
				)
				( pin "vss(11)"
					( attribute "PN" "259"
						( Origin gPackager )
					)
					( objectStatus "J6L1.259" )
				)
				( pin "vss(12)"
					( attribute "PN" "257"
						( Origin gPackager )
					)
					( objectStatus "J6L1.257" )
				)
				( pin "vss(13)"
					( attribute "PN" "254"
						( Origin gPackager )
					)
					( objectStatus "J6L1.254" )
				)
				( pin "vss(14)"
					( attribute "PN" "252"
						( Origin gPackager )
					)
					( objectStatus "J6L1.252" )
				)
				( pin "vss(15)"
					( attribute "PN" "250"
						( Origin gPackager )
					)
					( objectStatus "J6L1.250" )
				)
				( pin "vss(16)"
					( attribute "PN" "248"
						( Origin gPackager )
					)
					( objectStatus "J6L1.248" )
				)
				( pin "vss(17)"
					( attribute "PN" "246"
						( Origin gPackager )
					)
					( objectStatus "J6L1.246" )
				)
				( pin "vss(18)"
					( attribute "PN" "243"
						( Origin gPackager )
					)
					( objectStatus "J6L1.243" )
				)
				( pin "vss(19)"
					( attribute "PN" "241"
						( Origin gPackager )
					)
					( objectStatus "J6L1.241" )
				)
				( pin "vss(20)"
					( attribute "PN" "239"
						( Origin gPackager )
					)
					( objectStatus "J6L1.239" )
				)
				( pin "vss(21)"
					( attribute "PN" "202"
						( Origin gPackager )
					)
					( objectStatus "J6L1.202" )
				)
				( pin "vss(22)"
					( attribute "PN" "200"
						( Origin gPackager )
					)
					( objectStatus "J6L1.200" )
				)
				( pin "vss(23)"
					( attribute "PN" "198"
						( Origin gPackager )
					)
					( objectStatus "J6L1.198" )
				)
				( pin "vss(24)"
					( attribute "PN" "195"
						( Origin gPackager )
					)
					( objectStatus "J6L1.195" )
				)
				( pin "vss(25)"
					( attribute "PN" "193"
						( Origin gPackager )
					)
					( objectStatus "J6L1.193" )
				)
				( pin "vss(26)"
					( attribute "PN" "191"
						( Origin gPackager )
					)
					( objectStatus "J6L1.191" )
				)
				( pin "vss(27)"
					( attribute "PN" "189"
						( Origin gPackager )
					)
					( objectStatus "J6L1.189" )
				)
				( pin "vss(28)"
					( attribute "PN" "187"
						( Origin gPackager )
					)
					( objectStatus "J6L1.187" )
				)
				( pin "vss(29)"
					( attribute "PN" "184"
						( Origin gPackager )
					)
					( objectStatus "J6L1.184" )
				)
				( pin "vss(30)"
					( attribute "PN" "182"
						( Origin gPackager )
					)
					( objectStatus "J6L1.182" )
				)
				( pin "vss(31)"
					( attribute "PN" "180"
						( Origin gPackager )
					)
					( objectStatus "J6L1.180" )
				)
				( pin "vss(32)"
					( attribute "PN" "178"
						( Origin gPackager )
					)
					( objectStatus "J6L1.178" )
				)
				( pin "vss(33)"
					( attribute "PN" "176"
						( Origin gPackager )
					)
					( objectStatus "J6L1.176" )
				)
				( pin "vss(34)"
					( attribute "PN" "173"
						( Origin gPackager )
					)
					( objectStatus "J6L1.173" )
				)
				( pin "vss(35)"
					( attribute "PN" "171"
						( Origin gPackager )
					)
					( objectStatus "J6L1.171" )
				)
				( pin "vss(36)"
					( attribute "PN" "169"
						( Origin gPackager )
					)
					( objectStatus "J6L1.169" )
				)
				( pin "vss(37)"
					( attribute "PN" "167"
						( Origin gPackager )
					)
					( objectStatus "J6L1.167" )
				)
				( pin "vss(38)"
					( attribute "PN" "165"
						( Origin gPackager )
					)
					( objectStatus "J6L1.165" )
				)
				( pin "vss(39)"
					( attribute "PN" "162"
						( Origin gPackager )
					)
					( objectStatus "J6L1.162" )
				)
				( pin "vss(40)"
					( attribute "PN" "160"
						( Origin gPackager )
					)
					( objectStatus "J6L1.160" )
				)
				( pin "vss(41)"
					( attribute "PN" "158"
						( Origin gPackager )
					)
					( objectStatus "J6L1.158" )
				)
				( pin "vss(42)"
					( attribute "PN" "156"
						( Origin gPackager )
					)
					( objectStatus "J6L1.156" )
				)
				( pin "vss(43)"
					( attribute "PN" "154"
						( Origin gPackager )
					)
					( objectStatus "J6L1.154" )
				)
				( pin "vss(44)"
					( attribute "PN" "151"
						( Origin gPackager )
					)
					( objectStatus "J6L1.151" )
				)
				( pin "vss(45)"
					( attribute "PN" "149"
						( Origin gPackager )
					)
					( objectStatus "J6L1.149" )
				)
				( pin "vss(46)"
					( attribute "PN" "147"
						( Origin gPackager )
					)
					( objectStatus "J6L1.147" )
				)
				( pin "vss(47)"
					( attribute "PN" "138"
						( Origin gPackager )
					)
					( objectStatus "J6L1.138" )
				)
				( pin "vss(48)"
					( attribute "PN" "136"
						( Origin gPackager )
					)
					( objectStatus "J6L1.136" )
				)
				( pin "vss(49)"
					( attribute "PN" "134"
						( Origin gPackager )
					)
					( objectStatus "J6L1.134" )
				)
				( pin "vss(50)"
					( attribute "PN" "131"
						( Origin gPackager )
					)
					( objectStatus "J6L1.131" )
				)
				( pin "vss(51)"
					( attribute "PN" "129"
						( Origin gPackager )
					)
					( objectStatus "J6L1.129" )
				)
				( pin "vss(52)"
					( attribute "PN" "127"
						( Origin gPackager )
					)
					( objectStatus "J6L1.127" )
				)
				( pin "vss(53)"
					( attribute "PN" "125"
						( Origin gPackager )
					)
					( objectStatus "J6L1.125" )
				)
				( pin "vss(54)"
					( attribute "PN" "123"
						( Origin gPackager )
					)
					( objectStatus "J6L1.123" )
				)
				( pin "vss(55)"
					( attribute "PN" "120"
						( Origin gPackager )
					)
					( objectStatus "J6L1.120" )
				)
				( pin "vss(56)"
					( attribute "PN" "118"
						( Origin gPackager )
					)
					( objectStatus "J6L1.118" )
				)
				( pin "vss(57)"
					( attribute "PN" "116"
						( Origin gPackager )
					)
					( objectStatus "J6L1.116" )
				)
				( pin "vss(58)"
					( attribute "PN" "114"
						( Origin gPackager )
					)
					( objectStatus "J6L1.114" )
				)
				( pin "vss(59)"
					( attribute "PN" "112"
						( Origin gPackager )
					)
					( objectStatus "J6L1.112" )
				)
				( pin "vss(60)"
					( attribute "PN" "109"
						( Origin gPackager )
					)
					( objectStatus "J6L1.109" )
				)
				( pin "vss(61)"
					( attribute "PN" "107"
						( Origin gPackager )
					)
					( objectStatus "J6L1.107" )
				)
				( pin "vss(62)"
					( attribute "PN" "105"
						( Origin gPackager )
					)
					( objectStatus "J6L1.105" )
				)
				( pin "vss(63)"
					( attribute "PN" "103"
						( Origin gPackager )
					)
					( objectStatus "J6L1.103" )
				)
				( pin "vss(64)"
					( attribute "PN" "101"
						( Origin gPackager )
					)
					( objectStatus "J6L1.101" )
				)
				( pin "vss(65)"
					( attribute "PN" "98"
						( Origin gPackager )
					)
					( objectStatus "J6L1.98" )
				)
				( pin "vss(66)"
					( attribute "PN" "96"
						( Origin gPackager )
					)
					( objectStatus "J6L1.96" )
				)
				( pin "vss(67)"
					( attribute "PN" "94"
						( Origin gPackager )
					)
					( objectStatus "J6L1.94" )
				)
				( pin "vss(68)"
					( attribute "PN" "57"
						( Origin gPackager )
					)
					( objectStatus "J6L1.57" )
				)
				( pin "vss(69)"
					( attribute "PN" "55"
						( Origin gPackager )
					)
					( objectStatus "J6L1.55" )
				)
				( pin "vss(70)"
					( attribute "PN" "53"
						( Origin gPackager )
					)
					( objectStatus "J6L1.53" )
				)
				( pin "vss(71)"
					( attribute "PN" "50"
						( Origin gPackager )
					)
					( objectStatus "J6L1.50" )
				)
				( pin "vss(72)"
					( attribute "PN" "48"
						( Origin gPackager )
					)
					( objectStatus "J6L1.48" )
				)
				( pin "vss(73)"
					( attribute "PN" "46"
						( Origin gPackager )
					)
					( objectStatus "J6L1.46" )
				)
				( pin "vss(74)"
					( attribute "PN" "44"
						( Origin gPackager )
					)
					( objectStatus "J6L1.44" )
				)
				( pin "vss(75)"
					( attribute "PN" "42"
						( Origin gPackager )
					)
					( objectStatus "J6L1.42" )
				)
				( pin "vss(76)"
					( attribute "PN" "39"
						( Origin gPackager )
					)
					( objectStatus "J6L1.39" )
				)
				( pin "vss(77)"
					( attribute "PN" "37"
						( Origin gPackager )
					)
					( objectStatus "J6L1.37" )
				)
				( pin "vss(78)"
					( attribute "PN" "35"
						( Origin gPackager )
					)
					( objectStatus "J6L1.35" )
				)
				( pin "vss(79)"
					( attribute "PN" "33"
						( Origin gPackager )
					)
					( objectStatus "J6L1.33" )
				)
				( pin "vss(80)"
					( attribute "PN" "31"
						( Origin gPackager )
					)
					( objectStatus "J6L1.31" )
				)
				( pin "vss(81)"
					( attribute "PN" "28"
						( Origin gPackager )
					)
					( objectStatus "J6L1.28" )
				)
				( pin "vss(82)"
					( attribute "PN" "26"
						( Origin gPackager )
					)
					( objectStatus "J6L1.26" )
				)
				( pin "vss(83)"
					( attribute "PN" "24"
						( Origin gPackager )
					)
					( objectStatus "J6L1.24" )
				)
				( pin "vss(84)"
					( attribute "PN" "22"
						( Origin gPackager )
					)
					( objectStatus "J6L1.22" )
				)
				( pin "vss(85)"
					( attribute "PN" "20"
						( Origin gPackager )
					)
					( objectStatus "J6L1.20" )
				)
				( pin "vss(86)"
					( attribute "PN" "17"
						( Origin gPackager )
					)
					( objectStatus "J6L1.17" )
				)
				( pin "vss(87)"
					( attribute "PN" "15"
						( Origin gPackager )
					)
					( objectStatus "J6L1.15" )
				)
				( pin "vss(88)"
					( attribute "PN" "13"
						( Origin gPackager )
					)
					( objectStatus "J6L1.13" )
				)
				( pin "vss(89)"
					( attribute "PN" "11"
						( Origin gPackager )
					)
					( objectStatus "J6L1.11" )
				)
				( pin "vss(90)"
					( attribute "PN" "9"
						( Origin gPackager )
					)
					( objectStatus "J6L1.9" )
				)
				( pin "vss(91)"
					( attribute "PN" "6"
						( Origin gPackager )
					)
					( objectStatus "J6L1.6" )
				)
				( pin "vss(92)"
					( attribute "PN" "4"
						( Origin gPackager )
					)
					( objectStatus "J6L1.4" )
				)
				( pin "vss(93)"
					( attribute "PN" "2"
						( Origin gPackager )
					)
					( objectStatus "J6L1.2" )
				)
			)
			( gate "@baseboard_fab2_lib.baseboard_fab2(sch_1):page54_i66"
				( attribute "BOM_COST" "MEM"
					( Origin gFrontEnd )
				)
				( attribute "CDS_LIB" "mstr_sconn"
					( Origin gPackager )
				)
				( attribute "CDS_LOCATION" "J6L1"
					( Origin gPackager )
				)
				( attribute "CDS_SEC" "2"
					( Origin gPackager )
				)
				( attribute "LOCATION" "J6L1"
					( Origin gFrontEnd )
				)
				( attribute "MATERIAL" "SCONN"
					( Origin gFrontEnd )
				)
				( attribute "PACK_TYPE" "PIP"
					( Origin gFrontEnd )
				)
				( attribute "PART_NUMBER" "H44441-003"
					( Origin gFrontEnd )
				)
				( attribute "PHYS_PAGE" "54"
					( Origin gFrontEnd )
				)
				( attribute "ROOM" "DDR4_CH_F1"
					( Origin gFrontEnd )
				)
				( attribute "ROT" "0"
					( Origin gFrontEnd )
				)
				( attribute "SEC" "2"
					( Origin gFrontEnd )
				)
				( attribute "SEC_TYPE" "PIP"
					( Origin gFrontEnd )
				)
				( attribute "VER" "2"
					( Origin gFrontEnd )
				)
				( attribute "XY" "(0,4300)"
					( Origin gFrontEnd )
				)
				( attribute "CHIPS_PART_NAME" "SCONN288_H44441003"
					( Origin gPackager )
				)
				( attribute "CDS_PART_NAME" "SCONN288_H44441003_PIP-SCONN,HA"
					( Origin gPackager )
				)
				( objectStatus "J6L1" )
				( pin "dqs0n"
					( attribute "PN" "152"
						( Origin gPackager )
					)
					( objectStatus "J6L1.152" )
				)
				( pin "dqs0p"
					( attribute "PN" "153"
						( Origin gPackager )
					)
					( objectStatus "J6L1.153" )
				)
				( pin "dqs1n"
					( attribute "PN" "163"
						( Origin gPackager )
					)
					( objectStatus "J6L1.163" )
				)
				( pin "dqs1p"
					( attribute "PN" "164"
						( Origin gPackager )
					)
					( objectStatus "J6L1.164" )
				)
				( pin "dqs2n"
					( attribute "PN" "174"
						( Origin gPackager )
					)
					( objectStatus "J6L1.174" )
				)
				( pin "dqs2p"
					( attribute "PN" "175"
						( Origin gPackager )
					)
					( objectStatus "J6L1.175" )
				)
				( pin "dqs3n"
					( attribute "PN" "185"
						( Origin gPackager )
					)
					( objectStatus "J6L1.185" )
				)
				( pin "dqs3p"
					( attribute "PN" "186"
						( Origin gPackager )
					)
					( objectStatus "J6L1.186" )
				)
				( pin "dqs4n"
					( attribute "PN" "244"
						( Origin gPackager )
					)
					( objectStatus "J6L1.244" )
				)
				( pin "dqs4p"
					( attribute "PN" "245"
						( Origin gPackager )
					)
					( objectStatus "J6L1.245" )
				)
				( pin "dqs5n"
					( attribute "PN" "255"
						( Origin gPackager )
					)
					( objectStatus "J6L1.255" )
				)
				( pin "dqs5p"
					( attribute "PN" "256"
						( Origin gPackager )
					)
					( objectStatus "J6L1.256" )
				)
				( pin "dqs6n"
					( attribute "PN" "266"
						( Origin gPackager )
					)
					( objectStatus "J6L1.266" )
				)
				( pin "dqs6p"
					( attribute "PN" "267"
						( Origin gPackager )
					)
					( objectStatus "J6L1.267" )
				)
				( pin "dqs7n"
					( attribute "PN" "277"
						( Origin gPackager )
					)
					( objectStatus "J6L1.277" )
				)
				( pin "dqs7p"
					( attribute "PN" "278"
						( Origin gPackager )
					)
					( objectStatus "J6L1.278" )
				)
				( pin "dqs8n"
					( attribute "PN" "196"
						( Origin gPackager )
					)
					( objectStatus "J6L1.196" )
				)
				( pin "dqs8p"
					( attribute "PN" "197"
						( Origin gPackager )
					)
					( objectStatus "J6L1.197" )
				)
				( pin "dqs9n"
					( attribute "PN" "8"
						( Origin gPackager )
					)
					( objectStatus "J6L1.8" )
				)
				( pin "dqs9p"
					( attribute "PN" "7"
						( Origin gPackager )
					)
					( objectStatus "J6L1.7" )
				)
				( pin "dqs10n"
					( attribute "PN" "19"
						( Origin gPackager )
					)
					( objectStatus "J6L1.19" )
				)
				( pin "dqs10p"
					( attribute "PN" "18"
						( Origin gPackager )
					)
					( objectStatus "J6L1.18" )
				)
				( pin "dqs11n"
					( attribute "PN" "30"
						( Origin gPackager )
					)
					( objectStatus "J6L1.30" )
				)
				( pin "dqs11p"
					( attribute "PN" "29"
						( Origin gPackager )
					)
					( objectStatus "J6L1.29" )
				)
				( pin "dqs12n"
					( attribute "PN" "41"
						( Origin gPackager )
					)
					( objectStatus "J6L1.41" )
				)
				( pin "dqs12p"
					( attribute "PN" "40"
						( Origin gPackager )
					)
					( objectStatus "J6L1.40" )
				)
				( pin "dqs13n"
					( attribute "PN" "100"
						( Origin gPackager )
					)
					( objectStatus "J6L1.100" )
				)
				( pin "dqs13p"
					( attribute "PN" "99"
						( Origin gPackager )
					)
					( objectStatus "J6L1.99" )
				)
				( pin "dqs14n"
					( attribute "PN" "111"
						( Origin gPackager )
					)
					( objectStatus "J6L1.111" )
				)
				( pin "dqs14p"
					( attribute "PN" "110"
						( Origin gPackager )
					)
					( objectStatus "J6L1.110" )
				)
				( pin "dqs15n"
					( attribute "PN" "122"
						( Origin gPackager )
					)
					( objectStatus "J6L1.122" )
				)
				( pin "dqs15p"
					( attribute "PN" "121"
						( Origin gPackager )
					)
					( objectStatus "J6L1.121" )
				)
				( pin "dqs16n"
					( attribute "PN" "133"
						( Origin gPackager )
					)
					( objectStatus "J6L1.133" )
				)
				( pin "dqs16p"
					( attribute "PN" "132"
						( Origin gPackager )
					)
					( objectStatus "J6L1.132" )
				)
				( pin "dqs17n"
					( attribute "PN" "52"
						( Origin gPackager )
					)
					( objectStatus "J6L1.52" )
				)
				( pin "dqs17p"
					( attribute "PN" "51"
						( Origin gPackager )
					)
					( objectStatus "J6L1.51" )
				)
			)
			( gate "@baseboard_fab2_lib.baseboard_fab2(sch_1):page54_i111"
				( attribute "BOM_COST" "MEM"
					( Origin gFrontEnd )
				)
				( attribute "CDS_LIB" "mstr_sconn"
					( Origin gPackager )
				)
				( attribute "CDS_LOCATION" "J6L1"
					( Origin gPackager )
				)
				( attribute "CDS_SEC" "1"
					( Origin gPackager )
				)
				( attribute "LOCATION" "J6L1"
					( Origin gFrontEnd )
				)
				( attribute "MATERIAL" "SCONN"
					( Origin gFrontEnd )
				)
				( attribute "PACK_TYPE" "PIP"
					( Origin gFrontEnd )
				)
				( attribute "PART_NUMBER" "H44441-003"
					( Origin gFrontEnd )
				)
				( attribute "PHYS_PAGE" "54"
					( Origin gFrontEnd )
				)
				( attribute "ROOM" "DDR4_CH_F1"
					( Origin gFrontEnd )
				)
				( attribute "ROT" "0"
					( Origin gFrontEnd )
				)
				( attribute "SEC" "1"
					( Origin gFrontEnd )
				)
				( attribute "SEC_TYPE" "PIP"
					( Origin gFrontEnd )
				)
				( attribute "VER" "1"
					( Origin gFrontEnd )
				)
				( attribute "XY" "(-2400,3100)"
					( Origin gFrontEnd )
				)
				( attribute "CHIPS_PART_NAME" "SCONN288_H44441003"
					( Origin gPackager )
				)
				( attribute "CDS_PART_NAME" "SCONN288_H44441003_PIP-SCONN,HA"
					( Origin gPackager )
				)
				( objectStatus "J6L1" )
				( pin "a0"
					( attribute "PN" "79"
						( Origin gPackager )
					)
					( objectStatus "J6L1.79" )
				)
				( pin "a1"
					( attribute "PN" "72"
						( Origin gPackager )
					)
					( objectStatus "J6L1.72" )
				)
				( pin "a2"
					( attribute "PN" "216"
						( Origin gPackager )
					)
					( objectStatus "J6L1.216" )
				)
				( pin "a3"
					( attribute "PN" "71"
						( Origin gPackager )
					)
					( objectStatus "J6L1.71" )
				)
				( pin "a4"
					( attribute "PN" "214"
						( Origin gPackager )
					)
					( objectStatus "J6L1.214" )
				)
				( pin "a5"
					( attribute "PN" "213"
						( Origin gPackager )
					)
					( objectStatus "J6L1.213" )
				)
				( pin "a6"
					( attribute "PN" "69"
						( Origin gPackager )
					)
					( objectStatus "J6L1.69" )
				)
				( pin "a7"
					( attribute "PN" "211"
						( Origin gPackager )
					)
					( objectStatus "J6L1.211" )
				)
				( pin "a8"
					( attribute "PN" "68"
						( Origin gPackager )
					)
					( objectStatus "J6L1.68" )
				)
				( pin "a9"
					( attribute "PN" "66"
						( Origin gPackager )
					)
					( objectStatus "J6L1.66" )
				)
				( pin "a10"
					( attribute "PN" "225"
						( Origin gPackager )
					)
					( objectStatus "J6L1.225" )
				)
				( pin "a11"
					( attribute "PN" "210"
						( Origin gPackager )
					)
					( objectStatus "J6L1.210" )
				)
				( pin "a12"
					( attribute "PN" "65"
						( Origin gPackager )
					)
					( objectStatus "J6L1.65" )
				)
				( pin "a13"
					( attribute "PN" "232"
						( Origin gPackager )
					)
					( objectStatus "J6L1.232" )
				)
				( pin "a14_we_n"
					( attribute "PN" "228"
						( Origin gPackager )
					)
					( objectStatus "J6L1.228" )
				)
				( pin "a15_cas_n"
					( attribute "PN" "86"
						( Origin gPackager )
					)
					( objectStatus "J6L1.86" )
				)
				( pin "a16_ras_n"
					( attribute "PN" "82"
						( Origin gPackager )
					)
					( objectStatus "J6L1.82" )
				)
				( pin "a17"
					( attribute "PN" "234"
						( Origin gPackager )
					)
					( objectStatus "J6L1.234" )
				)
				( pin "act_n"
					( attribute "PN" "62"
						( Origin gPackager )
					)
					( objectStatus "J6L1.62" )
				)
				( pin "alert_n"
					( attribute "PN" "208"
						( Origin gPackager )
					)
					( objectStatus "J6L1.208" )
				)
				( pin "ba(0)"
					( attribute "PN" "81"
						( Origin gPackager )
					)
					( objectStatus "J6L1.81" )
				)
				( pin "ba(1)"
					( attribute "PN" "224"
						( Origin gPackager )
					)
					( objectStatus "J6L1.224" )
				)
				( pin "bg(0)"
					( attribute "PN" "63"
						( Origin gPackager )
					)
					( objectStatus "J6L1.63" )
				)
				( pin "bg(1)"
					( attribute "PN" "207"
						( Origin gPackager )
					)
					( objectStatus "J6L1.207" )
				)
				( pin "c(2)"
					( attribute "PN" "235"
						( Origin gPackager )
					)
					( objectStatus "J6L1.235" )
				)
				( pin "cb(0)"
					( attribute "PN" "49"
						( Origin gPackager )
					)
					( objectStatus "J6L1.49" )
				)
				( pin "cb(1)"
					( attribute "PN" "194"
						( Origin gPackager )
					)
					( objectStatus "J6L1.194" )
				)
				( pin "cb(2)"
					( attribute "PN" "56"
						( Origin gPackager )
					)
					( objectStatus "J6L1.56" )
				)
				( pin "cb(3)"
					( attribute "PN" "201"
						( Origin gPackager )
					)
					( objectStatus "J6L1.201" )
				)
				( pin "cb(4)"
					( attribute "PN" "47"
						( Origin gPackager )
					)
					( objectStatus "J6L1.47" )
				)
				( pin "cb(5)"
					( attribute "PN" "192"
						( Origin gPackager )
					)
					( objectStatus "J6L1.192" )
				)
				( pin "cb(6)"
					( attribute "PN" "54"
						( Origin gPackager )
					)
					( objectStatus "J6L1.54" )
				)
				( pin "cb(7)"
					( attribute "PN" "199"
						( Origin gPackager )
					)
					( objectStatus "J6L1.199" )
				)
				( pin "ck0n"
					( attribute "PN" "75"
						( Origin gPackager )
					)
					( objectStatus "J6L1.75" )
				)
				( pin "ck0p"
					( attribute "PN" "74"
						( Origin gPackager )
					)
					( objectStatus "J6L1.74" )
				)
				( pin "ck1n"
					( attribute "PN" "219"
						( Origin gPackager )
					)
					( objectStatus "J6L1.219" )
				)
				( pin "ck1p"
					( attribute "PN" "218"
						( Origin gPackager )
					)
					( objectStatus "J6L1.218" )
				)
				( pin "cke(0)"
					( attribute "PN" "60"
						( Origin gPackager )
					)
					( objectStatus "J6L1.60" )
				)
				( pin "cke(1)"
					( attribute "PN" "203"
						( Origin gPackager )
					)
					( objectStatus "J6L1.203" )
				)
				( pin "dq(0)"
					( attribute "PN" "5"
						( Origin gPackager )
					)
					( objectStatus "J6L1.5" )
				)
				( pin "dq(1)"
					( attribute "PN" "150"
						( Origin gPackager )
					)
					( objectStatus "J6L1.150" )
				)
				( pin "dq(2)"
					( attribute "PN" "12"
						( Origin gPackager )
					)
					( objectStatus "J6L1.12" )
				)
				( pin "dq(3)"
					( attribute "PN" "157"
						( Origin gPackager )
					)
					( objectStatus "J6L1.157" )
				)
				( pin "dq(4)"
					( attribute "PN" "3"
						( Origin gPackager )
					)
					( objectStatus "J6L1.3" )
				)
				( pin "dq(5)"
					( attribute "PN" "148"
						( Origin gPackager )
					)
					( objectStatus "J6L1.148" )
				)
				( pin "dq(6)"
					( attribute "PN" "10"
						( Origin gPackager )
					)
					( objectStatus "J6L1.10" )
				)
				( pin "dq(7)"
					( attribute "PN" "155"
						( Origin gPackager )
					)
					( objectStatus "J6L1.155" )
				)
				( pin "dq(8)"
					( attribute "PN" "16"
						( Origin gPackager )
					)
					( objectStatus "J6L1.16" )
				)
				( pin "dq(9)"
					( attribute "PN" "161"
						( Origin gPackager )
					)
					( objectStatus "J6L1.161" )
				)
				( pin "dq(10)"
					( attribute "PN" "23"
						( Origin gPackager )
					)
					( objectStatus "J6L1.23" )
				)
				( pin "dq(11)"
					( attribute "PN" "168"
						( Origin gPackager )
					)
					( objectStatus "J6L1.168" )
				)
				( pin "dq(12)"
					( attribute "PN" "14"
						( Origin gPackager )
					)
					( objectStatus "J6L1.14" )
				)
				( pin "dq(13)"
					( attribute "PN" "159"
						( Origin gPackager )
					)
					( objectStatus "J6L1.159" )
				)
				( pin "dq(14)"
					( attribute "PN" "21"
						( Origin gPackager )
					)
					( objectStatus "J6L1.21" )
				)
				( pin "dq(15)"
					( attribute "PN" "166"
						( Origin gPackager )
					)
					( objectStatus "J6L1.166" )
				)
				( pin "dq(16)"
					( attribute "PN" "27"
						( Origin gPackager )
					)
					( objectStatus "J6L1.27" )
				)
				( pin "dq(17)"
					( attribute "PN" "172"
						( Origin gPackager )
					)
					( objectStatus "J6L1.172" )
				)
				( pin "dq(18)"
					( attribute "PN" "34"
						( Origin gPackager )
					)
					( objectStatus "J6L1.34" )
				)
				( pin "dq(19)"
					( attribute "PN" "179"
						( Origin gPackager )
					)
					( objectStatus "J6L1.179" )
				)
				( pin "dq(20)"
					( attribute "PN" "25"
						( Origin gPackager )
					)
					( objectStatus "J6L1.25" )
				)
				( pin "dq(21)"
					( attribute "PN" "170"
						( Origin gPackager )
					)
					( objectStatus "J6L1.170" )
				)
				( pin "dq(22)"
					( attribute "PN" "32"
						( Origin gPackager )
					)
					( objectStatus "J6L1.32" )
				)
				( pin "dq(23)"
					( attribute "PN" "177"
						( Origin gPackager )
					)
					( objectStatus "J6L1.177" )
				)
				( pin "dq(24)"
					( attribute "PN" "38"
						( Origin gPackager )
					)
					( objectStatus "J6L1.38" )
				)
				( pin "dq(25)"
					( attribute "PN" "183"
						( Origin gPackager )
					)
					( objectStatus "J6L1.183" )
				)
				( pin "dq(26)"
					( attribute "PN" "45"
						( Origin gPackager )
					)
					( objectStatus "J6L1.45" )
				)
				( pin "dq(27)"
					( attribute "PN" "190"
						( Origin gPackager )
					)
					( objectStatus "J6L1.190" )
				)
				( pin "dq(28)"
					( attribute "PN" "36"
						( Origin gPackager )
					)
					( objectStatus "J6L1.36" )
				)
				( pin "dq(29)"
					( attribute "PN" "181"
						( Origin gPackager )
					)
					( objectStatus "J6L1.181" )
				)
				( pin "dq(30)"
					( attribute "PN" "43"
						( Origin gPackager )
					)
					( objectStatus "J6L1.43" )
				)
				( pin "dq(31)"
					( attribute "PN" "188"
						( Origin gPackager )
					)
					( objectStatus "J6L1.188" )
				)
				( pin "dq(32)"
					( attribute "PN" "97"
						( Origin gPackager )
					)
					( objectStatus "J6L1.97" )
				)
				( pin "dq(33)"
					( attribute "PN" "242"
						( Origin gPackager )
					)
					( objectStatus "J6L1.242" )
				)
				( pin "dq(34)"
					( attribute "PN" "104"
						( Origin gPackager )
					)
					( objectStatus "J6L1.104" )
				)
				( pin "dq(35)"
					( attribute "PN" "249"
						( Origin gPackager )
					)
					( objectStatus "J6L1.249" )
				)
				( pin "dq(36)"
					( attribute "PN" "95"
						( Origin gPackager )
					)
					( objectStatus "J6L1.95" )
				)
				( pin "dq(37)"
					( attribute "PN" "240"
						( Origin gPackager )
					)
					( objectStatus "J6L1.240" )
				)
				( pin "dq(38)"
					( attribute "PN" "102"
						( Origin gPackager )
					)
					( objectStatus "J6L1.102" )
				)
				( pin "dq(39)"
					( attribute "PN" "247"
						( Origin gPackager )
					)
					( objectStatus "J6L1.247" )
				)
				( pin "dq(40)"
					( attribute "PN" "108"
						( Origin gPackager )
					)
					( objectStatus "J6L1.108" )
				)
				( pin "dq(41)"
					( attribute "PN" "253"
						( Origin gPackager )
					)
					( objectStatus "J6L1.253" )
				)
				( pin "dq(42)"
					( attribute "PN" "115"
						( Origin gPackager )
					)
					( objectStatus "J6L1.115" )
				)
				( pin "dq(43)"
					( attribute "PN" "260"
						( Origin gPackager )
					)
					( objectStatus "J6L1.260" )
				)
				( pin "dq(44)"
					( attribute "PN" "106"
						( Origin gPackager )
					)
					( objectStatus "J6L1.106" )
				)
				( pin "dq(45)"
					( attribute "PN" "251"
						( Origin gPackager )
					)
					( objectStatus "J6L1.251" )
				)
				( pin "dq(46)"
					( attribute "PN" "113"
						( Origin gPackager )
					)
					( objectStatus "J6L1.113" )
				)
				( pin "dq(47)"
					( attribute "PN" "258"
						( Origin gPackager )
					)
					( objectStatus "J6L1.258" )
				)
				( pin "dq(48)"
					( attribute "PN" "119"
						( Origin gPackager )
					)
					( objectStatus "J6L1.119" )
				)
				( pin "dq(49)"
					( attribute "PN" "264"
						( Origin gPackager )
					)
					( objectStatus "J6L1.264" )
				)
				( pin "dq(50)"
					( attribute "PN" "126"
						( Origin gPackager )
					)
					( objectStatus "J6L1.126" )
				)
				( pin "dq(51)"
					( attribute "PN" "271"
						( Origin gPackager )
					)
					( objectStatus "J6L1.271" )
				)
				( pin "dq(52)"
					( attribute "PN" "117"
						( Origin gPackager )
					)
					( objectStatus "J6L1.117" )
				)
				( pin "dq(53)"
					( attribute "PN" "262"
						( Origin gPackager )
					)
					( objectStatus "J6L1.262" )
				)
				( pin "dq(54)"
					( attribute "PN" "124"
						( Origin gPackager )
					)
					( objectStatus "J6L1.124" )
				)
				( pin "dq(55)"
					( attribute "PN" "269"
						( Origin gPackager )
					)
					( objectStatus "J6L1.269" )
				)
				( pin "dq(56)"
					( attribute "PN" "130"
						( Origin gPackager )
					)
					( objectStatus "J6L1.130" )
				)
				( pin "dq(57)"
					( attribute "PN" "275"
						( Origin gPackager )
					)
					( objectStatus "J6L1.275" )
				)
				( pin "dq(58)"
					( attribute "PN" "137"
						( Origin gPackager )
					)
					( objectStatus "J6L1.137" )
				)
				( pin "dq(59)"
					( attribute "PN" "282"
						( Origin gPackager )
					)
					( objectStatus "J6L1.282" )
				)
				( pin "dq(60)"
					( attribute "PN" "128"
						( Origin gPackager )
					)
					( objectStatus "J6L1.128" )
				)
				( pin "dq(61)"
					( attribute "PN" "273"
						( Origin gPackager )
					)
					( objectStatus "J6L1.273" )
				)
				( pin "dq(62)"
					( attribute "PN" "135"
						( Origin gPackager )
					)
					( objectStatus "J6L1.135" )
				)
				( pin "dq(63)"
					( attribute "PN" "280"
						( Origin gPackager )
					)
					( objectStatus "J6L1.280" )
				)
				( pin "event_n"
					( attribute "PN" "78"
						( Origin gPackager )
					)
					( objectStatus "J6L1.78" )
				)
				( pin "odt(0)"
					( attribute "PN" "87"
						( Origin gPackager )
					)
					( objectStatus "J6L1.87" )
				)
				( pin "odt(1)"
					( attribute "PN" "91"
						( Origin gPackager )
					)
					( objectStatus "J6L1.91" )
				)
				( pin "par"
					( attribute "PN" "222"
						( Origin gPackager )
					)
					( objectStatus "J6L1.222" )
				)
				( pin "reset_n"
					( attribute "PN" "58"
						( Origin gPackager )
					)
					( objectStatus "J6L1.58" )
				)
				( pin "rfu(0)"
					( attribute "PN" "205"
						( Origin gPackager )
					)
					( objectStatus "J6L1.205" )
				)
				( pin "rfu(1)"
					( attribute "PN" "227"
						( Origin gPackager )
					)
					( objectStatus "J6L1.227" )
				)
				( pin "rfu(2)"
					( attribute "PN" "144"
						( Origin gPackager )
					)
					( objectStatus "J6L1.144" )
				)
				( pin "s0_n"
					( attribute "PN" "84"
						( Origin gPackager )
					)
					( objectStatus "J6L1.84" )
				)
				( pin "s1_n"
					( attribute "PN" "89"
						( Origin gPackager )
					)
					( objectStatus "J6L1.89" )
				)
				( pin "s2_n_c(0)"
					( attribute "PN" "93"
						( Origin gPackager )
					)
					( objectStatus "J6L1.93" )
				)
				( pin "s3_n_c(1)"
					( attribute "PN" "237"
						( Origin gPackager )
					)
					( objectStatus "J6L1.237" )
				)
				( pin "sa(0)"
					( attribute "PN" "139"
						( Origin gPackager )
					)
					( objectStatus "J6L1.139" )
				)
				( pin "sa(1)"
					( attribute "PN" "140"
						( Origin gPackager )
					)
					( objectStatus "J6L1.140" )
				)
				( pin "sa(2)"
					( attribute "PN" "238"
						( Origin gPackager )
					)
					( objectStatus "J6L1.238" )
				)
				( pin "save_n_nc"
					( attribute "PN" "230"
						( Origin gPackager )
					)
					( objectStatus "J6L1.230" )
				)
				( pin "scl"
					( attribute "PN" "141"
						( Origin gPackager )
					)
					( objectStatus "J6L1.141" )
				)
				( pin "sda"
					( attribute "PN" "285"
						( Origin gPackager )
					)
					( objectStatus "J6L1.285" )
				)
				( pin "vddspd"
					( attribute "PN" "284"
						( Origin gPackager )
					)
					( objectStatus "J6L1.284" )
				)
				( pin "vrefca"
					( attribute "PN" "146"
						( Origin gPackager )
					)
					( objectStatus "J6L1.146" )
				)
			)
			( gate "@baseboard_fab2_lib.baseboard_fab2(sch_1):page54_i170"
				( attribute "BOM_COST" "MEM"
					( Origin gFrontEnd )
				)
				( attribute "CDS_LIB" "mstr_sconn"
					( Origin gPackager )
				)
				( attribute "CDS_LOCATION" "J6L1"
					( Origin gPackager )
				)
				( attribute "CDS_SEC" "4"
					( Origin gPackager )
				)
				( attribute "LOCATION" "J6L1"
					( Origin gFrontEnd )
				)
				( attribute "MATERIAL" "SCONN"
					( Origin gFrontEnd )
				)
				( attribute "PACK_TYPE" "PIP"
					( Origin gFrontEnd )
				)
				( attribute "PART_NUMBER" "H44441-003"
					( Origin gFrontEnd )
				)
				( attribute "PHYS_PAGE" "54"
					( Origin gFrontEnd )
				)
				( attribute "ROOM" "DDR4_CH_F1"
					( Origin gFrontEnd )
				)
				( attribute "ROT" "0"
					( Origin gFrontEnd )
				)
				( attribute "SEC" "4"
					( Origin gFrontEnd )
				)
				( attribute "SEC_TYPE" "PIP"
					( Origin gFrontEnd )
				)
				( attribute "VER" "4"
					( Origin gFrontEnd )
				)
				( attribute "XY" "(-50,1900)"
					( Origin gFrontEnd )
				)
				( attribute "CHIPS_PART_NAME" "SCONN288_H44441003"
					( Origin gPackager )
				)
				( attribute "CDS_PART_NAME" "SCONN288_H44441003_PIP-SCONN,HA"
					( Origin gPackager )
				)
				( objectStatus "J6L1" )
				( pin "\12v\(0)"
					( attribute "PN" "145"
						( Origin gPackager )
					)
					( objectStatus "J6L1.145" )
				)
				( pin "\12v\(1)"
					( attribute "PN" "1"
						( Origin gPackager )
					)
					( objectStatus "J6L1.1" )
				)
				( pin "vdd(0)"
					( attribute "PN" "236"
						( Origin gPackager )
					)
					( objectStatus "J6L1.236" )
				)
				( pin "vdd(1)"
					( attribute "PN" "233"
						( Origin gPackager )
					)
					( objectStatus "J6L1.233" )
				)
				( pin "vdd(2)"
					( attribute "PN" "231"
						( Origin gPackager )
					)
					( objectStatus "J6L1.231" )
				)
				( pin "vdd(3)"
					( attribute "PN" "229"
						( Origin gPackager )
					)
					( objectStatus "J6L1.229" )
				)
				( pin "vdd(4)"
					( attribute "PN" "226"
						( Origin gPackager )
					)
					( objectStatus "J6L1.226" )
				)
				( pin "vdd(5)"
					( attribute "PN" "223"
						( Origin gPackager )
					)
					( objectStatus "J6L1.223" )
				)
				( pin "vdd(6)"
					( attribute "PN" "220"
						( Origin gPackager )
					)
					( objectStatus "J6L1.220" )
				)
				( pin "vdd(7)"
					( attribute "PN" "217"
						( Origin gPackager )
					)
					( objectStatus "J6L1.217" )
				)
				( pin "vdd(8)"
					( attribute "PN" "215"
						( Origin gPackager )
					)
					( objectStatus "J6L1.215" )
				)
				( pin "vdd(9)"
					( attribute "PN" "212"
						( Origin gPackager )
					)
					( objectStatus "J6L1.212" )
				)
				( pin "vdd(10)"
					( attribute "PN" "209"
						( Origin gPackager )
					)
					( objectStatus "J6L1.209" )
				)
				( pin "vdd(11)"
					( attribute "PN" "206"
						( Origin gPackager )
					)
					( objectStatus "J6L1.206" )
				)
				( pin "vdd(12)"
					( attribute "PN" "204"
						( Origin gPackager )
					)
					( objectStatus "J6L1.204" )
				)
				( pin "vdd(13)"
					( attribute "PN" "92"
						( Origin gPackager )
					)
					( objectStatus "J6L1.92" )
				)
				( pin "vdd(14)"
					( attribute "PN" "90"
						( Origin gPackager )
					)
					( objectStatus "J6L1.90" )
				)
				( pin "vdd(15)"
					( attribute "PN" "88"
						( Origin gPackager )
					)
					( objectStatus "J6L1.88" )
				)
				( pin "vdd(16)"
					( attribute "PN" "85"
						( Origin gPackager )
					)
					( objectStatus "J6L1.85" )
				)
				( pin "vdd(17)"
					( attribute "PN" "83"
						( Origin gPackager )
					)
					( objectStatus "J6L1.83" )
				)
				( pin "vdd(18)"
					( attribute "PN" "80"
						( Origin gPackager )
					)
					( objectStatus "J6L1.80" )
				)
				( pin "vdd(19)"
					( attribute "PN" "76"
						( Origin gPackager )
					)
					( objectStatus "J6L1.76" )
				)
				( pin "vdd(20)"
					( attribute "PN" "73"
						( Origin gPackager )
					)
					( objectStatus "J6L1.73" )
				)
				( pin "vdd(21)"
					( attribute "PN" "70"
						( Origin gPackager )
					)
					( objectStatus "J6L1.70" )
				)
				( pin "vdd(22)"
					( attribute "PN" "67"
						( Origin gPackager )
					)
					( objectStatus "J6L1.67" )
				)
				( pin "vdd(23)"
					( attribute "PN" "64"
						( Origin gPackager )
					)
					( objectStatus "J6L1.64" )
				)
				( pin "vdd(24)"
					( attribute "PN" "61"
						( Origin gPackager )
					)
					( objectStatus "J6L1.61" )
				)
				( pin "vdd(25)"
					( attribute "PN" "59"
						( Origin gPackager )
					)
					( objectStatus "J6L1.59" )
				)
				( pin "vpp(0)"
					( attribute "PN" "287"
						( Origin gPackager )
					)
					( objectStatus "J6L1.287" )
				)
				( pin "vpp(1)"
					( attribute "PN" "286"
						( Origin gPackager )
					)
					( objectStatus "J6L1.286" )
				)
				( pin "vpp(2)"
					( attribute "PN" "288"
						( Origin gPackager )
					)
					( objectStatus "J6L1.288" )
				)
				( pin "vpp(3)"
					( attribute "PN" "143"
						( Origin gPackager )
					)
					( objectStatus "J6L1.143" )
				)
				( pin "vpp(4)"
					( attribute "PN" "142"
						( Origin gPackager )
					)
					( objectStatus "J6L1.142" )
				)
				( pin "vtt(0)"
					( attribute "PN" "221"
						( Origin gPackager )
					)
					( objectStatus "J6L1.221" )
				)
				( pin "vtt(1)"
					( attribute "PN" "77"
						( Origin gPackager )
					)
					( objectStatus "J6L1.77" )
				)
			)
			( gate "@baseboard_fab2_lib.baseboard_fab2(sch_1):page54_i179"
				( attribute "BOM_COST" "MEM"
					( Origin gFrontEnd )
				)
				( attribute "CDS_LIB" "dev_discrete"
					( Origin gPackager )
				)
				( attribute "CDS_LOCATION" "C4A5"
					( Origin gPackager )
				)
				( attribute "CDS_SEC" "1"
					( Origin gPackager )
				)
				( attribute "LOCATION" "C4A5"
					( Origin gFrontEnd )
				)
				( attribute "MATERIAL" "X7R"
					( Origin gFrontEnd )
				)
				( attribute "PACK_TYPE" "0402V"
					( Origin gFrontEnd )
				)
				( attribute "PART_NUMBER" "A36096-045"
					( Origin gFrontEnd )
				)
				( attribute "PHYS_PAGE" "54"
					( Origin gFrontEnd )
				)
				( attribute "ROOM" "DDR4_CH_F1"
					( Origin gFrontEnd )
				)
				( attribute "ROT" "2"
					( Origin gFrontEnd )
				)
				( attribute "SEC" "1"
					( Origin gPackager )
				)
				( attribute "TOLERANCE" "10%"
					( Origin gFrontEnd )
				)
				( attribute "VALUE" "0.01UF"
					( Origin gFrontEnd )
				)
				( attribute "VER" "1"
					( Origin gFrontEnd )
				)
				( attribute "VOLTAGE" "25V"
					( Units "uVoltage" "V" 1.000000)
					( Origin gFrontEnd )
				)
				( attribute "XY" "(-4600,1400)"
					( Origin gFrontEnd )
				)
				( attribute "CHIPS_PART_NAME" "CAP_A"
					( Origin gPackager )
				)
				( attribute "CDS_PART_NAME" "CAP_A_0402V-0.01UF,25V,10%,X7RA"
					( Origin gPackager )
				)
				( objectStatus "C4A5" )
				( pin "a"
					( attribute "PN" "1"
						( Origin gPackager )
					)
					( objectStatus "C4A5.1" )
				)
				( pin "b"
					( attribute "PN" "2"
						( Origin gPackager )
					)
					( objectStatus "C4A5.2" )
				)
			)
			( gate "@baseboard_fab2_lib.baseboard_fab2(sch_1):page55_i4"
				( attribute "BOM_COST" "PROC_SOCKET"
					( Origin gFrontEnd )
				)
				( attribute "CDS_LIB" "mstr_discrete"
					( Origin gPackager )
				)
				( attribute "CDS_LOCATION" "R9N1"
					( Origin gPackager )
				)
				( attribute "CDS_SEC" "1"
					( Origin gPackager )
				)
				( attribute "LOCATION" "R9N1"
					( Origin gFrontEnd )
				)
				( attribute "MATERIAL" "CHIP"
					( Origin gFrontEnd )
				)
				( attribute "PACK_TYPE" "0402"
					( Origin gFrontEnd )
				)
				( attribute "PART_NUMBER" "G21796-047"
					( Origin gFrontEnd )
				)
				( attribute "PHYS_PAGE" "55"
					( Origin gFrontEnd )
				)
				( attribute "ROOM" "CPU1"
					( Origin gFrontEnd )
				)
				( attribute "ROT" "0"
					( Origin gFrontEnd )
				)
				( attribute "SEC" "1"
					( Origin gFrontEnd )
				)
				( attribute "SEC_TYPE" "0402"
					( Origin gFrontEnd )
				)
				( attribute "TOLERANCE" "1%"
					( Origin gFrontEnd )
				)
				( attribute "VALUE" "49.9"
					( Origin gFrontEnd )
				)
				( attribute "VER" "2"
					( Origin gFrontEnd )
				)
				( attribute "WATTAGE" "1/16W"
					( Origin gFrontEnd )
				)
				( attribute "XY" "(13575,3925)"
					( Origin gFrontEnd )
				)
				( attribute "CHIPS_PART_NAME" "RES"
					( Origin gPackager )
				)
				( attribute "CDS_PART_NAME" "RES_0402-49.9,1%,1/16W,CHIP,G2A"
					( Origin gPackager )
				)
				( objectStatus "R9N1" )
				( pin "a"
					( attribute "PN" "1"
						( Origin gPackager )
					)
					( objectStatus "R9N1.1" )
				)
				( pin "b"
					( attribute "PN" "2"
						( Origin gPackager )
					)
					( objectStatus "R9N1.2" )
				)
			)
			( gate "@baseboard_fab2_lib.baseboard_fab2(sch_1):page55_i7"
				( attribute "BOM_COST" "PROC_SOCKET"
					( Origin gFrontEnd )
				)
				( attribute "CDS_LIB" "mstr_discrete"
					( Origin gPackager )
				)
				( attribute "CDS_LOCATION" "R9N2"
					( Origin gPackager )
				)
				( attribute "CDS_SEC" "1"
					( Origin gPackager )
				)
				( attribute "LOCATION" "R9N2"
					( Origin gFrontEnd )
				)
				( attribute "MATERIAL" "CHIP"
					( Origin gFrontEnd )
				)
				( attribute "PACK_TYPE" "0402"
					( Origin gFrontEnd )
				)
				( attribute "PART_NUMBER" "G21796-017"
					( Origin gFrontEnd )
				)
				( attribute "PHYS_PAGE" "55"
					( Origin gFrontEnd )
				)
				( attribute "ROOM" "CPU1"
					( Origin gFrontEnd )
				)
				( attribute "ROT" "0"
					( Origin gFrontEnd )
				)
				( attribute "SEC" "1"
					( Origin gFrontEnd )
				)
				( attribute "SEC_TYPE" "0402"
					( Origin gFrontEnd )
				)
				( attribute "TOLERANCE" "1%"
					( Origin gFrontEnd )
				)
				( attribute "VALUE" "100.0"
					( Origin gFrontEnd )
				)
				( attribute "VER" "2"
					( Origin gFrontEnd )
				)
				( attribute "WATTAGE" "1/16W"
					( Origin gFrontEnd )
				)
				( attribute "XY" "(13325,3925)"
					( Origin gFrontEnd )
				)
				( attribute "CHIPS_PART_NAME" "RES"
					( Origin gPackager )
				)
				( attribute "CDS_PART_NAME" "RES_0402-100.0,1%,1/16W,CHIP,GA"
					( Origin gPackager )
				)
				( objectStatus "R9N2" )
				( pin "a"
					( attribute "PN" "1"
						( Origin gPackager )
					)
					( objectStatus "R9N2.1" )
				)
				( pin "b"
					( attribute "PN" "2"
						( Origin gPackager )
					)
					( objectStatus "R9N2.2" )
				)
			)
			( gate "@baseboard_fab2_lib.baseboard_fab2(sch_1):page55_i19"
				( attribute "BOM_COST" "PROC_SOCKET"
					( Origin gFrontEnd )
				)
				( attribute "CDS_LIB" "mstr_discrete"
					( Origin gPackager )
				)
				( attribute "CDS_LOCATION" "R3B2"
					( Origin gPackager )
				)
				( attribute "CDS_SEC" "1"
					( Origin gPackager )
				)
				( attribute "LOCATION" "R3B2"
					( Origin gFrontEnd )
				)
				( attribute "MATERIAL" "CHIP"
					( Origin gFrontEnd )
				)
				( attribute "PACK_TYPE" "0402"
					( Origin gFrontEnd )
				)
				( attribute "PART_NUMBER" "G21796-047"
					( Origin gFrontEnd )
				)
				( attribute "PHYS_PAGE" "55"
					( Origin gFrontEnd )
				)
				( attribute "ROOM" "CPU1"
					( Origin gFrontEnd )
				)
				( attribute "ROT" "0"
					( Origin gFrontEnd )
				)
				( attribute "SEC" "1"
					( Origin gFrontEnd )
				)
				( attribute "SEC_TYPE" "0402"
					( Origin gFrontEnd )
				)
				( attribute "TOLERANCE" "1%"
					( Origin gFrontEnd )
				)
				( attribute "VALUE" "49.9"
					( Origin gFrontEnd )
				)
				( attribute "VER" "2"
					( Origin gFrontEnd )
				)
				( attribute "WATTAGE" "1/16W"
					( Origin gFrontEnd )
				)
				( attribute "XY" "(13500,3225)"
					( Origin gFrontEnd )
				)
				( attribute "CHIPS_PART_NAME" "RES"
					( Origin gPackager )
				)
				( attribute "CDS_PART_NAME" "RES_0402-49.9,1%,1/16W,CHIP,G2A"
					( Origin gPackager )
				)
				( objectStatus "R3B2" )
				( pin "a"
					( attribute "PN" "1"
						( Origin gPackager )
					)
					( objectStatus "R3B2.1" )
				)
				( pin "b"
					( attribute "PN" "2"
						( Origin gPackager )
					)
					( objectStatus "R3B2.2" )
				)
			)
			( gate "@baseboard_fab2_lib.baseboard_fab2(sch_1):page55_i21"
				( attribute "BOM_COST" "PROC_SOCKET"
					( Origin gFrontEnd )
				)
				( attribute "CDS_LIB" "mstr_discrete"
					( Origin gPackager )
				)
				( attribute "CDS_LOCATION" "R3B4"
					( Origin gPackager )
				)
				( attribute "CDS_SEC" "1"
					( Origin gPackager )
				)
				( attribute "LOCATION" "R3B4"
					( Origin gFrontEnd )
				)
				( attribute "MATERIAL" "CHIP"
					( Origin gFrontEnd )
				)
				( attribute "PACK_TYPE" "0402"
					( Origin gFrontEnd )
				)
				( attribute "PART_NUMBER" "G21796-017"
					( Origin gFrontEnd )
				)
				( attribute "PHYS_PAGE" "55"
					( Origin gFrontEnd )
				)
				( attribute "ROOM" "CPU1"
					( Origin gFrontEnd )
				)
				( attribute "ROT" "0"
					( Origin gFrontEnd )
				)
				( attribute "SEC" "1"
					( Origin gFrontEnd )
				)
				( attribute "SEC_TYPE" "0402"
					( Origin gFrontEnd )
				)
				( attribute "TOLERANCE" "1%"
					( Origin gFrontEnd )
				)
				( attribute "VALUE" "100.0"
					( Origin gFrontEnd )
				)
				( attribute "VER" "2"
					( Origin gFrontEnd )
				)
				( attribute "WATTAGE" "1/16W"
					( Origin gFrontEnd )
				)
				( attribute "XY" "(13300,3225)"
					( Origin gFrontEnd )
				)
				( attribute "CHIPS_PART_NAME" "RES"
					( Origin gPackager )
				)
				( attribute "CDS_PART_NAME" "RES_0402-100.0,1%,1/16W,CHIP,GA"
					( Origin gPackager )
				)
				( objectStatus "R3B4" )
				( pin "a"
					( attribute "PN" "1"
						( Origin gPackager )
					)
					( objectStatus "R3B4.1" )
				)
				( pin "b"
					( attribute "PN" "2"
						( Origin gPackager )
					)
					( objectStatus "R3B4.2" )
				)
			)
			( gate "@baseboard_fab2_lib.baseboard_fab2(sch_1):page55_i24"
				( attribute "BOM_COST" "PROC_SOCKET"
					( Origin gFrontEnd )
				)
				( attribute "CDS_LIB" "mstr_discrete"
					( Origin gPackager )
				)
				( attribute "CDS_LOCATION" "R1C2"
					( Origin gPackager )
				)
				( attribute "CDS_SEC" "1"
					( Origin gPackager )
				)
				( attribute "LOCATION" "R1C2"
					( Origin gFrontEnd )
				)
				( attribute "MATERIAL" "CHIP"
					( Origin gFrontEnd )
				)
				( attribute "PACK_TYPE" "0402"
					( Origin gFrontEnd )
				)
				( attribute "PART_NUMBER" "G21497-005"
					( Origin gFrontEnd )
				)
				( attribute "PHYS_PAGE" "55"
					( Origin gFrontEnd )
				)
				( attribute "ROOM" "CPU1"
					( Origin gFrontEnd )
				)
				( attribute "ROT" "0"
					( Origin gFrontEnd )
				)
				( attribute "SEC" "1"
					( Origin gPackager )
				)
				( attribute "TOLERANCE" "5%"
					( Origin gFrontEnd )
				)
				( attribute "VALUE" "0.0"
					( Origin gFrontEnd )
				)
				( attribute "VER" "1"
					( Origin gFrontEnd )
				)
				( attribute "WATTAGE" "1/16W"
					( Origin gFrontEnd )
				)
				( attribute "XY" "(12300,3650)"
					( Origin gFrontEnd )
				)
				( attribute "CHIPS_PART_NAME" "RES"
					( Origin gPackager )
				)
				( attribute "CDS_PART_NAME" "RES_0402-0.0,5%,1/16W,CHIP,G21A"
					( Origin gPackager )
				)
				( objectStatus "R1C2" )
				( pin "a"
					( attribute "PN" "1"
						( Origin gPackager )
					)
					( objectStatus "R1C2.1" )
				)
				( pin "b"
					( attribute "PN" "2"
						( Origin gPackager )
					)
					( objectStatus "R1C2.2" )
				)
			)
			( gate "@baseboard_fab2_lib.baseboard_fab2(sch_1):page55_i25"
				( attribute "BOM_COST" "PROC_SOCKET"
					( Origin gFrontEnd )
				)
				( attribute "CDS_LIB" "mstr_discrete"
					( Origin gPackager )
				)
				( attribute "CDS_LOCATION" "R1C3"
					( Origin gPackager )
				)
				( attribute "CDS_SEC" "1"
					( Origin gPackager )
				)
				( attribute "LOCATION" "R1C3"
					( Origin gFrontEnd )
				)
				( attribute "MATERIAL" "CHIP"
					( Origin gFrontEnd )
				)
				( attribute "PACK_TYPE" "0402"
					( Origin gFrontEnd )
				)
				( attribute "PART_NUMBER" "G21497-005"
					( Origin gFrontEnd )
				)
				( attribute "PHYS_PAGE" "55"
					( Origin gFrontEnd )
				)
				( attribute "ROOM" "CPU1"
					( Origin gFrontEnd )
				)
				( attribute "ROT" "0"
					( Origin gFrontEnd )
				)
				( attribute "SEC" "1"
					( Origin gPackager )
				)
				( attribute "TOLERANCE" "5%"
					( Origin gFrontEnd )
				)
				( attribute "VALUE" "0.0"
					( Origin gFrontEnd )
				)
				( attribute "VER" "1"
					( Origin gFrontEnd )
				)
				( attribute "WATTAGE" "1/16W"
					( Origin gFrontEnd )
				)
				( attribute "XY" "(12300,3600)"
					( Origin gFrontEnd )
				)
				( attribute "CHIPS_PART_NAME" "RES"
					( Origin gPackager )
				)
				( attribute "CDS_PART_NAME" "RES_0402-0.0,5%,1/16W,CHIP,G21A"
					( Origin gPackager )
				)
				( objectStatus "R1C3" )
				( pin "a"
					( attribute "PN" "1"
						( Origin gPackager )
					)
					( objectStatus "R1C3.1" )
				)
				( pin "b"
					( attribute "PN" "2"
						( Origin gPackager )
					)
					( objectStatus "R1C3.2" )
				)
			)
			( gate "@baseboard_fab2_lib.baseboard_fab2(sch_1):page55_i26"
				( attribute "BOM_COST" "PROC_SOCKET"
					( Origin gFrontEnd )
				)
				( attribute "CDS_LIB" "mstr_discrete"
					( Origin gPackager )
				)
				( attribute "CDS_LOCATION" "R1C1"
					( Origin gPackager )
				)
				( attribute "CDS_SEC" "1"
					( Origin gPackager )
				)
				( attribute "LOCATION" "R1C1"
					( Origin gFrontEnd )
				)
				( attribute "MATERIAL" "CHIP"
					( Origin gFrontEnd )
				)
				( attribute "PACK_TYPE" "0402"
					( Origin gFrontEnd )
				)
				( attribute "PART_NUMBER" "G21796-271"
					( Origin gFrontEnd )
				)
				( attribute "PHYS_PAGE" "55"
					( Origin gFrontEnd )
				)
				( attribute "ROOM" "CPU1"
					( Origin gFrontEnd )
				)
				( attribute "ROT" "0"
					( Origin gFrontEnd )
				)
				( attribute "SEC" "1"
					( Origin gPackager )
				)
				( attribute "TOLERANCE" "1.0%"
					( Origin gFrontEnd )
				)
				( attribute "VALUE" "221"
					( Origin gFrontEnd )
				)
				( attribute "VER" "1"
					( Origin gFrontEnd )
				)
				( attribute "WATTAGE" "1/16W"
					( Origin gFrontEnd )
				)
				( attribute "XY" "(12300,3550)"
					( Origin gFrontEnd )
				)
				( attribute "CHIPS_PART_NAME" "RES"
					( Origin gPackager )
				)
				( attribute "CDS_PART_NAME" "RES_0402-221,1.0%,1/16W,CHIP,GA"
					( Origin gPackager )
				)
				( objectStatus "R1C1" )
				( pin "a"
					( attribute "PN" "1"
						( Origin gPackager )
					)
					( objectStatus "R1C1.1" )
				)
				( pin "b"
					( attribute "PN" "2"
						( Origin gPackager )
					)
					( objectStatus "R1C1.2" )
				)
			)
			( gate "@baseboard_fab2_lib.baseboard_fab2(sch_1):page55_i27"
				( attribute "BOM_COST" "PROC_SOCKET"
					( Origin gFrontEnd )
				)
				( attribute "CDS_LIB" "mstr_discrete"
					( Origin gPackager )
				)
				( attribute "CDS_LOCATION" "R3B1"
					( Origin gPackager )
				)
				( attribute "CDS_SEC" "1"
					( Origin gPackager )
				)
				( attribute "LOCATION" "R3B1"
					( Origin gFrontEnd )
				)
				( attribute "MATERIAL" "CHIP"
					( Origin gFrontEnd )
				)
				( attribute "PACK_TYPE" "0402"
					( Origin gFrontEnd )
				)
				( attribute "PART_NUMBER" "G21796-271"
					( Origin gFrontEnd )
				)
				( attribute "PHYS_PAGE" "55"
					( Origin gFrontEnd )
				)
				( attribute "ROOM" "CPU1"
					( Origin gFrontEnd )
				)
				( attribute "ROT" "0"
					( Origin gFrontEnd )
				)
				( attribute "SEC" "1"
					( Origin gPackager )
				)
				( attribute "TOLERANCE" "1.0%"
					( Origin gFrontEnd )
				)
				( attribute "VALUE" "221"
					( Origin gFrontEnd )
				)
				( attribute "VER" "1"
					( Origin gFrontEnd )
				)
				( attribute "WATTAGE" "1/16W"
					( Origin gFrontEnd )
				)
				( attribute "XY" "(12300,3400)"
					( Origin gFrontEnd )
				)
				( attribute "CHIPS_PART_NAME" "RES"
					( Origin gPackager )
				)
				( attribute "CDS_PART_NAME" "RES_0402-221,1.0%,1/16W,CHIP,GA"
					( Origin gPackager )
				)
				( objectStatus "R3B1" )
				( pin "a"
					( attribute "PN" "1"
						( Origin gPackager )
					)
					( objectStatus "R3B1.1" )
				)
				( pin "b"
					( attribute "PN" "2"
						( Origin gPackager )
					)
					( objectStatus "R3B1.2" )
				)
			)
			( gate "@baseboard_fab2_lib.baseboard_fab2(sch_1):page55_i28"
				( attribute "BOM_COST" "PROC_SOCKET"
					( Origin gFrontEnd )
				)
				( attribute "CDS_LIB" "mstr_discrete"
					( Origin gPackager )
				)
				( attribute "CDS_LOCATION" "R3B5"
					( Origin gPackager )
				)
				( attribute "CDS_SEC" "1"
					( Origin gPackager )
				)
				( attribute "LOCATION" "R3B5"
					( Origin gFrontEnd )
				)
				( attribute "MATERIAL" "CHIP"
					( Origin gFrontEnd )
				)
				( attribute "PACK_TYPE" "0402"
					( Origin gFrontEnd )
				)
				( attribute "PART_NUMBER" "G21497-005"
					( Origin gFrontEnd )
				)
				( attribute "PHYS_PAGE" "55"
					( Origin gFrontEnd )
				)
				( attribute "ROOM" "CPU1"
					( Origin gFrontEnd )
				)
				( attribute "ROT" "0"
					( Origin gFrontEnd )
				)
				( attribute "SEC" "1"
					( Origin gPackager )
				)
				( attribute "TOLERANCE" "5%"
					( Origin gFrontEnd )
				)
				( attribute "VALUE" "0.0"
					( Origin gFrontEnd )
				)
				( attribute "VER" "1"
					( Origin gFrontEnd )
				)
				( attribute "WATTAGE" "1/16W"
					( Origin gFrontEnd )
				)
				( attribute "XY" "(12300,3450)"
					( Origin gFrontEnd )
				)
				( attribute "CHIPS_PART_NAME" "RES"
					( Origin gPackager )
				)
				( attribute "CDS_PART_NAME" "RES_0402-0.0,5%,1/16W,CHIP,G21A"
					( Origin gPackager )
				)
				( objectStatus "R3B5" )
				( pin "a"
					( attribute "PN" "1"
						( Origin gPackager )
					)
					( objectStatus "R3B5.1" )
				)
				( pin "b"
					( attribute "PN" "2"
						( Origin gPackager )
					)
					( objectStatus "R3B5.2" )
				)
			)
			( gate "@baseboard_fab2_lib.baseboard_fab2(sch_1):page55_i29"
				( attribute "BOM_COST" "PROC_SOCKET"
					( Origin gFrontEnd )
				)
				( attribute "CDS_LIB" "mstr_discrete"
					( Origin gPackager )
				)
				( attribute "CDS_LOCATION" "R3B3"
					( Origin gPackager )
				)
				( attribute "CDS_SEC" "1"
					( Origin gPackager )
				)
				( attribute "LOCATION" "R3B3"
					( Origin gFrontEnd )
				)
				( attribute "MATERIAL" "CHIP"
					( Origin gFrontEnd )
				)
				( attribute "PACK_TYPE" "0402"
					( Origin gFrontEnd )
				)
				( attribute "PART_NUMBER" "G21497-005"
					( Origin gFrontEnd )
				)
				( attribute "PHYS_PAGE" "55"
					( Origin gFrontEnd )
				)
				( attribute "ROOM" "CPU1"
					( Origin gFrontEnd )
				)
				( attribute "ROT" "0"
					( Origin gFrontEnd )
				)
				( attribute "SEC" "1"
					( Origin gPackager )
				)
				( attribute "TOLERANCE" "5%"
					( Origin gFrontEnd )
				)
				( attribute "VALUE" "0.0"
					( Origin gFrontEnd )
				)
				( attribute "VER" "1"
					( Origin gFrontEnd )
				)
				( attribute "WATTAGE" "1/16W"
					( Origin gFrontEnd )
				)
				( attribute "XY" "(12300,3500)"
					( Origin gFrontEnd )
				)
				( attribute "CHIPS_PART_NAME" "RES"
					( Origin gPackager )
				)
				( attribute "CDS_PART_NAME" "RES_0402-0.0,5%,1/16W,CHIP,G21A"
					( Origin gPackager )
				)
				( objectStatus "R3B3" )
				( pin "a"
					( attribute "PN" "1"
						( Origin gPackager )
					)
					( objectStatus "R3B3.1" )
				)
				( pin "b"
					( attribute "PN" "2"
						( Origin gPackager )
					)
					( objectStatus "R3B3.2" )
				)
			)
			( gate "@baseboard_fab2_lib.baseboard_fab2(sch_1):page55_i115"
				( attribute "BOM_COST" "PROC_SOCKET"
					( Origin gFrontEnd )
				)
				( attribute "CDS_LIB" "mstr_discrete"
					( Origin gPackager )
				)
				( attribute "CDS_LOCATION" "R7P19"
					( Origin gPackager )
				)
				( attribute "CDS_SEC" "1"
					( Origin gPackager )
				)
				( attribute "LOCATION" "R7P19"
					( Origin gFrontEnd )
				)
				( attribute "MATERIAL" "CHIP"
					( Origin gFrontEnd )
				)
				( attribute "PACK_TYPE" "0402"
					( Origin gFrontEnd )
				)
				( attribute "PART_NUMBER" "G21796-017"
					( Origin gFrontEnd )
				)
				( attribute "PHYS_PAGE" "55"
					( Origin gFrontEnd )
				)
				( attribute "ROOM" "CPU1"
					( Origin gFrontEnd )
				)
				( attribute "ROT" "2"
					( Origin gFrontEnd )
				)
				( attribute "SEC" "1"
					( Origin gFrontEnd )
				)
				( attribute "SEC_TYPE" "0402"
					( Origin gFrontEnd )
				)
				( attribute "TOLERANCE" "1%"
					( Origin gFrontEnd )
				)
				( attribute "VALUE" "100.0"
					( Origin gFrontEnd )
				)
				( attribute "VER" "2"
					( Origin gFrontEnd )
				)
				( attribute "WATTAGE" "1/16W"
					( Origin gFrontEnd )
				)
				( attribute "XY" "(6575,2650)"
					( Origin gFrontEnd )
				)
				( attribute "CHIPS_PART_NAME" "RES"
					( Origin gPackager )
				)
				( attribute "CDS_PART_NAME" "RES_0402-100.0,1%,1/16W,CHIP,GA"
					( Origin gPackager )
				)
				( objectStatus "R7P19" )
				( pin "a"
					( attribute "PN" "1"
						( Origin gPackager )
					)
					( objectStatus "R7P19.1" )
				)
				( pin "b"
					( attribute "PN" "2"
						( Origin gPackager )
					)
					( objectStatus "R7P19.2" )
				)
			)
			( gate "@baseboard_fab2_lib.baseboard_fab2(sch_1):page55_i116"
				( attribute "BOM_COST" "PROC_SOCKET"
					( Origin gFrontEnd )
				)
				( attribute "CDS_LIB" "mstr_discrete"
					( Origin gPackager )
				)
				( attribute "CDS_LOCATION" "R3D1"
					( Origin gPackager )
				)
				( attribute "CDS_SEC" "1"
					( Origin gPackager )
				)
				( attribute "LOCATION" "R3D1"
					( Origin gFrontEnd )
				)
				( attribute "MATERIAL" "CHIP"
					( Origin gFrontEnd )
				)
				( attribute "PACK_TYPE" "0402"
					( Origin gFrontEnd )
				)
				( attribute "PART_NUMBER" "G21796-365"
					( Origin gFrontEnd )
				)
				( attribute "PHYS_PAGE" "55"
					( Origin gFrontEnd )
				)
				( attribute "ROOM" "CPU1"
					( Origin gFrontEnd )
				)
				( attribute "ROT" "2"
					( Origin gFrontEnd )
				)
				( attribute "SEC" "1"
					( Origin gFrontEnd )
				)
				( attribute "SEC_TYPE" "0402"
					( Origin gFrontEnd )
				)
				( attribute "TOLERANCE" "1%"
					( Origin gFrontEnd )
				)
				( attribute "VALUE" "90.9"
					( Origin gFrontEnd )
				)
				( attribute "VER" "2"
					( Origin gFrontEnd )
				)
				( attribute "WATTAGE" "1/16W"
					( Origin gFrontEnd )
				)
				( attribute "XY" "(7700,2525)"
					( Origin gFrontEnd )
				)
				( attribute "CHIPS_PART_NAME" "RES"
					( Origin gPackager )
				)
				( attribute "CDS_PART_NAME" "RES_0402-90.9,1%,1/16W,CHIP,G2A"
					( Origin gPackager )
				)
				( objectStatus "R3D1" )
				( pin "a"
					( attribute "PN" "1"
						( Origin gPackager )
					)
					( objectStatus "R3D1.1" )
				)
				( pin "b"
					( attribute "PN" "2"
						( Origin gPackager )
					)
					( objectStatus "R3D1.2" )
				)
			)
			( gate "@baseboard_fab2_lib.baseboard_fab2(sch_1):page55_i117"
				( attribute "BOM_COST" "PROC_SOCKET"
					( Origin gFrontEnd )
				)
				( attribute "CDS_LIB" "mstr_discrete"
					( Origin gPackager )
				)
				( attribute "CDS_LOCATION" "R3D2"
					( Origin gPackager )
				)
				( attribute "CDS_SEC" "1"
					( Origin gPackager )
				)
				( attribute "LOCATION" "R3D2"
					( Origin gFrontEnd )
				)
				( attribute "MATERIAL" "CHIP"
					( Origin gFrontEnd )
				)
				( attribute "PACK_TYPE" "0402"
					( Origin gFrontEnd )
				)
				( attribute "PART_NUMBER" "G21796-365"
					( Origin gFrontEnd )
				)
				( attribute "PHYS_PAGE" "55"
					( Origin gFrontEnd )
				)
				( attribute "ROOM" "CPU1"
					( Origin gFrontEnd )
				)
				( attribute "ROT" "2"
					( Origin gFrontEnd )
				)
				( attribute "SEC" "1"
					( Origin gFrontEnd )
				)
				( attribute "SEC_TYPE" "0402"
					( Origin gFrontEnd )
				)
				( attribute "TOLERANCE" "1%"
					( Origin gFrontEnd )
				)
				( attribute "VALUE" "90.9"
					( Origin gFrontEnd )
				)
				( attribute "VER" "2"
					( Origin gFrontEnd )
				)
				( attribute "WATTAGE" "1/16W"
					( Origin gFrontEnd )
				)
				( attribute "XY" "(7475,2575)"
					( Origin gFrontEnd )
				)
				( attribute "CHIPS_PART_NAME" "RES"
					( Origin gPackager )
				)
				( attribute "CDS_PART_NAME" "RES_0402-90.9,1%,1/16W,CHIP,G2A"
					( Origin gPackager )
				)
				( objectStatus "R3D2" )
				( pin "a"
					( attribute "PN" "1"
						( Origin gPackager )
					)
					( objectStatus "R3D2.1" )
				)
				( pin "b"
					( attribute "PN" "2"
						( Origin gPackager )
					)
					( objectStatus "R3D2.2" )
				)
			)
			( gate "@baseboard_fab2_lib.baseboard_fab2(sch_1):page55_i118"
				( attribute "BOM_COST" "PROC_SOCKET"
					( Origin gFrontEnd )
				)
				( attribute "CDS_LIB" "mstr_discrete"
					( Origin gPackager )
				)
				( attribute "CDS_LOCATION" "R3D3"
					( Origin gPackager )
				)
				( attribute "CDS_SEC" "1"
					( Origin gPackager )
				)
				( attribute "LOCATION" "R3D3"
					( Origin gFrontEnd )
				)
				( attribute "MATERIAL" "CHIP"
					( Origin gFrontEnd )
				)
				( attribute "PACK_TYPE" "0402"
					( Origin gFrontEnd )
				)
				( attribute "PART_NUMBER" "G21796-017"
					( Origin gFrontEnd )
				)
				( attribute "PHYS_PAGE" "55"
					( Origin gFrontEnd )
				)
				( attribute "ROOM" "CPU1"
					( Origin gFrontEnd )
				)
				( attribute "ROT" "2"
					( Origin gFrontEnd )
				)
				( attribute "SEC" "1"
					( Origin gFrontEnd )
				)
				( attribute "SEC_TYPE" "0402"
					( Origin gFrontEnd )
				)
				( attribute "TOLERANCE" "1%"
					( Origin gFrontEnd )
				)
				( attribute "VALUE" "100.0"
					( Origin gFrontEnd )
				)
				( attribute "VER" "2"
					( Origin gFrontEnd )
				)
				( attribute "WATTAGE" "1/16W"
					( Origin gFrontEnd )
				)
				( attribute "XY" "(7250,2575)"
					( Origin gFrontEnd )
				)
				( attribute "CHIPS_PART_NAME" "RES"
					( Origin gPackager )
				)
				( attribute "CDS_PART_NAME" "RES_0402-100.0,1%,1/16W,CHIP,GA"
					( Origin gPackager )
				)
				( objectStatus "R3D3" )
				( pin "a"
					( attribute "PN" "1"
						( Origin gPackager )
					)
					( objectStatus "R3D3.1" )
				)
				( pin "b"
					( attribute "PN" "2"
						( Origin gPackager )
					)
					( objectStatus "R3D3.2" )
				)
			)
			( gate "@baseboard_fab2_lib.baseboard_fab2(sch_1):page55_i119"
				( attribute "BOM_COST" "PROC_SOCKET"
					( Origin gFrontEnd )
				)
				( attribute "CDS_LIB" "mstr_discrete"
					( Origin gPackager )
				)
				( attribute "CDS_LOCATION" "R7P16"
					( Origin gPackager )
				)
				( attribute "CDS_SEC" "1"
					( Origin gPackager )
				)
				( attribute "LOCATION" "R7P16"
					( Origin gFrontEnd )
				)
				( attribute "MATERIAL" "CHIP"
					( Origin gFrontEnd )
				)
				( attribute "PACK_TYPE" "0402"
					( Origin gFrontEnd )
				)
				( attribute "PART_NUMBER" "G21796-365"
					( Origin gFrontEnd )
				)
				( attribute "PHYS_PAGE" "55"
					( Origin gFrontEnd )
				)
				( attribute "ROOM" "CPU1"
					( Origin gFrontEnd )
				)
				( attribute "ROT" "2"
					( Origin gFrontEnd )
				)
				( attribute "SEC" "1"
					( Origin gFrontEnd )
				)
				( attribute "SEC_TYPE" "0402"
					( Origin gFrontEnd )
				)
				( attribute "TOLERANCE" "1%"
					( Origin gFrontEnd )
				)
				( attribute "VALUE" "90.9"
					( Origin gFrontEnd )
				)
				( attribute "VER" "2"
					( Origin gFrontEnd )
				)
				( attribute "WATTAGE" "1/16W"
					( Origin gFrontEnd )
				)
				( attribute "XY" "(7025,2575)"
					( Origin gFrontEnd )
				)
				( attribute "CHIPS_PART_NAME" "RES"
					( Origin gPackager )
				)
				( attribute "CDS_PART_NAME" "RES_0402-90.9,1%,1/16W,CHIP,G2A"
					( Origin gPackager )
				)
				( objectStatus "R7P16" )
				( pin "a"
					( attribute "PN" "1"
						( Origin gPackager )
					)
					( objectStatus "R7P16.1" )
				)
				( pin "b"
					( attribute "PN" "2"
						( Origin gPackager )
					)
					( objectStatus "R7P16.2" )
				)
			)
			( gate "@baseboard_fab2_lib.baseboard_fab2(sch_1):page55_i123"
				( attribute "BOM_COST" "PROC_SOCKET"
					( Origin gFrontEnd )
				)
				( attribute "CDS_LIB" "mstr_discrete"
					( Origin gPackager )
				)
				( attribute "CDS_LOCATION" "R7P8"
					( Origin gPackager )
				)
				( attribute "CDS_SEC" "1"
					( Origin gPackager )
				)
				( attribute "LOCATION" "R7P8"
					( Origin gFrontEnd )
				)
				( attribute "MATERIAL" "CHIP"
					( Origin gFrontEnd )
				)
				( attribute "PACK_TYPE" "0402"
					( Origin gFrontEnd )
				)
				( attribute "PART_NUMBER" "G21796-047"
					( Origin gFrontEnd )
				)
				( attribute "PHYS_PAGE" "55"
					( Origin gFrontEnd )
				)
				( attribute "ROOM" "CPU1"
					( Origin gFrontEnd )
				)
				( attribute "ROT" "2"
					( Origin gFrontEnd )
				)
				( attribute "SEC" "1"
					( Origin gFrontEnd )
				)
				( attribute "SEC_TYPE" "0402"
					( Origin gFrontEnd )
				)
				( attribute "TOLERANCE" "1%"
					( Origin gFrontEnd )
				)
				( attribute "VALUE" "49.9"
					( Origin gFrontEnd )
				)
				( attribute "VER" "2"
					( Origin gFrontEnd )
				)
				( attribute "WATTAGE" "1/16W"
					( Origin gFrontEnd )
				)
				( attribute "XY" "(6575,1425)"
					( Origin gFrontEnd )
				)
				( attribute "CHIPS_PART_NAME" "RES"
					( Origin gPackager )
				)
				( attribute "CDS_PART_NAME" "RES_0402-49.9,1%,1/16W,CHIP,G2A"
					( Origin gPackager )
				)
				( objectStatus "R7P8" )
				( pin "a"
					( attribute "PN" "1"
						( Origin gPackager )
					)
					( objectStatus "R7P8.1" )
				)
				( pin "b"
					( attribute "PN" "2"
						( Origin gPackager )
					)
					( objectStatus "R7P8.2" )
				)
			)
			( gate "@baseboard_fab2_lib.baseboard_fab2(sch_1):page55_i124"
				( attribute "BOM_COST" "PROC_SOCKET"
					( Origin gFrontEnd )
				)
				( attribute "CDS_LIB" "mstr_discrete"
					( Origin gPackager )
				)
				( attribute "CDS_LOCATION" "R7P10"
					( Origin gPackager )
				)
				( attribute "CDS_SEC" "1"
					( Origin gPackager )
				)
				( attribute "LOCATION" "R7P10"
					( Origin gFrontEnd )
				)
				( attribute "MATERIAL" "CHIP"
					( Origin gFrontEnd )
				)
				( attribute "PACK_TYPE" "0402"
					( Origin gFrontEnd )
				)
				( attribute "PART_NUMBER" "G21796-047"
					( Origin gFrontEnd )
				)
				( attribute "PHYS_PAGE" "55"
					( Origin gFrontEnd )
				)
				( attribute "ROOM" "CPU1"
					( Origin gFrontEnd )
				)
				( attribute "ROT" "2"
					( Origin gFrontEnd )
				)
				( attribute "SEC" "1"
					( Origin gFrontEnd )
				)
				( attribute "SEC_TYPE" "0402"
					( Origin gFrontEnd )
				)
				( attribute "TOLERANCE" "1%"
					( Origin gFrontEnd )
				)
				( attribute "VALUE" "49.9"
					( Origin gFrontEnd )
				)
				( attribute "VER" "2"
					( Origin gFrontEnd )
				)
				( attribute "WATTAGE" "1/16W"
					( Origin gFrontEnd )
				)
				( attribute "XY" "(6775,1425)"
					( Origin gFrontEnd )
				)
				( attribute "CHIPS_PART_NAME" "RES"
					( Origin gPackager )
				)
				( attribute "CDS_PART_NAME" "RES_0402-49.9,1%,1/16W,CHIP,G2A"
					( Origin gPackager )
				)
				( objectStatus "R7P10" )
				( pin "a"
					( attribute "PN" "1"
						( Origin gPackager )
					)
					( objectStatus "R7P10.1" )
				)
				( pin "b"
					( attribute "PN" "2"
						( Origin gPackager )
					)
					( objectStatus "R7P10.2" )
				)
			)
			( gate "@baseboard_fab2_lib.baseboard_fab2(sch_1):page55_i125"
				( attribute "BOM_COST" "PROC_SOCKET"
					( Origin gFrontEnd )
				)
				( attribute "CDS_LIB" "mstr_discrete"
					( Origin gPackager )
				)
				( attribute "CDS_LOCATION" "R3D19"
					( Origin gPackager )
				)
				( attribute "CDS_SEC" "1"
					( Origin gPackager )
				)
				( attribute "LOCATION" "R3D19"
					( Origin gFrontEnd )
				)
				( attribute "MATERIAL" "CHIP"
					( Origin gFrontEnd )
				)
				( attribute "PACK_TYPE" "0402"
					( Origin gFrontEnd )
				)
				( attribute "PART_NUMBER" "G21796-047"
					( Origin gFrontEnd )
				)
				( attribute "PHYS_PAGE" "55"
					( Origin gFrontEnd )
				)
				( attribute "ROOM" "CPU1"
					( Origin gFrontEnd )
				)
				( attribute "ROT" "2"
					( Origin gFrontEnd )
				)
				( attribute "SEC" "1"
					( Origin gFrontEnd )
				)
				( attribute "SEC_TYPE" "0402"
					( Origin gFrontEnd )
				)
				( attribute "TOLERANCE" "1%"
					( Origin gFrontEnd )
				)
				( attribute "VALUE" "49.9"
					( Origin gFrontEnd )
				)
				( attribute "VER" "2"
					( Origin gFrontEnd )
				)
				( attribute "WATTAGE" "1/16W"
					( Origin gFrontEnd )
				)
				( attribute "XY" "(7000,1425)"
					( Origin gFrontEnd )
				)
				( attribute "CHIPS_PART_NAME" "RES"
					( Origin gPackager )
				)
				( attribute "CDS_PART_NAME" "RES_0402-49.9,1%,1/16W,CHIP,G2A"
					( Origin gPackager )
				)
				( objectStatus "R3D19" )
				( pin "a"
					( attribute "PN" "1"
						( Origin gPackager )
					)
					( objectStatus "R3D19.1" )
				)
				( pin "b"
					( attribute "PN" "2"
						( Origin gPackager )
					)
					( objectStatus "R3D19.2" )
				)
			)
			( gate "@baseboard_fab2_lib.baseboard_fab2(sch_1):page55_i126"
				( attribute "BOM_COST" "PROC_SOCKET"
					( Origin gFrontEnd )
				)
				( attribute "CDS_LIB" "mstr_discrete"
					( Origin gPackager )
				)
				( attribute "CDS_LOCATION" "R7P11"
					( Origin gPackager )
				)
				( attribute "CDS_SEC" "1"
					( Origin gPackager )
				)
				( attribute "LOCATION" "R7P11"
					( Origin gFrontEnd )
				)
				( attribute "MATERIAL" "CHIP"
					( Origin gFrontEnd )
				)
				( attribute "PACK_TYPE" "0402"
					( Origin gFrontEnd )
				)
				( attribute "PART_NUMBER" "G21796-047"
					( Origin gFrontEnd )
				)
				( attribute "PHYS_PAGE" "55"
					( Origin gFrontEnd )
				)
				( attribute "ROOM" "CPU1"
					( Origin gFrontEnd )
				)
				( attribute "ROT" "2"
					( Origin gFrontEnd )
				)
				( attribute "SEC" "1"
					( Origin gFrontEnd )
				)
				( attribute "SEC_TYPE" "0402"
					( Origin gFrontEnd )
				)
				( attribute "TOLERANCE" "1%"
					( Origin gFrontEnd )
				)
				( attribute "VALUE" "49.9"
					( Origin gFrontEnd )
				)
				( attribute "VER" "2"
					( Origin gFrontEnd )
				)
				( attribute "WATTAGE" "1/16W"
					( Origin gFrontEnd )
				)
				( attribute "XY" "(7200,1425)"
					( Origin gFrontEnd )
				)
				( attribute "CHIPS_PART_NAME" "RES"
					( Origin gPackager )
				)
				( attribute "CDS_PART_NAME" "RES_0402-49.9,1%,1/16W,CHIP,G2A"
					( Origin gPackager )
				)
				( objectStatus "R7P11" )
				( pin "a"
					( attribute "PN" "1"
						( Origin gPackager )
					)
					( objectStatus "R7P11.1" )
				)
				( pin "b"
					( attribute "PN" "2"
						( Origin gPackager )
					)
					( objectStatus "R7P11.2" )
				)
			)
			( gate "@baseboard_fab2_lib.baseboard_fab2(sch_1):page55_i140"
				( attribute "BOM_COST" "PROC_SOCKET"
					( Origin gFrontEnd )
				)
				( attribute "CDS_LIB" "mstr_discrete"
					( Origin gPackager )
				)
				( attribute "CDS_LOCATION" "R7P17"
					( Origin gPackager )
				)
				( attribute "CDS_SEC" "1"
					( Origin gPackager )
				)
				( attribute "LOCATION" "R7P17"
					( Origin gFrontEnd )
				)
				( attribute "MATERIAL" "CHIP"
					( Origin gFrontEnd )
				)
				( attribute "PACK_TYPE" "0402"
					( Origin gFrontEnd )
				)
				( attribute "PART_NUMBER" "G21796-365"
					( Origin gFrontEnd )
				)
				( attribute "PHYS_PAGE" "55"
					( Origin gFrontEnd )
				)
				( attribute "ROOM" "CPU1"
					( Origin gFrontEnd )
				)
				( attribute "ROT" "2"
					( Origin gFrontEnd )
				)
				( attribute "SEC" "1"
					( Origin gFrontEnd )
				)
				( attribute "SEC_TYPE" "0402"
					( Origin gFrontEnd )
				)
				( attribute "TOLERANCE" "1%"
					( Origin gFrontEnd )
				)
				( attribute "VALUE" "90.9"
					( Origin gFrontEnd )
				)
				( attribute "VER" "2"
					( Origin gFrontEnd )
				)
				( attribute "WATTAGE" "1/16W"
					( Origin gFrontEnd )
				)
				( attribute "XY" "(6800,2650)"
					( Origin gFrontEnd )
				)
				( attribute "CHIPS_PART_NAME" "RES"
					( Origin gPackager )
				)
				( attribute "CDS_PART_NAME" "RES_0402-90.9,1%,1/16W,CHIP,G2A"
					( Origin gPackager )
				)
				( objectStatus "R7P17" )
				( pin "a"
					( attribute "PN" "1"
						( Origin gPackager )
					)
					( objectStatus "R7P17.1" )
				)
				( pin "b"
					( attribute "PN" "2"
						( Origin gPackager )
					)
					( objectStatus "R7P17.2" )
				)
			)
			( gate "@baseboard_fab2_lib.baseboard_fab2(sch_1):page55_i152"
				( attribute "BOM_COST" "PROC_SOCKET"
					( Origin gFrontEnd )
				)
				( attribute "CDS_LIB" "chpset_lib"
					( Origin gPackager )
				)
				( attribute "CDS_LOCATION" "XRU2"
					( Origin gPackager )
				)
				( attribute "LOCATION" "XRU2"
					( Origin gFrontEnd )
				)
				( attribute "MATERIAL" "PLASTIC"
					( Origin gFrontEnd )
				)
				( attribute "PACK_TYPE" "RIGHT"
					( Origin gFrontEnd )
				)
				( attribute "PART_NUMBER" "H37604-101"
					( Origin gFrontEnd )
				)
				( attribute "PHYS_PAGE" "55"
					( Origin gFrontEnd )
				)
				( attribute "ROOM" "CPU1"
					( Origin gFrontEnd )
				)
				( attribute "ROT" "0"
					( Origin gFrontEnd )
				)
				( attribute "SKT_NUMBER" "P0"
					( Origin gFrontEnd )
				)
				( attribute "VER" "1"
					( Origin gFrontEnd )
				)
				( attribute "XY" "(6875,4000)"
					( Origin gFrontEnd )
				)
				( attribute "CHIPS_PART_NAME" "SOCKET_P_MECH_A"
					( Origin gPackager )
				)
				( attribute "CDS_PART_NAME" "SOCKET_P_MECH_A_RIGHT-P0,PLASTA"
					( Origin gPackager )
				)
				( objectStatus "XRU2" )
			)
			( gate "@baseboard_fab2_lib.baseboard_fab2(sch_1):page55_i153"
				( attribute "BOM_COST" "PROC_SOCKET"
					( Origin gFrontEnd )
				)
				( attribute "CDS_LIB" "chpset_lib"
					( Origin gPackager )
				)
				( attribute "CDS_LOCATION" "XLU2"
					( Origin gPackager )
				)
				( attribute "LOCATION" "XLU2"
					( Origin gFrontEnd )
				)
				( attribute "MATERIAL" "PLASTIC"
					( Origin gFrontEnd )
				)
				( attribute "PACK_TYPE" "LEFT"
					( Origin gFrontEnd )
				)
				( attribute "PART_NUMBER" "H37604-201"
					( Origin gFrontEnd )
				)
				( attribute "PHYS_PAGE" "55"
					( Origin gFrontEnd )
				)
				( attribute "ROOM" "CPU1"
					( Origin gFrontEnd )
				)
				( attribute "ROT" "0"
					( Origin gFrontEnd )
				)
				( attribute "SKT_NUMBER" "P0"
					( Origin gFrontEnd )
				)
				( attribute "VER" "1"
					( Origin gFrontEnd )
				)
				( attribute "XY" "(6875,3725)"
					( Origin gFrontEnd )
				)
				( attribute "CHIPS_PART_NAME" "SOCKET_P_MECH_A"
					( Origin gPackager )
				)
				( attribute "CDS_PART_NAME" "SOCKET_P_MECH_A_LEFT-P0,PLASTIA"
					( Origin gPackager )
				)
				( objectStatus "XLU2" )
			)
			( gate "@baseboard_fab2_lib.baseboard_fab2(sch_1):page55_i155"
				( attribute "BOM_COST" "PROC_SOCKET"
					( Origin gFrontEnd )
				)
				( attribute "CDS_LIB" "mstr_discrete"
					( Origin gPackager )
				)
				( attribute "CDS_LOCATION" "R3D4"
					( Origin gPackager )
				)
				( attribute "CDS_SEC" "1"
					( Origin gPackager )
				)
				( attribute "LOCATION" "R3D4"
					( Origin gFrontEnd )
				)
				( attribute "MATERIAL" "CHIP"
					( Origin gFrontEnd )
				)
				( attribute "PACK_TYPE" "0402"
					( Origin gFrontEnd )
				)
				( attribute "PART_NUMBER" "G21796-047"
					( Origin gFrontEnd )
				)
				( attribute "PHYS_PAGE" "55"
					( Origin gFrontEnd )
				)
				( attribute "ROOM" "CPU1"
					( Origin gFrontEnd )
				)
				( attribute "ROT" "2"
					( Origin gFrontEnd )
				)
				( attribute "SEC" "1"
					( Origin gFrontEnd )
				)
				( attribute "SEC_TYPE" "0402"
					( Origin gFrontEnd )
				)
				( attribute "TOLERANCE" "1%"
					( Origin gFrontEnd )
				)
				( attribute "VALUE" "49.9"
					( Origin gFrontEnd )
				)
				( attribute "VER" "2"
					( Origin gFrontEnd )
				)
				( attribute "WATTAGE" "1/16W"
					( Origin gFrontEnd )
				)
				( attribute "XY" "(7400,1425)"
					( Origin gFrontEnd )
				)
				( attribute "CHIPS_PART_NAME" "RES"
					( Origin gPackager )
				)
				( attribute "CDS_PART_NAME" "RES_0402-49.9,1%,1/16W,CHIP,G2A"
					( Origin gPackager )
				)
				( objectStatus "R3D4" )
				( pin "a"
					( attribute "PN" "1"
						( Origin gPackager )
					)
					( objectStatus "R3D4.1" )
				)
				( pin "b"
					( attribute "PN" "2"
						( Origin gPackager )
					)
					( objectStatus "R3D4.2" )
				)
			)
			( gate "@baseboard_fab2_lib.baseboard_fab2(sch_1):page55_i156"
				( attribute "BOM_COST" "PROC_SOCKET"
					( Origin gFrontEnd )
				)
				( attribute "CDS_LIB" "mstr_discrete"
					( Origin gPackager )
				)
				( attribute "CDS_LOCATION" "R7P26"
					( Origin gPackager )
				)
				( attribute "CDS_SEC" "1"
					( Origin gPackager )
				)
				( attribute "LOCATION" "R7P26"
					( Origin gFrontEnd )
				)
				( attribute "MATERIAL" "CHIP"
					( Origin gFrontEnd )
				)
				( attribute "PACK_TYPE" "0402"
					( Origin gFrontEnd )
				)
				( attribute "PART_NUMBER" "G21796-047"
					( Origin gFrontEnd )
				)
				( attribute "PHYS_PAGE" "55"
					( Origin gFrontEnd )
				)
				( attribute "ROOM" "CPU1"
					( Origin gFrontEnd )
				)
				( attribute "ROT" "0"
					( Origin gFrontEnd )
				)
				( attribute "SEC" "1"
					( Origin gFrontEnd )
				)
				( attribute "SEC_TYPE" "0402"
					( Origin gFrontEnd )
				)
				( attribute "TOLERANCE" "1%"
					( Origin gFrontEnd )
				)
				( attribute "VALUE" "49.9"
					( Origin gFrontEnd )
				)
				( attribute "VER" "1"
					( Origin gFrontEnd )
				)
				( attribute "WATTAGE" "1/16W"
					( Origin gFrontEnd )
				)
				( attribute "XY" "(11925,3850)"
					( Origin gFrontEnd )
				)
				( attribute "CHIPS_PART_NAME" "RES"
					( Origin gPackager )
				)
				( attribute "CDS_PART_NAME" "RES_0402-49.9,1%,1/16W,CHIP,G2A"
					( Origin gPackager )
				)
				( objectStatus "R7P26" )
				( pin "a"
					( attribute "PN" "1"
						( Origin gPackager )
					)
					( objectStatus "R7P26.1" )
				)
				( pin "b"
					( attribute "PN" "2"
						( Origin gPackager )
					)
					( objectStatus "R7P26.2" )
				)
			)
			( gate "@baseboard_fab2_lib.baseboard_fab2(sch_1):page55_i157"
				( attribute "BOM_COST" "PROC_SOCKET"
					( Origin gFrontEnd )
				)
				( attribute "CDS_LIB" "mstr_discrete"
					( Origin gPackager )
				)
				( attribute "CDS_LOCATION" "R8N1"
					( Origin gPackager )
				)
				( attribute "CDS_SEC" "1"
					( Origin gPackager )
				)
				( attribute "LOCATION" "R8N1"
					( Origin gFrontEnd )
				)
				( attribute "MATERIAL" "CHIP"
					( Origin gFrontEnd )
				)
				( attribute "PACK_TYPE" "0402"
					( Origin gFrontEnd )
				)
				( attribute "PART_NUMBER" "G21796-336"
					( Origin gFrontEnd )
				)
				( attribute "PHYS_PAGE" "55"
					( Origin gFrontEnd )
				)
				( attribute "ROOM" "CPU1"
					( Origin gFrontEnd )
				)
				( attribute "ROT" "0"
					( Origin gFrontEnd )
				)
				( attribute "SEC" "1"
					( Origin gFrontEnd )
				)
				( attribute "SEC_TYPE" "0402"
					( Origin gFrontEnd )
				)
				( attribute "TOLERANCE" "1%"
					( Origin gFrontEnd )
				)
				( attribute "VALUE" "1.8K"
					( Origin gFrontEnd )
				)
				( attribute "VER" "2"
					( Origin gFrontEnd )
				)
				( attribute "WATTAGE" "1/16W"
					( Origin gFrontEnd )
				)
				( attribute "XY" "(12875,2350)"
					( Origin gFrontEnd )
				)
				( attribute "CHIPS_PART_NAME" "RES"
					( Origin gPackager )
				)
				( attribute "CDS_PART_NAME" "RES_0402-1.8K,1%,1/16W,CHIP,G2A"
					( Origin gPackager )
				)
				( objectStatus "R8N1" )
				( pin "a"
					( attribute "PN" "1"
						( Origin gPackager )
					)
					( objectStatus "R8N1.1" )
				)
				( pin "b"
					( attribute "PN" "2"
						( Origin gPackager )
					)
					( objectStatus "R8N1.2" )
				)
			)
			( gate "@baseboard_fab2_lib.baseboard_fab2(sch_1):page55_i158"
				( attribute "BOM_COST" "PROC_SOCKET"
					( Origin gFrontEnd )
				)
				( attribute "CDS_LIB" "mstr_discrete"
					( Origin gPackager )
				)
				( attribute "CDS_LOCATION" "R8N4"
					( Origin gPackager )
				)
				( attribute "CDS_SEC" "1"
					( Origin gPackager )
				)
				( attribute "LOCATION" "R8N4"
					( Origin gFrontEnd )
				)
				( attribute "MATERIAL" "CHIP"
					( Origin gFrontEnd )
				)
				( attribute "PACK_TYPE" "0402"
					( Origin gFrontEnd )
				)
				( attribute "PART_NUMBER" "G21796-336"
					( Origin gFrontEnd )
				)
				( attribute "PHYS_PAGE" "55"
					( Origin gFrontEnd )
				)
				( attribute "ROOM" "CPU1"
					( Origin gFrontEnd )
				)
				( attribute "ROT" "0"
					( Origin gFrontEnd )
				)
				( attribute "SEC" "1"
					( Origin gFrontEnd )
				)
				( attribute "SEC_TYPE" "0402"
					( Origin gFrontEnd )
				)
				( attribute "TOLERANCE" "1%"
					( Origin gFrontEnd )
				)
				( attribute "VALUE" "1.8K"
					( Origin gFrontEnd )
				)
				( attribute "VER" "2"
					( Origin gFrontEnd )
				)
				( attribute "WATTAGE" "1/16W"
					( Origin gFrontEnd )
				)
				( attribute "XY" "(13075,2350)"
					( Origin gFrontEnd )
				)
				( attribute "CHIPS_PART_NAME" "RES"
					( Origin gPackager )
				)
				( attribute "CDS_PART_NAME" "RES_0402-1.8K,1%,1/16W,CHIP,G2A"
					( Origin gPackager )
				)
				( objectStatus "R8N4" )
				( pin "a"
					( attribute "PN" "1"
						( Origin gPackager )
					)
					( objectStatus "R8N4.1" )
				)
				( pin "b"
					( attribute "PN" "2"
						( Origin gPackager )
					)
					( objectStatus "R8N4.2" )
				)
			)
			( gate "@baseboard_fab2_lib.baseboard_fab2(sch_1):page55_i159"
				( attribute "BOM_COST" "PROC_SOCKET"
					( Origin gFrontEnd )
				)
				( attribute "CDS_LIB" "mstr_discrete"
					( Origin gPackager )
				)
				( attribute "CDS_LOCATION" "R8N3"
					( Origin gPackager )
				)
				( attribute "CDS_SEC" "1"
					( Origin gPackager )
				)
				( attribute "LOCATION" "R8N3"
					( Origin gFrontEnd )
				)
				( attribute "MATERIAL" "CHIP"
					( Origin gFrontEnd )
				)
				( attribute "PACK_TYPE" "0402"
					( Origin gFrontEnd )
				)
				( attribute "PART_NUMBER" "G21796-016"
					( Origin gFrontEnd )
				)
				( attribute "PHYS_PAGE" "55"
					( Origin gFrontEnd )
				)
				( attribute "ROOM" "CPU1"
					( Origin gFrontEnd )
				)
				( attribute "ROT" "0"
					( Origin gFrontEnd )
				)
				( attribute "SEC" "1"
					( Origin gFrontEnd )
				)
				( attribute "SEC_TYPE" "0402"
					( Origin gFrontEnd )
				)
				( attribute "TOLERANCE" "1%"
					( Origin gFrontEnd )
				)
				( attribute "VALUE" "10.0K"
					( Origin gFrontEnd )
				)
				( attribute "VER" "2"
					( Origin gFrontEnd )
				)
				( attribute "WATTAGE" "1/16W"
					( Origin gFrontEnd )
				)
				( attribute "XY" "(13275,2350)"
					( Origin gFrontEnd )
				)
				( attribute "CHIPS_PART_NAME" "RES"
					( Origin gPackager )
				)
				( attribute "CDS_PART_NAME" "RES_0402-10.0K,1%,1/16W,CHIP,GA"
					( Origin gPackager )
				)
				( objectStatus "R8N3" )
				( pin "a"
					( attribute "PN" "1"
						( Origin gPackager )
					)
					( objectStatus "R8N3.1" )
				)
				( pin "b"
					( attribute "PN" "2"
						( Origin gPackager )
					)
					( objectStatus "R8N3.2" )
				)
			)
			( gate "@baseboard_fab2_lib.baseboard_fab2(sch_1):page55_i160"
				( attribute "BOM_COST" "PROC_SOCKET"
					( Origin gFrontEnd )
				)
				( attribute "CDS_LIB" "mstr_discrete"
					( Origin gPackager )
				)
				( attribute "CDS_LOCATION" "R8N5"
					( Origin gPackager )
				)
				( attribute "CDS_SEC" "1"
					( Origin gPackager )
				)
				( attribute "LOCATION" "R8N5"
					( Origin gFrontEnd )
				)
				( attribute "MATERIAL" "CHIP"
					( Origin gFrontEnd )
				)
				( attribute "PACK_TYPE" "0402"
					( Origin gFrontEnd )
				)
				( attribute "PART_NUMBER" "G21796-016"
					( Origin gFrontEnd )
				)
				( attribute "PHYS_PAGE" "55"
					( Origin gFrontEnd )
				)
				( attribute "ROOM" "CPU1"
					( Origin gFrontEnd )
				)
				( attribute "ROT" "0"
					( Origin gFrontEnd )
				)
				( attribute "SEC" "1"
					( Origin gFrontEnd )
				)
				( attribute "SEC_TYPE" "0402"
					( Origin gFrontEnd )
				)
				( attribute "TOLERANCE" "1%"
					( Origin gFrontEnd )
				)
				( attribute "VALUE" "10.0K"
					( Origin gFrontEnd )
				)
				( attribute "VER" "2"
					( Origin gFrontEnd )
				)
				( attribute "WATTAGE" "1/16W"
					( Origin gFrontEnd )
				)
				( attribute "XY" "(13475,2350)"
					( Origin gFrontEnd )
				)
				( attribute "CHIPS_PART_NAME" "RES"
					( Origin gPackager )
				)
				( attribute "CDS_PART_NAME" "RES_0402-10.0K,1%,1/16W,CHIP,GA"
					( Origin gPackager )
				)
				( objectStatus "R8N5" )
				( pin "a"
					( attribute "PN" "1"
						( Origin gPackager )
					)
					( objectStatus "R8N5.1" )
				)
				( pin "b"
					( attribute "PN" "2"
						( Origin gPackager )
					)
					( objectStatus "R8N5.2" )
				)
			)
			( gate "@baseboard_fab2_lib.baseboard_fab2(sch_1):page55_i161"
				( attribute "BOM_COST" "PROC_SOCKET"
					( Origin gFrontEnd )
				)
				( attribute "CDS_LIB" "mstr_discrete"
					( Origin gPackager )
				)
				( attribute "CDS_LOCATION" "R8N2"
					( Origin gPackager )
				)
				( attribute "CDS_SEC" "1"
					( Origin gPackager )
				)
				( attribute "LOCATION" "R8N2"
					( Origin gFrontEnd )
				)
				( attribute "MATERIAL" "CHIP"
					( Origin gFrontEnd )
				)
				( attribute "PACK_TYPE" "0402"
					( Origin gFrontEnd )
				)
				( attribute "PART_NUMBER" "G21796-016"
					( Origin gFrontEnd )
				)
				( attribute "PHYS_PAGE" "55"
					( Origin gFrontEnd )
				)
				( attribute "ROOM" "CPU1"
					( Origin gFrontEnd )
				)
				( attribute "ROT" "0"
					( Origin gFrontEnd )
				)
				( attribute "SEC" "1"
					( Origin gFrontEnd )
				)
				( attribute "SEC_TYPE" "0402"
					( Origin gFrontEnd )
				)
				( attribute "TOLERANCE" "1%"
					( Origin gFrontEnd )
				)
				( attribute "VALUE" "10.0K"
					( Origin gFrontEnd )
				)
				( attribute "VER" "2"
					( Origin gFrontEnd )
				)
				( attribute "WATTAGE" "1/16W"
					( Origin gFrontEnd )
				)
				( attribute "XY" "(13675,2350)"
					( Origin gFrontEnd )
				)
				( attribute "CHIPS_PART_NAME" "RES"
					( Origin gPackager )
				)
				( attribute "CDS_PART_NAME" "RES_0402-10.0K,1%,1/16W,CHIP,GA"
					( Origin gPackager )
				)
				( objectStatus "R8N2" )
				( pin "a"
					( attribute "PN" "1"
						( Origin gPackager )
					)
					( objectStatus "R8N2.1" )
				)
				( pin "b"
					( attribute "PN" "2"
						( Origin gPackager )
					)
					( objectStatus "R8N2.2" )
				)
			)
			( gate "@baseboard_fab2_lib.baseboard_fab2(sch_1):page55_i170"
				( attribute "BOM_COST" "PROC_SOCKET"
					( Origin gFrontEnd )
				)
				( attribute "CDS_LIB" "mstr_discrete"
					( Origin gPackager )
				)
				( attribute "CDS_LOCATION" "R7P25"
					( Origin gPackager )
				)
				( attribute "CDS_SEC" "1"
					( Origin gPackager )
				)
				( attribute "LOCATION" "R7P25"
					( Origin gFrontEnd )
				)
				( attribute "MATERIAL" "CHIP"
					( Origin gFrontEnd )
				)
				( attribute "PACK_TYPE" "0402"
					( Origin gFrontEnd )
				)
				( attribute "PART_NUMBER" "G21796-047"
					( Origin gFrontEnd )
				)
				( attribute "PHYS_PAGE" "55"
					( Origin gFrontEnd )
				)
				( attribute "ROOM" "CPU1"
					( Origin gFrontEnd )
				)
				( attribute "ROT" "0"
					( Origin gFrontEnd )
				)
				( attribute "SEC" "1"
					( Origin gFrontEnd )
				)
				( attribute "SEC_TYPE" "0402"
					( Origin gFrontEnd )
				)
				( attribute "TOLERANCE" "1%"
					( Origin gFrontEnd )
				)
				( attribute "VALUE" "49.9"
					( Origin gFrontEnd )
				)
				( attribute "VER" "1"
					( Origin gFrontEnd )
				)
				( attribute "WATTAGE" "1/16W"
					( Origin gFrontEnd )
				)
				( attribute "XY" "(11800,3900)"
					( Origin gFrontEnd )
				)
				( attribute "CHIPS_PART_NAME" "RES"
					( Origin gPackager )
				)
				( attribute "CDS_PART_NAME" "RES_0402-49.9,1%,1/16W,CHIP,G2A"
					( Origin gPackager )
				)
				( objectStatus "R7P25" )
				( pin "a"
					( attribute "PN" "1"
						( Origin gPackager )
					)
					( objectStatus "R7P25.1" )
				)
				( pin "b"
					( attribute "PN" "2"
						( Origin gPackager )
					)
					( objectStatus "R7P25.2" )
				)
			)
			( gate "@baseboard_fab2_lib.baseboard_fab2(sch_1):page55_i172"
				( attribute "CDS_LIB" "chpset_lib"
					( Origin gPackager )
				)
				( attribute "CDS_LOCATION" "U2D1"
					( Origin gPackager )
				)
				( attribute "CDS_SEC" "1"
					( Origin gPackager )
				)
				( attribute "LOCATION" "U2D1"
					( Origin gFrontEnd )
				)
				( attribute "MATERIAL" "IC"
					( Origin gFrontEnd )
				)
				( attribute "PACK_TYPE" "BGA1"
					( Origin gFrontEnd )
				)
				( attribute "PART_NUMBER" "TBD"
					( Origin gFrontEnd )
				)
				( attribute "PHYS_PAGE" "55"
					( Origin gFrontEnd )
				)
				( attribute "ROOM" "CPU1"
					( Origin gFrontEnd )
				)
				( attribute "ROT" "0"
					( Origin gFrontEnd )
				)
				( attribute "SEC" "1"
					( Origin gFrontEnd )
				)
				( attribute "SEC_TYPE" "BGA1"
					( Origin gFrontEnd )
				)
				( attribute "VER" "1"
					( Origin gFrontEnd )
				)
				( attribute "XY" "(10225,2500)"
					( Origin gFrontEnd )
				)
				( attribute "CHIPS_PART_NAME" "SKX_EXT_B"
					( Origin gPackager )
				)
				( attribute "CDS_PART_NAME" "SKX_EXT_B_BGA1-IC,TBD"
					( Origin gPackager )
				)
				( objectStatus "U2D1" )
				( pin "bclk0_dn"
					( attribute "PN" "AU24"
						( Origin gPackager )
					)
					( objectStatus "U2D1.AU24" )
				)
				( pin "bclk0_dp"
					( attribute "PN" "AW24"
						( Origin gPackager )
					)
					( objectStatus "U2D1.AW24" )
				)
				( pin "bclk1_dn"
					( attribute "PN" "CR26"
						( Origin gPackager )
					)
					( objectStatus "U2D1.CR26" )
				)
				( pin "bclk1_dp"
					( attribute "PN" "CP27"
						( Origin gPackager )
					)
					( objectStatus "U2D1.CP27" )
				)
				( pin "bclk2_dn"
					( attribute "PN" "CT25"
						( Origin gPackager )
					)
					( objectStatus "U2D1.CT25" )
				)
				( pin "bclk2_dp"
					( attribute "PN" "CU26"
						( Origin gPackager )
					)
					( objectStatus "U2D1.CU26" )
				)
				( pin "bist_enable"
					( attribute "PN" "BA20"
						( Origin gPackager )
					)
					( objectStatus "U2D1.BA20" )
				)
				( pin "bmcinit"
					( attribute "PN" "BD23"
						( Origin gPackager )
					)
					( objectStatus "U2D1.BD23" )
				)
				( pin "bpm_n(0)"
					( attribute "PN" "AJ10"
						( Origin gPackager )
					)
					( objectStatus "U2D1.AJ10" )
				)
				( pin "bpm_n(1)"
					( attribute "PN" "AH11"
						( Origin gPackager )
					)
					( objectStatus "U2D1.AH11" )
				)
				( pin "bpm_n(2)"
					( attribute "PN" "AG10"
						( Origin gPackager )
					)
					( objectStatus "U2D1.AG10" )
				)
				( pin "bpm_n(3)"
					( attribute "PN" "AF11"
						( Origin gPackager )
					)
					( objectStatus "U2D1.AF11" )
				)
				( pin "bpm_n(4)"
					( attribute "PN" "AA12"
						( Origin gPackager )
					)
					( objectStatus "U2D1.AA12" )
				)
				( pin "bpm_n(5)"
					( attribute "PN" "Y11"
						( Origin gPackager )
					)
					( objectStatus "U2D1.Y11" )
				)
				( pin "bpm_n(6)"
					( attribute "PN" "AE12"
						( Origin gPackager )
					)
					( objectStatus "U2D1.AE12" )
				)
				( pin "bpm_n(7)"
					( attribute "PN" "AC12"
						( Origin gPackager )
					)
					( objectStatus "U2D1.AC12" )
				)
				( pin "caterr_n"
					( attribute "PN" "AL14"
						( Origin gPackager )
					)
					( objectStatus "U2D1.AL14" )
				)
				( pin "ddr0_cavref"
					( attribute "PN" "AJ64"
						( Origin gPackager )
					)
					( objectStatus "U2D1.AJ64" )
				)
				( pin "ddr1_cavref"
					( attribute "PN" "AK63"
						( Origin gPackager )
					)
					( objectStatus "U2D1.AK63" )
				)
				( pin "ddr2_cavref"
					( attribute "PN" "AH63"
						( Origin gPackager )
					)
					( objectStatus "U2D1.AH63" )
				)
				( pin "ddr3_cavref"
					( attribute "PN" "CP61"
						( Origin gPackager )
					)
					( objectStatus "U2D1.CP61" )
				)
				( pin "ddr4_cavref"
					( attribute "PN" "CT61"
						( Origin gPackager )
					)
					( objectStatus "U2D1.CT61" )
				)
				( pin "ddr5_cavref"
					( attribute "PN" "CV61"
						( Origin gPackager )
					)
					( objectStatus "U2D1.CV61" )
				)
				( pin "ddr012_dram_pwr_ok"
					( attribute "PN" "AN30"
						( Origin gPackager )
					)
					( objectStatus "U2D1.AN30" )
				)
				( pin "ddr012_rcomp(0)"
					( attribute "PN" "Y43"
						( Origin gPackager )
					)
					( objectStatus "U2D1.Y43" )
				)
				( pin "ddr012_rcomp(1)"
					( attribute "PN" "AB43"
						( Origin gPackager )
					)
					( objectStatus "U2D1.AB43" )
				)
				( pin "ddr012_rcomp(2)"
					( attribute "PN" "AC42"
						( Origin gPackager )
					)
					( objectStatus "U2D1.AC42" )
				)
				( pin "ddr012_reset_n"
					( attribute "PN" "U64"
						( Origin gPackager )
					)
					( objectStatus "U2D1.U64" )
				)
				( pin "ddr012_spdscl"
					( attribute "PN" "AJ18"
						( Origin gPackager )
					)
					( objectStatus "U2D1.AJ18" )
				)
				( pin "ddr012_spdsda"
					( attribute "PN" "AF17"
						( Origin gPackager )
					)
					( objectStatus "U2D1.AF17" )
				)
				( pin "ddr345_dram_pwr_ok"
					( attribute "PN" "CR28"
						( Origin gPackager )
					)
					( objectStatus "U2D1.CR28" )
				)
				( pin "ddr345_rcomp(0)"
					( attribute "PN" "DC48"
						( Origin gPackager )
					)
					( objectStatus "U2D1.DC48" )
				)
				( pin "ddr345_rcomp(1)"
					( attribute "PN" "DD47"
						( Origin gPackager )
					)
					( objectStatus "U2D1.DD47" )
				)
				( pin "ddr345_rcomp(2)"
					( attribute "PN" "DD49"
						( Origin gPackager )
					)
					( objectStatus "U2D1.DD49" )
				)
				( pin "ddr345_reset_n"
					( attribute "PN" "DV63"
						( Origin gPackager )
					)
					( objectStatus "U2D1.DV63" )
				)
				( pin "ddr345_spdscl"
					( attribute "PN" "AE18"
						( Origin gPackager )
					)
					( objectStatus "U2D1.AE18" )
				)
				( pin "ddr345_spdsda"
					( attribute "PN" "AD17"
						( Origin gPackager )
					)
					( objectStatus "U2D1.AD17" )
				)
				( pin "ear_n"
					( attribute "PN" "AJ14"
						( Origin gPackager )
					)
					( objectStatus "U2D1.AJ14" )
				)
				( pin "error_n(0)"
					( attribute "PN" "AJ12"
						( Origin gPackager )
					)
					( objectStatus "U2D1.AJ12" )
				)
				( pin "error_n(1)"
					( attribute "PN" "AK11"
						( Origin gPackager )
					)
					( objectStatus "U2D1.AK11" )
				)
				( pin "error_n(2)"
					( attribute "PN" "AL12"
						( Origin gPackager )
					)
					( objectStatus "U2D1.AL12" )
				)
				( pin "frmagent"
					( attribute "PN" "AV17"
						( Origin gPackager )
					)
					( objectStatus "U2D1.AV17" )
				)
				( pin "legacy_skt"
					( attribute "PN" "AE20"
						( Origin gPackager )
					)
					( objectStatus "U2D1.AE20" )
				)
				( pin "mcp01_rbias(0)"
					( attribute "PN" "CU32"
						( Origin gPackager )
					)
					( objectStatus "U2D1.CU32" )
				)
				( pin "mcp01_rbias(1)"
					( attribute "PN" "CT31"
						( Origin gPackager )
					)
					( objectStatus "U2D1.CT31" )
				)
				( pin "mem_hot_c012_n"
					( attribute "PN" "AH13"
						( Origin gPackager )
					)
					( objectStatus "U2D1.AH13" )
				)
				( pin "mem_hot_c345_n"
					( attribute "PN" "AF13"
						( Origin gPackager )
					)
					( objectStatus "U2D1.AF13" )
				)
				( pin "msmi_n"
					( attribute "PN" "AN20"
						( Origin gPackager )
					)
					( objectStatus "U2D1.AN20" )
				)
				( pin "nmi"
					( attribute "PN" "AP11"
						( Origin gPackager )
					)
					( objectStatus "U2D1.AP11" )
				)
				( pin "pe3_rbias(0)"
					( attribute "PN" "CP29"
						( Origin gPackager )
					)
					( objectStatus "U2D1.CP29" )
				)
				( pin "pe3_rbias(1)"
					( attribute "PN" "CR30"
						( Origin gPackager )
					)
					( objectStatus "U2D1.CR30" )
				)
				( pin "pe012_rbias(0)"
					( attribute "PN" "CN30"
						( Origin gPackager )
					)
					( objectStatus "U2D1.CN30" )
				)
				( pin "pe012_rbias(1)"
					( attribute "PN" "CL30"
						( Origin gPackager )
					)
					( objectStatus "U2D1.CL30" )
				)
				( pin "pe_hp_scl"
					( attribute "PN" "AM19"
						( Origin gPackager )
					)
					( objectStatus "U2D1.AM19" )
				)
				( pin "pe_hp_sda"
					( attribute "PN" "AL18"
						( Origin gPackager )
					)
					( objectStatus "U2D1.AL18" )
				)
				( pin "peci"
					( attribute "PN" "AU12"
						( Origin gPackager )
					)
					( objectStatus "U2D1.AU12" )
				)
				( pin "pirom_addr(0)"
					( attribute "PN" "CU58"
						( Origin gPackager )
					)
					( objectStatus "U2D1.CU58" )
				)
				( pin "pirom_addr(1)"
					( attribute "PN" "CV57"
						( Origin gPackager )
					)
					( objectStatus "U2D1.CV57" )
				)
				( pin "pirom_addr(2)"
					( attribute "PN" "CW56"
						( Origin gPackager )
					)
					( objectStatus "U2D1.CW56" )
				)
				( pin "pkgid(0)"
					( attribute "PN" "DC72"
						( Origin gPackager )
					)
					( objectStatus "U2D1.DC72" )
				)
				( pin "pkgid(1)"
					( attribute "PN" "CW72"
						( Origin gPackager )
					)
					( objectStatus "U2D1.CW72" )
				)
				( pin "pkgid(2)"
					( attribute "PN" "DA72"
						( Origin gPackager )
					)
					( objectStatus "U2D1.DA72" )
				)
				( pin "pm_fast_wake_n"
					( attribute "PN" "AF15"
						( Origin gPackager )
					)
					( objectStatus "U2D1.AF15" )
				)
				( pin "pmsync"
					( attribute "PN" "AR14"
						( Origin gPackager )
					)
					( objectStatus "U2D1.AR14" )
				)
				( pin "pmsync_clk"
					( attribute "PN" "AT19"
						( Origin gPackager )
					)
					( objectStatus "U2D1.AT19" )
				)
				( pin "prdy_n"
					( attribute "PN" "AG16"
						( Origin gPackager )
					)
					( objectStatus "U2D1.AG16" )
				)
				( pin "preq_n"
					( attribute "PN" "AR12"
						( Origin gPackager )
					)
					( objectStatus "U2D1.AR12" )
				)
				( pin "proc_id(0)"
					( attribute "PN" "CY71"
						( Origin gPackager )
					)
					( objectStatus "U2D1.CY71" )
				)
				( pin "proc_id(1)"
					( attribute "PN" "DB71"
						( Origin gPackager )
					)
					( objectStatus "U2D1.DB71" )
				)
				( pin "procdis_n"
					( attribute "PN" "AB17"
						( Origin gPackager )
					)
					( objectStatus "U2D1.AB17" )
				)
				( pin "prochot_n"
					( attribute "PN" "AC16"
						( Origin gPackager )
					)
					( objectStatus "U2D1.AC16" )
				)
				( pin "pwrgood"
					( attribute "PN" "BC24"
						( Origin gPackager )
					)
					( objectStatus "U2D1.BC24" )
				)
				( pin "reset_n"
					( attribute "PN" "AP21"
						( Origin gPackager )
					)
					( objectStatus "U2D1.AP21" )
				)
				( pin "safe_mode_boot"
					( attribute "PN" "AR18"
						( Origin gPackager )
					)
					( objectStatus "U2D1.AR18" )
				)
				( pin "sktocc_n"
					( attribute "PN" "AB13"
						( Origin gPackager )
					)
					( objectStatus "U2D1.AB13" )
				)
				( pin "sm_wp"
					( attribute "PN" "CV59"
						( Origin gPackager )
					)
					( objectStatus "U2D1.CV59" )
				)
				( pin "smbclk"
					( attribute "PN" "CT59"
						( Origin gPackager )
					)
					( objectStatus "U2D1.CT59" )
				)
				( pin "smbdat"
					( attribute "PN" "CW58"
						( Origin gPackager )
					)
					( objectStatus "U2D1.CW58" )
				)
				( pin "socket_id(0)"
					( attribute "PN" "AU22"
						( Origin gPackager )
					)
					( objectStatus "U2D1.AU22" )
				)
				( pin "socket_id(1)"
					( attribute "PN" "AU16"
						( Origin gPackager )
					)
					( objectStatus "U2D1.AU16" )
				)
				( pin "socket_id(2)"
					( attribute "PN" "AU20"
						( Origin gPackager )
					)
					( objectStatus "U2D1.AU20" )
				)
				( pin "svidalert_n(0)"
					( attribute "PN" "DE44"
						( Origin gPackager )
					)
					( objectStatus "U2D1.DE44" )
				)
				( pin "svidalert_n(1)"
					( attribute "PN" "DL44"
						( Origin gPackager )
					)
					( objectStatus "U2D1.DL44" )
				)
				( pin "svidclk(0)"
					( attribute "PN" "DC44"
						( Origin gPackager )
					)
					( objectStatus "U2D1.DC44" )
				)
				( pin "svidclk(1)"
					( attribute "PN" "DG44"
						( Origin gPackager )
					)
					( objectStatus "U2D1.DG44" )
				)
				( pin "sviddata(0)"
					( attribute "PN" "DB45"
						( Origin gPackager )
					)
					( objectStatus "U2D1.DB45" )
				)
				( pin "sviddata(1)"
					( attribute "PN" "DJ44"
						( Origin gPackager )
					)
					( objectStatus "U2D1.DJ44" )
				)
				( pin "tck"
					( attribute "PN" "AA14"
						( Origin gPackager )
					)
					( objectStatus "U2D1.AA14" )
				)
				( pin "tdi"
					( attribute "PN" "AC14"
						( Origin gPackager )
					)
					( objectStatus "U2D1.AC14" )
				)
				( pin "tdo"
					( attribute "PN" "AE14"
						( Origin gPackager )
					)
					( objectStatus "U2D1.AE14" )
				)
				( pin "test_12"
					( attribute "PN" "AY19"
						( Origin gPackager )
					)
					( objectStatus "U2D1.AY19" )
				)
				( pin "test_13"
					( attribute "PN" "DB51"
						( Origin gPackager )
					)
					( objectStatus "U2D1.DB51" )
				)
				( pin "test_14"
					( attribute "PN" "DC50"
						( Origin gPackager )
					)
					( objectStatus "U2D1.DC50" )
				)
				( pin "test_15"
					( attribute "PN" "AW14"
						( Origin gPackager )
					)
					( objectStatus "U2D1.AW14" )
				)
				( pin "thermtrip_n"
					( attribute "PN" "AB15"
						( Origin gPackager )
					)
					( objectStatus "U2D1.AB15" )
				)
				( pin "tms"
					( attribute "PN" "W14"
						( Origin gPackager )
					)
					( objectStatus "U2D1.W14" )
				)
				( pin "trst_n"
					( attribute "PN" "Y13"
						( Origin gPackager )
					)
					( objectStatus "U2D1.Y13" )
				)
				( pin "tsc_sync"
					( attribute "PN" "AM11"
						( Origin gPackager )
					)
					( objectStatus "U2D1.AM11" )
				)
				( pin "txt_agent"
					( attribute "PN" "AW18"
						( Origin gPackager )
					)
					( objectStatus "U2D1.AW18" )
				)
				( pin "txt_plten"
					( attribute "PN" "AV15"
						( Origin gPackager )
					)
					( objectStatus "U2D1.AV15" )
				)
				( pin "upi01_rbias(0)"
					( attribute "PN" "AT29"
						( Origin gPackager )
					)
					( objectStatus "U2D1.AT29" )
				)
				( pin "upi01_rbias(1)"
					( attribute "PN" "AP29"
						( Origin gPackager )
					)
					( objectStatus "U2D1.AP29" )
				)
				( pin "upi2_rbias(0)"
					( attribute "PN" "CL28"
						( Origin gPackager )
					)
					( objectStatus "U2D1.CL28" )
				)
				( pin "upi2_rbias(1)"
					( attribute "PN" "CK29"
						( Origin gPackager )
					)
					( objectStatus "U2D1.CK29" )
				)
			)
			( gate "@baseboard_fab2_lib.baseboard_fab2(sch_1):page55_i181"
				( attribute "CDS_LIB" "mstr_discrete"
					( Origin gPackager )
				)
				( attribute "CDS_LOCATION" "R6P39"
					( Origin gPackager )
				)
				( attribute "CDS_SEC" "1"
					( Origin gPackager )
				)
				( attribute "LOCATION" "R6P39"
					( Origin gFrontEnd )
				)
				( attribute "MATERIAL" "CHIP"
					( Origin gFrontEnd )
				)
				( attribute "PACK_TYPE" "0402"
					( Origin gFrontEnd )
				)
				( attribute "PART_NUMBER" "G21796-072"
					( Origin gFrontEnd )
				)
				( attribute "PHYS_PAGE" "55"
					( Origin gFrontEnd )
				)
				( attribute "ROOM" "CPU1"
					( Origin gFrontEnd )
				)
				( attribute "ROT" "0"
					( Origin gFrontEnd )
				)
				( attribute "SEC" "1"
					( Origin gFrontEnd )
				)
				( attribute "SEC_TYPE" "0402"
					( Origin gFrontEnd )
				)
				( attribute "TOLERANCE" "1%"
					( Origin gFrontEnd )
				)
				( attribute "VALUE" "4.75K"
					( Origin gFrontEnd )
				)
				( attribute "VER" "2"
					( Origin gFrontEnd )
				)
				( attribute "WATTAGE" "1/16W"
					( Origin gFrontEnd )
				)
				( attribute "XY" "(13275,1100)"
					( Origin gFrontEnd )
				)
				( attribute "CHIPS_PART_NAME" "RES"
					( Origin gPackager )
				)
				( attribute "CDS_PART_NAME" "RES_0402-4.75K,1%,1/16W,CHIP,GA"
					( Origin gPackager )
				)
				( objectStatus "R6P39" )
				( pin "a"
					( attribute "PN" "1"
						( Origin gPackager )
					)
					( objectStatus "R6P39.1" )
				)
				( pin "b"
					( attribute "PN" "2"
						( Origin gPackager )
					)
					( objectStatus "R6P39.2" )
				)
			)
			( gate "@baseboard_fab2_lib.baseboard_fab2(sch_1):page56_i169"
				( attribute "CDS_LIB" "chpset_lib"
					( Origin gPackager )
				)
				( attribute "CDS_LOCATION" "U2D1"
					( Origin gPackager )
				)
				( attribute "CDS_SEC" "2"
					( Origin gPackager )
				)
				( attribute "LOCATION" "U2D1"
					( Origin gFrontEnd )
				)
				( attribute "MATERIAL" "IC"
					( Origin gFrontEnd )
				)
				( attribute "PACK_TYPE" "BGA1"
					( Origin gFrontEnd )
				)
				( attribute "PART_NUMBER" "TBD"
					( Origin gFrontEnd )
				)
				( attribute "PHYS_PAGE" "56"
					( Origin gFrontEnd )
				)
				( attribute "ROT" "0"
					( Origin gFrontEnd )
				)
				( attribute "SEC" "2"
					( Origin gFrontEnd )
				)
				( attribute "SEC_TYPE" "BGA1"
					( Origin gFrontEnd )
				)
				( attribute "VER" "2"
					( Origin gFrontEnd )
				)
				( attribute "XY" "(-4025,2550)"
					( Origin gFrontEnd )
				)
				( attribute "CHIPS_PART_NAME" "SKX_EXT_B"
					( Origin gPackager )
				)
				( attribute "CDS_PART_NAME" "SKX_EXT_B_BGA1-IC,TBD"
					( Origin gPackager )
				)
				( objectStatus "U2D1" )
				( pin "debug_en_n"
					( attribute "PN" "AV21"
						( Origin gPackager )
					)
					( objectStatus "U2D1.AV21" )
				)
				( pin "dmimode_override"
					( attribute "PN" "AW12"
						( Origin gPackager )
					)
					( objectStatus "U2D1.AW12" )
				)
				( pin "fivr_fault"
					( attribute "PN" "AU14"
						( Origin gPackager )
					)
					( objectStatus "U2D1.AU14" )
				)
				( pin "pwr_debug_n"
					( attribute "PN" "AP17"
						( Origin gPackager )
					)
					( objectStatus "U2D1.AP17" )
				)
				( pin "rsvd(194)"
					( attribute "PN" "AP61"
						( Origin gPackager )
					)
					( objectStatus "U2D1.AP61" )
				)
				( pin "rsvd(195)"
					( attribute "PN" "AP27"
						( Origin gPackager )
					)
					( objectStatus "U2D1.AP27" )
				)
				( pin "rsvd(196)"
					( attribute "PN" "AP25"
						( Origin gPackager )
					)
					( objectStatus "U2D1.AP25" )
				)
				( pin "rsvd(197)"
					( attribute "PN" "AP23"
						( Origin gPackager )
					)
					( objectStatus "U2D1.AP23" )
				)
				( pin "rsvd(198)"
					( attribute "PN" "AN62"
						( Origin gPackager )
					)
					( objectStatus "U2D1.AN62" )
				)
				( pin "rsvd(199)"
					( attribute "PN" "AN60"
						( Origin gPackager )
					)
					( objectStatus "U2D1.AN60" )
				)
				( pin "rsvd(200)"
					( attribute "PN" "AN26"
						( Origin gPackager )
					)
					( objectStatus "U2D1.AN26" )
				)
				( pin "rsvd(201)"
					( attribute "PN" "AN24"
						( Origin gPackager )
					)
					( objectStatus "U2D1.AN24" )
				)
				( pin "rsvd(202)"
					( attribute "PN" "AN22"
						( Origin gPackager )
					)
					( objectStatus "U2D1.AN22" )
				)
				( pin "rsvd(203)"
					( attribute "PN" "AN18"
						( Origin gPackager )
					)
					( objectStatus "U2D1.AN18" )
				)
				( pin "rsvd(204)"
					( attribute "PN" "AM61"
						( Origin gPackager )
					)
					( objectStatus "U2D1.AM61" )
				)
				( pin "rsvd(205)"
					( attribute "PN" "AM59"
						( Origin gPackager )
					)
					( objectStatus "U2D1.AM59" )
				)
				( pin "rsvd(206)"
					( attribute "PN" "AM27"
						( Origin gPackager )
					)
					( objectStatus "U2D1.AM27" )
				)
				( pin "rsvd(207)"
					( attribute "PN" "AM25"
						( Origin gPackager )
					)
					( objectStatus "U2D1.AM25" )
				)
				( pin "rsvd(208)"
					( attribute "PN" "AM23"
						( Origin gPackager )
					)
					( objectStatus "U2D1.AM23" )
				)
				( pin "rsvd(209)"
					( attribute "PN" "AM21"
						( Origin gPackager )
					)
					( objectStatus "U2D1.AM21" )
				)
				( pin "rsvd(210)"
					( attribute "PN" "AL62"
						( Origin gPackager )
					)
					( objectStatus "U2D1.AL62" )
				)
				( pin "rsvd(211)"
					( attribute "PN" "AL60"
						( Origin gPackager )
					)
					( objectStatus "U2D1.AL60" )
				)
				( pin "rsvd(212)"
					( attribute "PN" "AL58"
						( Origin gPackager )
					)
					( objectStatus "U2D1.AL58" )
				)
				( pin "rsvd(213)"
					( attribute "PN" "AL26"
						( Origin gPackager )
					)
					( objectStatus "U2D1.AL26" )
				)
				( pin "rsvd(214)"
					( attribute "PN" "AL22"
						( Origin gPackager )
					)
					( objectStatus "U2D1.AL22" )
				)
				( pin "rsvd(215)"
					( attribute "PN" "AL20"
						( Origin gPackager )
					)
					( objectStatus "U2D1.AL20" )
				)
				( pin "rsvd(216)"
					( attribute "PN" "AK69"
						( Origin gPackager )
					)
					( objectStatus "U2D1.AK69" )
				)
				( pin "rsvd(217)"
					( attribute "PN" "AK61"
						( Origin gPackager )
					)
					( objectStatus "U2D1.AK61" )
				)
				( pin "rsvd(218)"
					( attribute "PN" "AK59"
						( Origin gPackager )
					)
					( objectStatus "U2D1.AK59" )
				)
				( pin "rsvd(219)"
					( attribute "PN" "AK57"
						( Origin gPackager )
					)
					( objectStatus "U2D1.AK57" )
				)
				( pin "rsvd(220)"
					( attribute "PN" "AK27"
						( Origin gPackager )
					)
					( objectStatus "U2D1.AK27" )
				)
				( pin "rsvd(221)"
					( attribute "PN" "AK21"
						( Origin gPackager )
					)
					( objectStatus "U2D1.AK21" )
				)
				( pin "rsvd(222)"
					( attribute "PN" "AJ70"
						( Origin gPackager )
					)
					( objectStatus "U2D1.AJ70" )
				)
				( pin "rsvd(223)"
					( attribute "PN" "AJ62"
						( Origin gPackager )
					)
					( objectStatus "U2D1.AJ62" )
				)
				( pin "rsvd(224)"
					( attribute "PN" "AJ60"
						( Origin gPackager )
					)
					( objectStatus "U2D1.AJ60" )
				)
				( pin "rsvd(225)"
					( attribute "PN" "AJ58"
						( Origin gPackager )
					)
					( objectStatus "U2D1.AJ58" )
				)
				( pin "rsvd(226)"
					( attribute "PN" "AJ56"
						( Origin gPackager )
					)
					( objectStatus "U2D1.AJ56" )
				)
				( pin "rsvd(227)"
					( attribute "PN" "AJ20"
						( Origin gPackager )
					)
					( objectStatus "U2D1.AJ20" )
				)
				( pin "rsvd(228)"
					( attribute "PN" "AH73"
						( Origin gPackager )
					)
					( objectStatus "U2D1.AH73" )
				)
				( pin "rsvd(229)"
					( attribute "PN" "AH71"
						( Origin gPackager )
					)
					( objectStatus "U2D1.AH71" )
				)
				( pin "rsvd(230)"
					( attribute "PN" "AH57"
						( Origin gPackager )
					)
					( objectStatus "U2D1.AH57" )
				)
				( pin "rsvd(231)"
					( attribute "PN" "AH55"
						( Origin gPackager )
					)
					( objectStatus "U2D1.AH55" )
				)
				( pin "rsvd(232)"
					( attribute "PN" "AH19"
						( Origin gPackager )
					)
					( objectStatus "U2D1.AH19" )
				)
				( pin "rsvd(233)"
					( attribute "PN" "AH15"
						( Origin gPackager )
					)
					( objectStatus "U2D1.AH15" )
				)
				( pin "rsvd(234)"
					( attribute "PN" "AG72"
						( Origin gPackager )
					)
					( objectStatus "U2D1.AG72" )
				)
				( pin "rsvd(235)"
					( attribute "PN" "AG56"
						( Origin gPackager )
					)
					( objectStatus "U2D1.AG56" )
				)
				( pin "rsvd(236)"
					( attribute "PN" "AG54"
						( Origin gPackager )
					)
					( objectStatus "U2D1.AG54" )
				)
				( pin "rsvd(237)"
					( attribute "PN" "AG52"
						( Origin gPackager )
					)
					( objectStatus "U2D1.AG52" )
				)
				( pin "rsvd(238)"
					( attribute "PN" "AG50"
						( Origin gPackager )
					)
					( objectStatus "U2D1.AG50" )
				)
				( pin "rsvd(239)"
					( attribute "PN" "AG48"
						( Origin gPackager )
					)
					( objectStatus "U2D1.AG48" )
				)
				( pin "rsvd(240)"
					( attribute "PN" "AG20"
						( Origin gPackager )
					)
					( objectStatus "U2D1.AG20" )
				)
				( pin "rsvd(241)"
					( attribute "PN" "AF71"
						( Origin gPackager )
					)
					( objectStatus "U2D1.AF71" )
				)
				( pin "rsvd(242)"
					( attribute "PN" "AF53"
						( Origin gPackager )
					)
					( objectStatus "U2D1.AF53" )
				)
				( pin "rsvd(243)"
					( attribute "PN" "AF51"
						( Origin gPackager )
					)
					( objectStatus "U2D1.AF51" )
				)
				( pin "rsvd(244)"
					( attribute "PN" "AF49"
						( Origin gPackager )
					)
					( objectStatus "U2D1.AF49" )
				)
				( pin "rsvd(245)"
					( attribute "PN" "AF47"
						( Origin gPackager )
					)
					( objectStatus "U2D1.AF47" )
				)
				( pin "rsvd(246)"
					( attribute "PN" "AF19"
						( Origin gPackager )
					)
					( objectStatus "U2D1.AF19" )
				)
				( pin "rsvd(247)"
					( attribute "PN" "AE72"
						( Origin gPackager )
					)
					( objectStatus "U2D1.AE72" )
				)
				( pin "rsvd(248)"
					( attribute "PN" "AE52"
						( Origin gPackager )
					)
					( objectStatus "U2D1.AE52" )
				)
				( pin "rsvd(249)"
					( attribute "PN" "AE50"
						( Origin gPackager )
					)
					( objectStatus "U2D1.AE50" )
				)
				( pin "rsvd(250)"
					( attribute "PN" "AE48"
						( Origin gPackager )
					)
					( objectStatus "U2D1.AE48" )
				)
				( pin "rsvd(251)"
					( attribute "PN" "AE46"
						( Origin gPackager )
					)
					( objectStatus "U2D1.AE46" )
				)
				( pin "rsvd(252)"
					( attribute "PN" "AD51"
						( Origin gPackager )
					)
					( objectStatus "U2D1.AD51" )
				)
				( pin "rsvd(253)"
					( attribute "PN" "AD49"
						( Origin gPackager )
					)
					( objectStatus "U2D1.AD49" )
				)
				( pin "rsvd(254)"
					( attribute "PN" "AD47"
						( Origin gPackager )
					)
					( objectStatus "U2D1.AD47" )
				)
				( pin "rsvd(255)"
					( attribute "CDS_NOT_ON_SYM" "TRUE"
						( Origin gFrontEnd )
					)
				)
				( pin "rsvd(256)"
					( attribute "PN" "Y65"
						( Origin gPackager )
					)
					( objectStatus "U2D1.Y65" )
				)
				( pin "rsvd(257)"
					( attribute "PN" "Y23"
						( Origin gPackager )
					)
					( objectStatus "U2D1.Y23" )
				)
				( pin "rsvd(258)"
					( attribute "PN" "W66"
						( Origin gPackager )
					)
					( objectStatus "U2D1.W66" )
				)
				( pin "rsvd(259)"
					( attribute "PN" "V67"
						( Origin gPackager )
					)
					( objectStatus "U2D1.V67" )
				)
				( pin "rsvd(260)"
					( attribute "PN" "V65"
						( Origin gPackager )
					)
					( objectStatus "U2D1.V65" )
				)
				( pin "rsvd(261)"
					( attribute "PN" "U66"
						( Origin gPackager )
					)
					( objectStatus "U2D1.U66" )
				)
				( pin "rsvd(262)"
					( attribute "PN" "T67"
						( Origin gPackager )
					)
					( objectStatus "U2D1.T67" )
				)
				( pin "rsvd(263)"
					( attribute "PN" "R66"
						( Origin gPackager )
					)
					( objectStatus "U2D1.R66" )
				)
				( pin "rsvd(264)"
					( attribute "PN" "R62"
						( Origin gPackager )
					)
					( objectStatus "U2D1.R62" )
				)
				( pin "rsvd(265)"
					( attribute "PN" "P65"
						( Origin gPackager )
					)
					( objectStatus "U2D1.P65" )
				)
				( pin "rsvd(266)"
					( attribute "PN" "M63"
						( Origin gPackager )
					)
					( objectStatus "U2D1.M63" )
				)
				( pin "rsvd(267)"
					( attribute "PN" "K61"
						( Origin gPackager )
					)
					( objectStatus "U2D1.K61" )
				)
				( pin "rsvd(268)"
					( attribute "PN" "J62"
						( Origin gPackager )
					)
					( objectStatus "U2D1.J62" )
				)
				( pin "rsvd(269)"
					( attribute "PN" "J46"
						( Origin gPackager )
					)
					( objectStatus "U2D1.J46" )
				)
				( pin "rsvd(270)"
					( attribute "PN" "H85"
						( Origin gPackager )
					)
					( objectStatus "U2D1.H85" )
				)
				( pin "rsvd(271)"
					( attribute "PN" "H83"
						( Origin gPackager )
					)
					( objectStatus "U2D1.H83" )
				)
				( pin "rsvd(272)"
					( attribute "PN" "H1"
						( Origin gPackager )
					)
					( objectStatus "U2D1.H1" )
				)
				( pin "rsvd(273)"
					( attribute "PN" "G84"
						( Origin gPackager )
					)
					( objectStatus "U2D1.G84" )
				)
				( pin "rsvd(274)"
					( attribute "PN" "G64"
						( Origin gPackager )
					)
					( objectStatus "U2D1.G64" )
				)
				( pin "rsvd(275)"
					( attribute "PN" "G2"
						( Origin gPackager )
					)
					( objectStatus "U2D1.G2" )
				)
				( pin "rsvd(276)"
					( attribute "PN" "F83"
						( Origin gPackager )
					)
					( objectStatus "U2D1.F83" )
				)
				( pin "rsvd(277)"
					( attribute "PN" "F65"
						( Origin gPackager )
					)
					( objectStatus "U2D1.F65" )
				)
				( pin "rsvd(278)"
					( attribute "PN" "F23"
						( Origin gPackager )
					)
					( objectStatus "U2D1.F23" )
				)
				( pin "rsvd(279)"
					( attribute "PN" "F3"
						( Origin gPackager )
					)
					( objectStatus "U2D1.F3" )
				)
				( pin "rsvd(280)"
					( attribute "PN" "E84"
						( Origin gPackager )
					)
					( objectStatus "U2D1.E84" )
				)
				( pin "rsvd(281)"
					( attribute "PN" "E24"
						( Origin gPackager )
					)
					( objectStatus "U2D1.E24" )
				)
				( pin "rsvd(282)"
					( attribute "PN" "E4"
						( Origin gPackager )
					)
					( objectStatus "U2D1.E4" )
				)
				( pin "rsvd(283)"
					( attribute "PN" "E2"
						( Origin gPackager )
					)
					( objectStatus "U2D1.E2" )
				)
				( pin "rsvd(284)"
					( attribute "PN" "D83"
						( Origin gPackager )
					)
					( objectStatus "U2D1.D83" )
				)
				( pin "rsvd(285)"
					( attribute "PN" "D65"
						( Origin gPackager )
					)
					( objectStatus "U2D1.D65" )
				)
				( pin "rsvd(286)"
					( attribute "PN" "D17"
						( Origin gPackager )
					)
					( objectStatus "U2D1.D17" )
				)
				( pin "rsvd(287)"
					( attribute "PN" "D5"
						( Origin gPackager )
					)
					( objectStatus "U2D1.D5" )
				)
				( pin "rsvd(288)"
					( attribute "PN" "C82"
						( Origin gPackager )
					)
					( objectStatus "U2D1.C82" )
				)
				( pin "rsvd(289)"
					( attribute "PN" "C24"
						( Origin gPackager )
					)
					( objectStatus "U2D1.C24" )
				)
				( pin "rsvd(290)"
					( attribute "PN" "C18"
						( Origin gPackager )
					)
					( objectStatus "U2D1.C18" )
				)
				( pin "rsvd(291)"
					( attribute "PN" "C6"
						( Origin gPackager )
					)
					( objectStatus "U2D1.C6" )
				)
				( pin "rsvd(292)"
					( attribute "PN" "B81"
						( Origin gPackager )
					)
					( objectStatus "U2D1.B81" )
				)
				( pin "rsvd(293)"
					( attribute "PN" "B77"
						( Origin gPackager )
					)
					( objectStatus "U2D1.B77" )
				)
				( pin "rsvd(294)"
					( attribute "PN" "B17"
						( Origin gPackager )
					)
					( objectStatus "U2D1.B17" )
				)
				( pin "rsvd(295)"
					( attribute "PN" "B15"
						( Origin gPackager )
					)
					( objectStatus "U2D1.B15" )
				)
				( pin "rsvd(296)"
					( attribute "PN" "B13"
						( Origin gPackager )
					)
					( objectStatus "U2D1.B13" )
				)
				( pin "rsvd(297)"
					( attribute "CDS_NOT_ON_SYM" "TRUE"
						( Origin gFrontEnd )
					)
				)
				( pin "rsvd(298)"
					( attribute "PN" "B7"
						( Origin gPackager )
					)
					( objectStatus "U2D1.B7" )
				)
				( pin "rsvd(299)"
					( attribute "PN" "B3"
						( Origin gPackager )
					)
					( objectStatus "U2D1.B3" )
				)
				( pin "rsvd(300)"
					( attribute "PN" "A24"
						( Origin gPackager )
					)
					( objectStatus "U2D1.A24" )
				)
				( pin "rsvd(301)"
					( attribute "PN" "A16"
						( Origin gPackager )
					)
					( objectStatus "U2D1.A16" )
				)
				( pin "rsvd(302)"
					( attribute "PN" "A14"
						( Origin gPackager )
					)
					( objectStatus "U2D1.A14" )
				)
				( pin "rsvd(303)"
					( attribute "PN" "A6"
						( Origin gPackager )
					)
					( objectStatus "U2D1.A6" )
				)
				( pin "rsvd(304)"
					( attribute "PN" "A4"
						( Origin gPackager )
					)
					( objectStatus "U2D1.A4" )
				)
				( pin "test_1"
					( attribute "PN" "AF45"
						( Origin gPackager )
					)
					( objectStatus "U2D1.AF45" )
				)
				( pin "test_2"
					( attribute "PN" "AG46"
						( Origin gPackager )
					)
					( objectStatus "U2D1.AG46" )
				)
				( pin "test_3"
					( attribute "PN" "AM13"
						( Origin gPackager )
					)
					( objectStatus "U2D1.AM13" )
				)
				( pin "test_4"
					( attribute "PN" "AN12"
						( Origin gPackager )
					)
					( objectStatus "U2D1.AN12" )
				)
				( pin "test_5"
					( attribute "PN" "AN14"
						( Origin gPackager )
					)
					( objectStatus "U2D1.AN14" )
				)
				( pin "test_11"
					( attribute "PN" "AY13"
						( Origin gPackager )
					)
					( objectStatus "U2D1.AY13" )
				)
			)
			( gate "@baseboard_fab2_lib.baseboard_fab2(sch_1):page56_i173"
				( attribute "CDS_LIB" "mstr_discrete"
					( Origin gPackager )
				)
				( attribute "CDS_LOCATION" "R8P3"
					( Origin gPackager )
				)
				( attribute "CDS_SEC" "1"
					( Origin gPackager )
				)
				( attribute "LOCATION" "R8P3"
					( Origin gFrontEnd )
				)
				( attribute "MATERIAL" "CHIP"
					( Origin gFrontEnd )
				)
				( attribute "PACK_TYPE" "0402"
					( Origin gFrontEnd )
				)
				( attribute "PART_NUMBER" "G21796-047"
					( Origin gFrontEnd )
				)
				( attribute "PHYS_PAGE" "56"
					( Origin gFrontEnd )
				)
				( attribute "ROOM" "CPU1"
					( Origin gFrontEnd )
				)
				( attribute "ROT" "0"
					( Origin gFrontEnd )
				)
				( attribute "SEC" "1"
					( Origin gFrontEnd )
				)
				( attribute "SEC_TYPE" "0402"
					( Origin gFrontEnd )
				)
				( attribute "TOLERANCE" "1%"
					( Origin gFrontEnd )
				)
				( attribute "VALUE" "49.9"
					( Origin gFrontEnd )
				)
				( attribute "VER" "2"
					( Origin gFrontEnd )
				)
				( attribute "WATTAGE" "1/16W"
					( Origin gFrontEnd )
				)
				( attribute "XY" "(-550,2750)"
					( Origin gFrontEnd )
				)
				( attribute "CHIPS_PART_NAME" "RES"
					( Origin gPackager )
				)
				( attribute "CDS_PART_NAME" "RES_0402-49.9,1%,1/16W,CHIP,G2A"
					( Origin gPackager )
				)
				( objectStatus "R8P3" )
				( pin "a"
					( attribute "PN" "1"
						( Origin gPackager )
					)
					( objectStatus "R8P3.1" )
				)
				( pin "b"
					( attribute "PN" "2"
						( Origin gPackager )
					)
					( objectStatus "R8P3.2" )
				)
			)
			( gate "@baseboard_fab2_lib.baseboard_fab2(sch_1):page56_i174"
				( attribute "CDS_LIB" "mstr_discrete"
					( Origin gPackager )
				)
				( attribute "CDS_LOCATION" "R8R1"
					( Origin gPackager )
				)
				( attribute "CDS_SEC" "1"
					( Origin gPackager )
				)
				( attribute "LOCATION" "R8R1"
					( Origin gFrontEnd )
				)
				( attribute "MATERIAL" "CHIP"
					( Origin gFrontEnd )
				)
				( attribute "PACK_TYPE" "0402"
					( Origin gFrontEnd )
				)
				( attribute "PART_NUMBER" "G21796-047"
					( Origin gFrontEnd )
				)
				( attribute "PHYS_PAGE" "56"
					( Origin gFrontEnd )
				)
				( attribute "ROOM" "CPU1"
					( Origin gFrontEnd )
				)
				( attribute "ROT" "0"
					( Origin gFrontEnd )
				)
				( attribute "SEC" "1"
					( Origin gFrontEnd )
				)
				( attribute "SEC_TYPE" "0402"
					( Origin gFrontEnd )
				)
				( attribute "TOLERANCE" "1%"
					( Origin gFrontEnd )
				)
				( attribute "VALUE" "49.9"
					( Origin gFrontEnd )
				)
				( attribute "VER" "2"
					( Origin gFrontEnd )
				)
				( attribute "WATTAGE" "1/16W"
					( Origin gFrontEnd )
				)
				( attribute "XY" "(-275,2750)"
					( Origin gFrontEnd )
				)
				( attribute "CHIPS_PART_NAME" "RES"
					( Origin gPackager )
				)
				( attribute "CDS_PART_NAME" "RES_0402-49.9,1%,1/16W,CHIP,G2A"
					( Origin gPackager )
				)
				( objectStatus "R8R1" )
				( pin "a"
					( attribute "PN" "1"
						( Origin gPackager )
					)
					( objectStatus "R8R1.1" )
				)
				( pin "b"
					( attribute "PN" "2"
						( Origin gPackager )
					)
					( objectStatus "R8R1.2" )
				)
			)
			( gate "@baseboard_fab2_lib.baseboard_fab2(sch_1):page57_i172"
				( attribute "CDS_LIB" "chpset_lib"
					( Origin gPackager )
				)
				( attribute "CDS_LOCATION" "U2D1"
					( Origin gPackager )
				)
				( attribute "CDS_SEC" "3"
					( Origin gPackager )
				)
				( attribute "LOCATION" "U2D1"
					( Origin gFrontEnd )
				)
				( attribute "MATERIAL" "IC"
					( Origin gFrontEnd )
				)
				( attribute "PACK_TYPE" "BGA1"
					( Origin gFrontEnd )
				)
				( attribute "PART_NUMBER" "TBD"
					( Origin gFrontEnd )
				)
				( attribute "PHYS_PAGE" "57"
					( Origin gFrontEnd )
				)
				( attribute "ROT" "0"
					( Origin gFrontEnd )
				)
				( attribute "SEC" "3"
					( Origin gFrontEnd )
				)
				( attribute "SEC_TYPE" "BGA1"
					( Origin gFrontEnd )
				)
				( attribute "VER" "3"
					( Origin gFrontEnd )
				)
				( attribute "XY" "(-4175,2575)"
					( Origin gFrontEnd )
				)
				( attribute "CHIPS_PART_NAME" "SKX_EXT_B"
					( Origin gPackager )
				)
				( attribute "CDS_PART_NAME" "SKX_EXT_B_BGA1-IC,TBD"
					( Origin gPackager )
				)
				( objectStatus "U2D1" )
				( pin "ddr0_act_n"
					( attribute "PN" "J60"
						( Origin gPackager )
					)
					( objectStatus "U2D1.J60" )
				)
				( pin "ddr0_alert_n"
					( attribute "PN" "B61"
						( Origin gPackager )
					)
					( objectStatus "U2D1.B61" )
				)
				( pin "ddr0_ba(0)"
					( attribute "PN" "C52"
						( Origin gPackager )
					)
					( objectStatus "U2D1.C52" )
				)
				( pin "ddr0_ba(1)"
					( attribute "PN" "G54"
						( Origin gPackager )
					)
					( objectStatus "U2D1.G54" )
				)
				( pin "ddr0_bg(0)"
					( attribute "PN" "D61"
						( Origin gPackager )
					)
					( objectStatus "U2D1.D61" )
				)
				( pin "ddr0_bg(1)"
					( attribute "PN" "F63"
						( Origin gPackager )
					)
					( objectStatus "U2D1.F63" )
				)
				( pin "ddr0_cid(2)"
					( attribute "PN" "G46"
						( Origin gPackager )
					)
					( objectStatus "U2D1.G46" )
				)
				( pin "ddr0_cke(0)"
					( attribute "PN" "C62"
						( Origin gPackager )
					)
					( objectStatus "U2D1.C62" )
				)
				( pin "ddr0_cke(1)"
					( attribute "PN" "C64"
						( Origin gPackager )
					)
					( objectStatus "U2D1.C64" )
				)
				( pin "ddr0_cke(2)"
					( attribute "PN" "B63"
						( Origin gPackager )
					)
					( objectStatus "U2D1.B63" )
				)
				( pin "ddr0_cke(3)"
					( attribute "PN" "D63"
						( Origin gPackager )
					)
					( objectStatus "U2D1.D63" )
				)
				( pin "ddr0_clk_dn(0)"
					( attribute "PN" "F55"
						( Origin gPackager )
					)
					( objectStatus "U2D1.F55" )
				)
				( pin "ddr0_clk_dn(1)"
					( attribute "PN" "C54"
						( Origin gPackager )
					)
					( objectStatus "U2D1.C54" )
				)
				( pin "ddr0_clk_dn(2)"
					( attribute "PN" "J56"
						( Origin gPackager )
					)
					( objectStatus "U2D1.J56" )
				)
				( pin "ddr0_clk_dn(3)"
					( attribute "PN" "C56"
						( Origin gPackager )
					)
					( objectStatus "U2D1.C56" )
				)
				( pin "ddr0_clk_dp(0)"
					( attribute "PN" "D55"
						( Origin gPackager )
					)
					( objectStatus "U2D1.D55" )
				)
				( pin "ddr0_clk_dp(1)"
					( attribute "PN" "B55"
						( Origin gPackager )
					)
					( objectStatus "U2D1.B55" )
				)
				( pin "ddr0_clk_dp(2)"
					( attribute "PN" "G56"
						( Origin gPackager )
					)
					( objectStatus "U2D1.G56" )
				)
				( pin "ddr0_clk_dp(3)"
					( attribute "PN" "B57"
						( Origin gPackager )
					)
					( objectStatus "U2D1.B57" )
				)
				( pin "ddr0_cs_n(0)"
					( attribute "PN" "G52"
						( Origin gPackager )
					)
					( objectStatus "U2D1.G52" )
				)
				( pin "ddr0_cs_n(1)"
					( attribute "PN" "F49"
						( Origin gPackager )
					)
					( objectStatus "U2D1.F49" )
				)
				( pin "ddr0_cs_n(2)"
					( attribute "PN" "D47"
						( Origin gPackager )
					)
					( objectStatus "U2D1.D47" )
				)
				( pin "ddr0_cs_n(3)"
					( attribute "PN" "F47"
						( Origin gPackager )
					)
					( objectStatus "U2D1.F47" )
				)
				( pin "ddr0_cs_n(4)"
					( attribute "PN" "B51"
						( Origin gPackager )
					)
					( objectStatus "U2D1.B51" )
				)
				( pin "ddr0_cs_n(5)"
					( attribute "PN" "D49"
						( Origin gPackager )
					)
					( objectStatus "U2D1.D49" )
				)
				( pin "ddr0_cs_n(6)"
					( attribute "PN" "F45"
						( Origin gPackager )
					)
					( objectStatus "U2D1.F45" )
				)
				( pin "ddr0_cs_n(7)"
					( attribute "PN" "K45"
						( Origin gPackager )
					)
					( objectStatus "U2D1.K45" )
				)
				( pin "ddr0_dq(0)"
					( attribute "PN" "AN86"
						( Origin gPackager )
					)
					( objectStatus "U2D1.AN86" )
				)
				( pin "ddr0_dq(1)"
					( attribute "PN" "AN84"
						( Origin gPackager )
					)
					( objectStatus "U2D1.AN84" )
				)
				( pin "ddr0_dq(2)"
					( attribute "PN" "AE86"
						( Origin gPackager )
					)
					( objectStatus "U2D1.AE86" )
				)
				( pin "ddr0_dq(3)"
					( attribute "PN" "AE84"
						( Origin gPackager )
					)
					( objectStatus "U2D1.AE84" )
				)
				( pin "ddr0_dq(4)"
					( attribute "PN" "AR86"
						( Origin gPackager )
					)
					( objectStatus "U2D1.AR86" )
				)
				( pin "ddr0_dq(5)"
					( attribute "PN" "AR84"
						( Origin gPackager )
					)
					( objectStatus "U2D1.AR84" )
				)
				( pin "ddr0_dq(6)"
					( attribute "PN" "AG86"
						( Origin gPackager )
					)
					( objectStatus "U2D1.AG86" )
				)
				( pin "ddr0_dq(7)"
					( attribute "PN" "AG84"
						( Origin gPackager )
					)
					( objectStatus "U2D1.AG84" )
				)
				( pin "ddr0_dq(8)"
					( attribute "PN" "W86"
						( Origin gPackager )
					)
					( objectStatus "U2D1.W86" )
				)
				( pin "ddr0_dq(9)"
					( attribute "PN" "W84"
						( Origin gPackager )
					)
					( objectStatus "U2D1.W84" )
				)
				( pin "ddr0_dq(10)"
					( attribute "PN" "L86"
						( Origin gPackager )
					)
					( objectStatus "U2D1.L86" )
				)
				( pin "ddr0_dq(11)"
					( attribute "PN" "L84"
						( Origin gPackager )
					)
					( objectStatus "U2D1.L84" )
				)
				( pin "ddr0_dq(12)"
					( attribute "PN" "AA86"
						( Origin gPackager )
					)
					( objectStatus "U2D1.AA86" )
				)
				( pin "ddr0_dq(13)"
					( attribute "PN" "AA84"
						( Origin gPackager )
					)
					( objectStatus "U2D1.AA84" )
				)
				( pin "ddr0_dq(14)"
					( attribute "PN" "N86"
						( Origin gPackager )
					)
					( objectStatus "U2D1.N86" )
				)
				( pin "ddr0_dq(15)"
					( attribute "PN" "N84"
						( Origin gPackager )
					)
					( objectStatus "U2D1.N84" )
				)
				( pin "ddr0_dq(16)"
					( attribute "PN" "V81"
						( Origin gPackager )
					)
					( objectStatus "U2D1.V81" )
				)
				( pin "ddr0_dq(17)"
					( attribute "PN" "T79"
						( Origin gPackager )
					)
					( objectStatus "U2D1.T79" )
				)
				( pin "ddr0_dq(18)"
					( attribute "PN" "N82"
						( Origin gPackager )
					)
					( objectStatus "U2D1.N82" )
				)
				( pin "ddr0_dq(19)"
					( attribute "PN" "M81"
						( Origin gPackager )
					)
					( objectStatus "U2D1.M81" )
				)
				( pin "ddr0_dq(20)"
					( attribute "PN" "W80"
						( Origin gPackager )
					)
					( objectStatus "U2D1.W80" )
				)
				( pin "ddr0_dq(21)"
					( attribute "PN" "V79"
						( Origin gPackager )
					)
					( objectStatus "U2D1.V79" )
				)
				( pin "ddr0_dq(22)"
					( attribute "PN" "R82"
						( Origin gPackager )
					)
					( objectStatus "U2D1.R82" )
				)
				( pin "ddr0_dq(23)"
					( attribute "PN" "N80"
						( Origin gPackager )
					)
					( objectStatus "U2D1.N80" )
				)
				( pin "ddr0_dq(24)"
					( attribute "PN" "L76"
						( Origin gPackager )
					)
					( objectStatus "U2D1.L76" )
				)
				( pin "ddr0_dq(25)"
					( attribute "PN" "R76"
						( Origin gPackager )
					)
					( objectStatus "U2D1.R76" )
				)
				( pin "ddr0_dq(26)"
					( attribute "PN" "M73"
						( Origin gPackager )
					)
					( objectStatus "U2D1.M73" )
				)
				( pin "ddr0_dq(27)"
					( attribute "PN" "P73"
						( Origin gPackager )
					)
					( objectStatus "U2D1.P73" )
				)
				( pin "ddr0_dq(28)"
					( attribute "PN" "M77"
						( Origin gPackager )
					)
					( objectStatus "U2D1.M77" )
				)
				( pin "ddr0_dq(29)"
					( attribute "PN" "P77"
						( Origin gPackager )
					)
					( objectStatus "U2D1.P77" )
				)
				( pin "ddr0_dq(30)"
					( attribute "PN" "L74"
						( Origin gPackager )
					)
					( objectStatus "U2D1.L74" )
				)
				( pin "ddr0_dq(31)"
					( attribute "PN" "R74"
						( Origin gPackager )
					)
					( objectStatus "U2D1.R74" )
				)
				( pin "ddr0_dq(32)"
					( attribute "PN" "C42"
						( Origin gPackager )
					)
					( objectStatus "U2D1.C42" )
				)
				( pin "ddr0_dq(33)"
					( attribute "PN" "B41"
						( Origin gPackager )
					)
					( objectStatus "U2D1.B41" )
				)
				( pin "ddr0_dq(34)"
					( attribute "PN" "C38"
						( Origin gPackager )
					)
					( objectStatus "U2D1.C38" )
				)
				( pin "ddr0_dq(35)"
					( attribute "PN" "E38"
						( Origin gPackager )
					)
					( objectStatus "U2D1.E38" )
				)
				( pin "ddr0_dq(36)"
					( attribute "PN" "E42"
						( Origin gPackager )
					)
					( objectStatus "U2D1.E42" )
				)
				( pin "ddr0_dq(37)"
					( attribute "PN" "F41"
						( Origin gPackager )
					)
					( objectStatus "U2D1.F41" )
				)
				( pin "ddr0_dq(38)"
					( attribute "PN" "B39"
						( Origin gPackager )
					)
					( objectStatus "U2D1.B39" )
				)
				( pin "ddr0_dq(39)"
					( attribute "PN" "F39"
						( Origin gPackager )
					)
					( objectStatus "U2D1.F39" )
				)
				( pin "ddr0_dq(40)"
					( attribute "PN" "K37"
						( Origin gPackager )
					)
					( objectStatus "U2D1.K37" )
				)
				( pin "ddr0_dq(41)"
					( attribute "PN" "P37"
						( Origin gPackager )
					)
					( objectStatus "U2D1.P37" )
				)
				( pin "ddr0_dq(42)"
					( attribute "PN" "L34"
						( Origin gPackager )
					)
					( objectStatus "U2D1.L34" )
				)
				( pin "ddr0_dq(43)"
					( attribute "PN" "N34"
						( Origin gPackager )
					)
					( objectStatus "U2D1.N34" )
				)
				( pin "ddr0_dq(44)"
					( attribute "PN" "L38"
						( Origin gPackager )
					)
					( objectStatus "U2D1.L38" )
				)
				( pin "ddr0_dq(45)"
					( attribute "PN" "N38"
						( Origin gPackager )
					)
					( objectStatus "U2D1.N38" )
				)
				( pin "ddr0_dq(46)"
					( attribute "PN" "K35"
						( Origin gPackager )
					)
					( objectStatus "U2D1.K35" )
				)
				( pin "ddr0_dq(47)"
					( attribute "PN" "P35"
						( Origin gPackager )
					)
					( objectStatus "U2D1.P35" )
				)
				( pin "ddr0_dq(48)"
					( attribute "PN" "K31"
						( Origin gPackager )
					)
					( objectStatus "U2D1.K31" )
				)
				( pin "ddr0_dq(49)"
					( attribute "PN" "P31"
						( Origin gPackager )
					)
					( objectStatus "U2D1.P31" )
				)
				( pin "ddr0_dq(50)"
					( attribute "PN" "L28"
						( Origin gPackager )
					)
					( objectStatus "U2D1.L28" )
				)
				( pin "ddr0_dq(51)"
					( attribute "PN" "N28"
						( Origin gPackager )
					)
					( objectStatus "U2D1.N28" )
				)
				( pin "ddr0_dq(52)"
					( attribute "PN" "L32"
						( Origin gPackager )
					)
					( objectStatus "U2D1.L32" )
				)
				( pin "ddr0_dq(53)"
					( attribute "PN" "N32"
						( Origin gPackager )
					)
					( objectStatus "U2D1.N32" )
				)
				( pin "ddr0_dq(54)"
					( attribute "PN" "K29"
						( Origin gPackager )
					)
					( objectStatus "U2D1.K29" )
				)
				( pin "ddr0_dq(55)"
					( attribute "PN" "P29"
						( Origin gPackager )
					)
					( objectStatus "U2D1.P29" )
				)
				( pin "ddr0_dq(56)"
					( attribute "PN" "K25"
						( Origin gPackager )
					)
					( objectStatus "U2D1.K25" )
				)
				( pin "ddr0_dq(57)"
					( attribute "PN" "P25"
						( Origin gPackager )
					)
					( objectStatus "U2D1.P25" )
				)
				( pin "ddr0_dq(58)"
					( attribute "PN" "P23"
						( Origin gPackager )
					)
					( objectStatus "U2D1.P23" )
				)
				( pin "ddr0_dq(59)"
					( attribute "PN" "T23"
						( Origin gPackager )
					)
					( objectStatus "U2D1.T23" )
				)
				( pin "ddr0_dq(60)"
					( attribute "PN" "L26"
						( Origin gPackager )
					)
					( objectStatus "U2D1.L26" )
				)
				( pin "ddr0_dq(61)"
					( attribute "PN" "N26"
						( Origin gPackager )
					)
					( objectStatus "U2D1.N26" )
				)
				( pin "ddr0_dq(62)"
					( attribute "PN" "H23"
						( Origin gPackager )
					)
					( objectStatus "U2D1.H23" )
				)
				( pin "ddr0_dq(63)"
					( attribute "PN" "K23"
						( Origin gPackager )
					)
					( objectStatus "U2D1.K23" )
				)
				( pin "ddr0_dqs_dn(0)"
					( attribute "PN" "AJ84"
						( Origin gPackager )
					)
					( objectStatus "U2D1.AJ84" )
				)
				( pin "ddr0_dqs_dn(1)"
					( attribute "PN" "R84"
						( Origin gPackager )
					)
					( objectStatus "U2D1.R84" )
				)
				( pin "ddr0_dqs_dn(2)"
					( attribute "PN" "P79"
						( Origin gPackager )
					)
					( objectStatus "U2D1.P79" )
				)
				( pin "ddr0_dqs_dn(3)"
					( attribute "PN" "T75"
						( Origin gPackager )
					)
					( objectStatus "U2D1.T75" )
				)
				( pin "ddr0_dqs_dn(4)"
					( attribute "PN" "G40"
						( Origin gPackager )
					)
					( objectStatus "U2D1.G40" )
				)
				( pin "ddr0_dqs_dn(5)"
					( attribute "PN" "R36"
						( Origin gPackager )
					)
					( objectStatus "U2D1.R36" )
				)
				( pin "ddr0_dqs_dn(6)"
					( attribute "PN" "R30"
						( Origin gPackager )
					)
					( objectStatus "U2D1.R30" )
				)
				( pin "ddr0_dqs_dn(7)"
					( attribute "PN" "N24"
						( Origin gPackager )
					)
					( objectStatus "U2D1.N24" )
				)
				( pin "ddr0_dqs_dn(8)"
					( attribute "PN" "AH67"
						( Origin gPackager )
					)
					( objectStatus "U2D1.AH67" )
				)
				( pin "ddr0_dqs_dn(9)"
					( attribute "PN" "AL84"
						( Origin gPackager )
					)
					( objectStatus "U2D1.AL84" )
				)
				( pin "ddr0_dqs_dn(10)"
					( attribute "PN" "U84"
						( Origin gPackager )
					)
					( objectStatus "U2D1.U84" )
				)
				( pin "ddr0_dqs_dn(11)"
					( attribute "PN" "U82"
						( Origin gPackager )
					)
					( objectStatus "U2D1.U82" )
				)
				( pin "ddr0_dqs_dn(12)"
					( attribute "PN" "K75"
						( Origin gPackager )
					)
					( objectStatus "U2D1.K75" )
				)
				( pin "ddr0_dqs_dn(13)"
					( attribute "PN" "A40"
						( Origin gPackager )
					)
					( objectStatus "U2D1.A40" )
				)
				( pin "ddr0_dqs_dn(14)"
					( attribute "PN" "J36"
						( Origin gPackager )
					)
					( objectStatus "U2D1.J36" )
				)
				( pin "ddr0_dqs_dn(15)"
					( attribute "PN" "J30"
						( Origin gPackager )
					)
					( objectStatus "U2D1.J30" )
				)
				( pin "ddr0_dqs_dn(16)"
					( attribute "PN" "J24"
						( Origin gPackager )
					)
					( objectStatus "U2D1.J24" )
				)
				( pin "ddr0_dqs_dn(17)"
					( attribute "PN" "AB67"
						( Origin gPackager )
					)
					( objectStatus "U2D1.AB67" )
				)
				( pin "ddr0_dqs_dp(0)"
					( attribute "PN" "AH85"
						( Origin gPackager )
					)
					( objectStatus "U2D1.AH85" )
				)
				( pin "ddr0_dqs_dp(1)"
					( attribute "PN" "P85"
						( Origin gPackager )
					)
					( objectStatus "U2D1.P85" )
				)
				( pin "ddr0_dqs_dp(2)"
					( attribute "PN" "R80"
						( Origin gPackager )
					)
					( objectStatus "U2D1.R80" )
				)
				( pin "ddr0_dqs_dp(3)"
					( attribute "PN" "P75"
						( Origin gPackager )
					)
					( objectStatus "U2D1.P75" )
				)
				( pin "ddr0_dqs_dp(4)"
					( attribute "PN" "E40"
						( Origin gPackager )
					)
					( objectStatus "U2D1.E40" )
				)
				( pin "ddr0_dqs_dp(5)"
					( attribute "PN" "N36"
						( Origin gPackager )
					)
					( objectStatus "U2D1.N36" )
				)
				( pin "ddr0_dqs_dp(6)"
					( attribute "PN" "N30"
						( Origin gPackager )
					)
					( objectStatus "U2D1.N30" )
				)
				( pin "ddr0_dqs_dp(7)"
					( attribute "PN" "R24"
						( Origin gPackager )
					)
					( objectStatus "U2D1.R24" )
				)
				( pin "ddr0_dqs_dp(8)"
					( attribute "PN" "AF67"
						( Origin gPackager )
					)
					( objectStatus "U2D1.AF67" )
				)
				( pin "ddr0_dqs_dp(9)"
					( attribute "PN" "AM85"
						( Origin gPackager )
					)
					( objectStatus "U2D1.AM85" )
				)
				( pin "ddr0_dqs_dp(10)"
					( attribute "PN" "V85"
						( Origin gPackager )
					)
					( objectStatus "U2D1.V85" )
				)
				( pin "ddr0_dqs_dp(11)"
					( attribute "PN" "T81"
						( Origin gPackager )
					)
					( objectStatus "U2D1.T81" )
				)
				( pin "ddr0_dqs_dp(12)"
					( attribute "PN" "M75"
						( Origin gPackager )
					)
					( objectStatus "U2D1.M75" )
				)
				( pin "ddr0_dqs_dp(13)"
					( attribute "PN" "C40"
						( Origin gPackager )
					)
					( objectStatus "U2D1.C40" )
				)
				( pin "ddr0_dqs_dp(14)"
					( attribute "PN" "L36"
						( Origin gPackager )
					)
					( objectStatus "U2D1.L36" )
				)
				( pin "ddr0_dqs_dp(15)"
					( attribute "PN" "L30"
						( Origin gPackager )
					)
					( objectStatus "U2D1.L30" )
				)
				( pin "ddr0_dqs_dp(16)"
					( attribute "PN" "L24"
						( Origin gPackager )
					)
					( objectStatus "U2D1.L24" )
				)
				( pin "ddr0_dqs_dp(17)"
					( attribute "PN" "AD67"
						( Origin gPackager )
					)
					( objectStatus "U2D1.AD67" )
				)
				( pin "ddr0_ecc(0)"
					( attribute "PN" "AC68"
						( Origin gPackager )
					)
					( objectStatus "U2D1.AC68" )
				)
				( pin "ddr0_ecc(1)"
					( attribute "PN" "AG68"
						( Origin gPackager )
					)
					( objectStatus "U2D1.AG68" )
				)
				( pin "ddr0_ecc(2)"
					( attribute "PN" "AD65"
						( Origin gPackager )
					)
					( objectStatus "U2D1.AD65" )
				)
				( pin "ddr0_ecc(3)"
					( attribute "PN" "AF65"
						( Origin gPackager )
					)
					( objectStatus "U2D1.AF65" )
				)
				( pin "ddr0_ecc(4)"
					( attribute "PN" "AD69"
						( Origin gPackager )
					)
					( objectStatus "U2D1.AD69" )
				)
				( pin "ddr0_ecc(5)"
					( attribute "PN" "AF69"
						( Origin gPackager )
					)
					( objectStatus "U2D1.AF69" )
				)
				( pin "ddr0_ecc(6)"
					( attribute "PN" "AC66"
						( Origin gPackager )
					)
					( objectStatus "U2D1.AC66" )
				)
				( pin "ddr0_ecc(7)"
					( attribute "PN" "AG66"
						( Origin gPackager )
					)
					( objectStatus "U2D1.AG66" )
				)
				( pin "ddr0_ma(0)"
					( attribute "PN" "F53"
						( Origin gPackager )
					)
					( objectStatus "U2D1.F53" )
				)
				( pin "ddr0_ma(1)"
					( attribute "PN" "F57"
						( Origin gPackager )
					)
					( objectStatus "U2D1.F57" )
				)
				( pin "ddr0_ma(2)"
					( attribute "PN" "D57"
						( Origin gPackager )
					)
					( objectStatus "U2D1.D57" )
				)
				( pin "ddr0_ma(3)"
					( attribute "PN" "C58"
						( Origin gPackager )
					)
					( objectStatus "U2D1.C58" )
				)
				( pin "ddr0_ma(4)"
					( attribute "PN" "G58"
						( Origin gPackager )
					)
					( objectStatus "U2D1.G58" )
				)
				( pin "ddr0_ma(5)"
					( attribute "PN" "F59"
						( Origin gPackager )
					)
					( objectStatus "U2D1.F59" )
				)
				( pin "ddr0_ma(6)"
					( attribute "PN" "D59"
						( Origin gPackager )
					)
					( objectStatus "U2D1.D59" )
				)
				( pin "ddr0_ma(7)"
					( attribute "PN" "G60"
						( Origin gPackager )
					)
					( objectStatus "U2D1.G60" )
				)
				( pin "ddr0_ma(8)"
					( attribute "PN" "C60"
						( Origin gPackager )
					)
					( objectStatus "U2D1.C60" )
				)
				( pin "ddr0_ma(9)"
					( attribute "PN" "F61"
						( Origin gPackager )
					)
					( objectStatus "U2D1.F61" )
				)
				( pin "ddr0_ma(10)"
					( attribute "PN" "J54"
						( Origin gPackager )
					)
					( objectStatus "U2D1.J54" )
				)
				( pin "ddr0_ma(11)"
					( attribute "PN" "G62"
						( Origin gPackager )
					)
					( objectStatus "U2D1.G62" )
				)
				( pin "ddr0_ma(12)"
					( attribute "PN" "J64"
						( Origin gPackager )
					)
					( objectStatus "U2D1.J64" )
				)
				( pin "ddr0_ma(13)"
					( attribute "PN" "J48"
						( Origin gPackager )
					)
					( objectStatus "U2D1.J48" )
				)
				( pin "ddr0_ma(14)"
					( attribute "PN" "F51"
						( Origin gPackager )
					)
					( objectStatus "U2D1.F51" )
				)
				( pin "ddr0_ma(15)"
					( attribute "PN" "K49"
						( Origin gPackager )
					)
					( objectStatus "U2D1.K49" )
				)
				( pin "ddr0_ma(16)"
					( attribute "PN" "D51"
						( Origin gPackager )
					)
					( objectStatus "U2D1.D51" )
				)
				( pin "ddr0_ma(17)"
					( attribute "PN" "K47"
						( Origin gPackager )
					)
					( objectStatus "U2D1.K47" )
				)
				( pin "ddr0_odt(0)"
					( attribute "PN" "C50"
						( Origin gPackager )
					)
					( objectStatus "U2D1.C50" )
				)
				( pin "ddr0_odt(1)"
					( attribute "PN" "C48"
						( Origin gPackager )
					)
					( objectStatus "U2D1.C48" )
				)
				( pin "ddr0_odt(2)"
					( attribute "PN" "G50"
						( Origin gPackager )
					)
					( objectStatus "U2D1.G50" )
				)
				( pin "ddr0_odt(3)"
					( attribute "PN" "G48"
						( Origin gPackager )
					)
					( objectStatus "U2D1.G48" )
				)
				( pin "ddr0_par"
					( attribute "PN" "D53"
						( Origin gPackager )
					)
					( objectStatus "U2D1.D53" )
				)
			)
			( gate "@baseboard_fab2_lib.baseboard_fab2(sch_1):page58_i172"
				( attribute "CDS_LIB" "chpset_lib"
					( Origin gPackager )
				)
				( attribute "CDS_LOCATION" "U2D1"
					( Origin gPackager )
				)
				( attribute "CDS_SEC" "4"
					( Origin gPackager )
				)
				( attribute "LOCATION" "U2D1"
					( Origin gFrontEnd )
				)
				( attribute "MATERIAL" "IC"
					( Origin gFrontEnd )
				)
				( attribute "PACK_TYPE" "BGA1"
					( Origin gFrontEnd )
				)
				( attribute "PART_NUMBER" "TBD"
					( Origin gFrontEnd )
				)
				( attribute "PHYS_PAGE" "58"
					( Origin gFrontEnd )
				)
				( attribute "ROT" "0"
					( Origin gFrontEnd )
				)
				( attribute "SEC" "4"
					( Origin gFrontEnd )
				)
				( attribute "SEC_TYPE" "BGA1"
					( Origin gFrontEnd )
				)
				( attribute "VER" "4"
					( Origin gFrontEnd )
				)
				( attribute "XY" "(-4200,2575)"
					( Origin gFrontEnd )
				)
				( attribute "CHIPS_PART_NAME" "SKX_EXT_B"
					( Origin gPackager )
				)
				( attribute "CDS_PART_NAME" "SKX_EXT_B_BGA1-IC,TBD"
					( Origin gPackager )
				)
				( objectStatus "U2D1" )
				( pin "ddr1_act_n"
					( attribute "PN" "T63"
						( Origin gPackager )
					)
					( objectStatus "U2D1.T63" )
				)
				( pin "ddr1_alert_n"
					( attribute "PN" "W62"
						( Origin gPackager )
					)
					( objectStatus "U2D1.W62" )
				)
				( pin "ddr1_ba(0)"
					( attribute "PN" "T53"
						( Origin gPackager )
					)
					( objectStatus "U2D1.T53" )
				)
				( pin "ddr1_ba(1)"
					( attribute "PN" "K55"
						( Origin gPackager )
					)
					( objectStatus "U2D1.K55" )
				)
				( pin "ddr1_bg(0)"
					( attribute "PN" "M61"
						( Origin gPackager )
					)
					( objectStatus "U2D1.M61" )
				)
				( pin "ddr1_bg(1)"
					( attribute "PN" "N60"
						( Origin gPackager )
					)
					( objectStatus "U2D1.N60" )
				)
				( pin "ddr1_cid(2)"
					( attribute "PN" "M47"
						( Origin gPackager )
					)
					( objectStatus "U2D1.M47" )
				)
				( pin "ddr1_cke(0)"
					( attribute "PN" "N62"
						( Origin gPackager )
					)
					( objectStatus "U2D1.N62" )
				)
				( pin "ddr1_cke(1)"
					( attribute "PN" "R64"
						( Origin gPackager )
					)
					( objectStatus "U2D1.R64" )
				)
				( pin "ddr1_cke(2)"
					( attribute "PN" "K63"
						( Origin gPackager )
					)
					( objectStatus "U2D1.K63" )
				)
				( pin "ddr1_cke(3)"
					( attribute "PN" "L64"
						( Origin gPackager )
					)
					( objectStatus "U2D1.L64" )
				)
				( pin "ddr1_clk_dn(0)"
					( attribute "PN" "M53"
						( Origin gPackager )
					)
					( objectStatus "U2D1.M53" )
				)
				( pin "ddr1_clk_dn(1)"
					( attribute "PN" "R54"
						( Origin gPackager )
					)
					( objectStatus "U2D1.R54" )
				)
				( pin "ddr1_clk_dn(2)"
					( attribute "PN" "N56"
						( Origin gPackager )
					)
					( objectStatus "U2D1.N56" )
				)
				( pin "ddr1_clk_dn(3)"
					( attribute "PN" "R56"
						( Origin gPackager )
					)
					( objectStatus "U2D1.R56" )
				)
				( pin "ddr1_clk_dp(0)"
					( attribute "PN" "N54"
						( Origin gPackager )
					)
					( objectStatus "U2D1.N54" )
				)
				( pin "ddr1_clk_dp(1)"
					( attribute "PN" "T55"
						( Origin gPackager )
					)
					( objectStatus "U2D1.T55" )
				)
				( pin "ddr1_clk_dp(2)"
					( attribute "PN" "M57"
						( Origin gPackager )
					)
					( objectStatus "U2D1.M57" )
				)
				( pin "ddr1_clk_dp(3)"
					( attribute "PN" "T57"
						( Origin gPackager )
					)
					( objectStatus "U2D1.T57" )
				)
				( pin "ddr1_cs_n(0)"
					( attribute "PN" "K51"
						( Origin gPackager )
					)
					( objectStatus "U2D1.K51" )
				)
				( pin "ddr1_cs_n(1)"
					( attribute "PN" "R50"
						( Origin gPackager )
					)
					( objectStatus "U2D1.R50" )
				)
				( pin "ddr1_cs_n(2)"
					( attribute "PN" "N46"
						( Origin gPackager )
					)
					( objectStatus "U2D1.N46" )
				)
				( pin "ddr1_cs_n(3)"
					( attribute "PN" "V47"
						( Origin gPackager )
					)
					( objectStatus "U2D1.V47" )
				)
				( pin "ddr1_cs_n(4)"
					( attribute "PN" "J50"
						( Origin gPackager )
					)
					( objectStatus "U2D1.J50" )
				)
				( pin "ddr1_cs_n(5)"
					( attribute "PN" "T49"
						( Origin gPackager )
					)
					( objectStatus "U2D1.T49" )
				)
				( pin "ddr1_cs_n(6)"
					( attribute "PN" "M45"
						( Origin gPackager )
					)
					( objectStatus "U2D1.M45" )
				)
				( pin "ddr1_cs_n(7)"
					( attribute "PN" "R46"
						( Origin gPackager )
					)
					( objectStatus "U2D1.R46" )
				)
				( pin "ddr1_dq(0)"
					( attribute "PN" "AV81"
						( Origin gPackager )
					)
					( objectStatus "U2D1.AV81" )
				)
				( pin "ddr1_dq(1)"
					( attribute "PN" "AT79"
						( Origin gPackager )
					)
					( objectStatus "U2D1.AT79" )
				)
				( pin "ddr1_dq(2)"
					( attribute "PN" "AN82"
						( Origin gPackager )
					)
					( objectStatus "U2D1.AN82" )
				)
				( pin "ddr1_dq(3)"
					( attribute "PN" "AM81"
						( Origin gPackager )
					)
					( objectStatus "U2D1.AM81" )
				)
				( pin "ddr1_dq(4)"
					( attribute "PN" "AW80"
						( Origin gPackager )
					)
					( objectStatus "U2D1.AW80" )
				)
				( pin "ddr1_dq(5)"
					( attribute "PN" "AV79"
						( Origin gPackager )
					)
					( objectStatus "U2D1.AV79" )
				)
				( pin "ddr1_dq(6)"
					( attribute "PN" "AR82"
						( Origin gPackager )
					)
					( objectStatus "U2D1.AR82" )
				)
				( pin "ddr1_dq(7)"
					( attribute "PN" "AN80"
						( Origin gPackager )
					)
					( objectStatus "U2D1.AN80" )
				)
				( pin "ddr1_dq(8)"
					( attribute "PN" "AH81"
						( Origin gPackager )
					)
					( objectStatus "U2D1.AH81" )
				)
				( pin "ddr1_dq(9)"
					( attribute "PN" "AF79"
						( Origin gPackager )
					)
					( objectStatus "U2D1.AF79" )
				)
				( pin "ddr1_dq(10)"
					( attribute "PN" "AC82"
						( Origin gPackager )
					)
					( objectStatus "U2D1.AC82" )
				)
				( pin "ddr1_dq(11)"
					( attribute "PN" "AB81"
						( Origin gPackager )
					)
					( objectStatus "U2D1.AB81" )
				)
				( pin "ddr1_dq(12)"
					( attribute "PN" "AJ80"
						( Origin gPackager )
					)
					( objectStatus "U2D1.AJ80" )
				)
				( pin "ddr1_dq(13)"
					( attribute "PN" "AH79"
						( Origin gPackager )
					)
					( objectStatus "U2D1.AH79" )
				)
				( pin "ddr1_dq(14)"
					( attribute "PN" "AE82"
						( Origin gPackager )
					)
					( objectStatus "U2D1.AE82" )
				)
				( pin "ddr1_dq(15)"
					( attribute "PN" "AC80"
						( Origin gPackager )
					)
					( objectStatus "U2D1.AC80" )
				)
				( pin "ddr1_dq(16)"
					( attribute "PN" "E80"
						( Origin gPackager )
					)
					( objectStatus "U2D1.E80" )
				)
				( pin "ddr1_dq(17)"
					( attribute "PN" "J80"
						( Origin gPackager )
					)
					( objectStatus "U2D1.J80" )
				)
				( pin "ddr1_dq(18)"
					( attribute "PN" "F77"
						( Origin gPackager )
					)
					( objectStatus "U2D1.F77" )
				)
				( pin "ddr1_dq(19)"
					( attribute "PN" "H77"
						( Origin gPackager )
					)
					( objectStatus "U2D1.H77" )
				)
				( pin "ddr1_dq(20)"
					( attribute "PN" "F81"
						( Origin gPackager )
					)
					( objectStatus "U2D1.F81" )
				)
				( pin "ddr1_dq(21)"
					( attribute "PN" "H81"
						( Origin gPackager )
					)
					( objectStatus "U2D1.H81" )
				)
				( pin "ddr1_dq(22)"
					( attribute "PN" "E78"
						( Origin gPackager )
					)
					( objectStatus "U2D1.E78" )
				)
				( pin "ddr1_dq(23)"
					( attribute "PN" "J78"
						( Origin gPackager )
					)
					( objectStatus "U2D1.J78" )
				)
				( pin "ddr1_dq(24)"
					( attribute "PN" "D75"
						( Origin gPackager )
					)
					( objectStatus "U2D1.D75" )
				)
				( pin "ddr1_dq(25)"
					( attribute "PN" "C74"
						( Origin gPackager )
					)
					( objectStatus "U2D1.C74" )
				)
				( pin "ddr1_dq(26)"
					( attribute "PN" "D71"
						( Origin gPackager )
					)
					( objectStatus "U2D1.D71" )
				)
				( pin "ddr1_dq(27)"
					( attribute "PN" "F71"
						( Origin gPackager )
					)
					( objectStatus "U2D1.F71" )
				)
				( pin "ddr1_dq(28)"
					( attribute "PN" "F75"
						( Origin gPackager )
					)
					( objectStatus "U2D1.F75" )
				)
				( pin "ddr1_dq(29)"
					( attribute "PN" "G74"
						( Origin gPackager )
					)
					( objectStatus "U2D1.G74" )
				)
				( pin "ddr1_dq(30)"
					( attribute "PN" "C72"
						( Origin gPackager )
					)
					( objectStatus "U2D1.C72" )
				)
				( pin "ddr1_dq(31)"
					( attribute "PN" "G72"
						( Origin gPackager )
					)
					( objectStatus "U2D1.G72" )
				)
				( pin "ddr1_dq(32)"
					( attribute "PN" "K43"
						( Origin gPackager )
					)
					( objectStatus "U2D1.K43" )
				)
				( pin "ddr1_dq(33)"
					( attribute "PN" "H43"
						( Origin gPackager )
					)
					( objectStatus "U2D1.H43" )
				)
				( pin "ddr1_dq(34)"
					( attribute "PN" "L40"
						( Origin gPackager )
					)
					( objectStatus "U2D1.L40" )
				)
				( pin "ddr1_dq(35)"
					( attribute "PN" "N40"
						( Origin gPackager )
					)
					( objectStatus "U2D1.N40" )
				)
				( pin "ddr1_dq(36)"
					( attribute "PN" "P43"
						( Origin gPackager )
					)
					( objectStatus "U2D1.P43" )
				)
				( pin "ddr1_dq(37)"
					( attribute "PN" "T43"
						( Origin gPackager )
					)
					( objectStatus "U2D1.T43" )
				)
				( pin "ddr1_dq(38)"
					( attribute "PN" "K41"
						( Origin gPackager )
					)
					( objectStatus "U2D1.K41" )
				)
				( pin "ddr1_dq(39)"
					( attribute "PN" "P41"
						( Origin gPackager )
					)
					( objectStatus "U2D1.P41" )
				)
				( pin "ddr1_dq(40)"
					( attribute "PN" "C36"
						( Origin gPackager )
					)
					( objectStatus "U2D1.C36" )
				)
				( pin "ddr1_dq(41)"
					( attribute "PN" "B35"
						( Origin gPackager )
					)
					( objectStatus "U2D1.B35" )
				)
				( pin "ddr1_dq(42)"
					( attribute "PN" "C32"
						( Origin gPackager )
					)
					( objectStatus "U2D1.C32" )
				)
				( pin "ddr1_dq(43)"
					( attribute "PN" "E32"
						( Origin gPackager )
					)
					( objectStatus "U2D1.E32" )
				)
				( pin "ddr1_dq(44)"
					( attribute "PN" "E36"
						( Origin gPackager )
					)
					( objectStatus "U2D1.E36" )
				)
				( pin "ddr1_dq(45)"
					( attribute "PN" "F35"
						( Origin gPackager )
					)
					( objectStatus "U2D1.F35" )
				)
				( pin "ddr1_dq(46)"
					( attribute "PN" "B33"
						( Origin gPackager )
					)
					( objectStatus "U2D1.B33" )
				)
				( pin "ddr1_dq(47)"
					( attribute "PN" "F33"
						( Origin gPackager )
					)
					( objectStatus "U2D1.F33" )
				)
				( pin "ddr1_dq(48)"
					( attribute "PN" "C30"
						( Origin gPackager )
					)
					( objectStatus "U2D1.C30" )
				)
				( pin "ddr1_dq(49)"
					( attribute "PN" "B29"
						( Origin gPackager )
					)
					( objectStatus "U2D1.B29" )
				)
				( pin "ddr1_dq(50)"
					( attribute "PN" "C26"
						( Origin gPackager )
					)
					( objectStatus "U2D1.C26" )
				)
				( pin "ddr1_dq(51)"
					( attribute "PN" "E26"
						( Origin gPackager )
					)
					( objectStatus "U2D1.E26" )
				)
				( pin "ddr1_dq(52)"
					( attribute "PN" "E30"
						( Origin gPackager )
					)
					( objectStatus "U2D1.E30" )
				)
				( pin "ddr1_dq(53)"
					( attribute "PN" "F29"
						( Origin gPackager )
					)
					( objectStatus "U2D1.F29" )
				)
				( pin "ddr1_dq(54)"
					( attribute "PN" "B27"
						( Origin gPackager )
					)
					( objectStatus "U2D1.B27" )
				)
				( pin "ddr1_dq(55)"
					( attribute "PN" "F27"
						( Origin gPackager )
					)
					( objectStatus "U2D1.F27" )
				)
				( pin "ddr1_dq(56)"
					( attribute "PN" "U28"
						( Origin gPackager )
					)
					( objectStatus "U2D1.U28" )
				)
				( pin "ddr1_dq(57)"
					( attribute "PN" "AA28"
						( Origin gPackager )
					)
					( objectStatus "U2D1.AA28" )
				)
				( pin "ddr1_dq(58)"
					( attribute "PN" "V25"
						( Origin gPackager )
					)
					( objectStatus "U2D1.V25" )
				)
				( pin "ddr1_dq(59)"
					( attribute "PN" "Y25"
						( Origin gPackager )
					)
					( objectStatus "U2D1.Y25" )
				)
				( pin "ddr1_dq(60)"
					( attribute "PN" "V29"
						( Origin gPackager )
					)
					( objectStatus "U2D1.V29" )
				)
				( pin "ddr1_dq(61)"
					( attribute "PN" "Y29"
						( Origin gPackager )
					)
					( objectStatus "U2D1.Y29" )
				)
				( pin "ddr1_dq(62)"
					( attribute "PN" "U26"
						( Origin gPackager )
					)
					( objectStatus "U2D1.U26" )
				)
				( pin "ddr1_dq(63)"
					( attribute "PN" "AA26"
						( Origin gPackager )
					)
					( objectStatus "U2D1.AA26" )
				)
				( pin "ddr1_dqs_dn(0)"
					( attribute "PN" "AP79"
						( Origin gPackager )
					)
					( objectStatus "U2D1.AP79" )
				)
				( pin "ddr1_dqs_dn(1)"
					( attribute "PN" "AD79"
						( Origin gPackager )
					)
					( objectStatus "U2D1.AD79" )
				)
				( pin "ddr1_dqs_dn(2)"
					( attribute "PN" "K79"
						( Origin gPackager )
					)
					( objectStatus "U2D1.K79" )
				)
				( pin "ddr1_dqs_dn(3)"
					( attribute "PN" "H73"
						( Origin gPackager )
					)
					( objectStatus "U2D1.H73" )
				)
				( pin "ddr1_dqs_dn(4)"
					( attribute "PN" "N42"
						( Origin gPackager )
					)
					( objectStatus "U2D1.N42" )
				)
				( pin "ddr1_dqs_dn(5)"
					( attribute "PN" "G34"
						( Origin gPackager )
					)
					( objectStatus "U2D1.G34" )
				)
				( pin "ddr1_dqs_dn(6)"
					( attribute "PN" "G28"
						( Origin gPackager )
					)
					( objectStatus "U2D1.G28" )
				)
				( pin "ddr1_dqs_dn(7)"
					( attribute "PN" "AB27"
						( Origin gPackager )
					)
					( objectStatus "U2D1.AB27" )
				)
				( pin "ddr1_dqs_dn(8)"
					( attribute "PN" "N68"
						( Origin gPackager )
					)
					( objectStatus "U2D1.N68" )
				)
				( pin "ddr1_dqs_dn(9)"
					( attribute "PN" "AU82"
						( Origin gPackager )
					)
					( objectStatus "U2D1.AU82" )
				)
				( pin "ddr1_dqs_dn(10)"
					( attribute "PN" "AG82"
						( Origin gPackager )
					)
					( objectStatus "U2D1.AG82" )
				)
				( pin "ddr1_dqs_dn(11)"
					( attribute "PN" "D79"
						( Origin gPackager )
					)
					( objectStatus "U2D1.D79" )
				)
				( pin "ddr1_dqs_dn(12)"
					( attribute "PN" "B73"
						( Origin gPackager )
					)
					( objectStatus "U2D1.B73" )
				)
				( pin "ddr1_dqs_dn(13)"
					( attribute "PN" "J42"
						( Origin gPackager )
					)
					( objectStatus "U2D1.J42" )
				)
				( pin "ddr1_dqs_dn(14)"
					( attribute "PN" "A34"
						( Origin gPackager )
					)
					( objectStatus "U2D1.A34" )
				)
				( pin "ddr1_dqs_dn(15)"
					( attribute "PN" "A28"
						( Origin gPackager )
					)
					( objectStatus "U2D1.A28" )
				)
				( pin "ddr1_dqs_dn(16)"
					( attribute "PN" "T27"
						( Origin gPackager )
					)
					( objectStatus "U2D1.T27" )
				)
				( pin "ddr1_dqs_dn(17)"
					( attribute "PN" "G68"
						( Origin gPackager )
					)
					( objectStatus "U2D1.G68" )
				)
				( pin "ddr1_dqs_dp(0)"
					( attribute "PN" "AR80"
						( Origin gPackager )
					)
					( objectStatus "U2D1.AR80" )
				)
				( pin "ddr1_dqs_dp(1)"
					( attribute "PN" "AE80"
						( Origin gPackager )
					)
					( objectStatus "U2D1.AE80" )
				)
				( pin "ddr1_dqs_dp(2)"
					( attribute "PN" "H79"
						( Origin gPackager )
					)
					( objectStatus "U2D1.H79" )
				)
				( pin "ddr1_dqs_dp(3)"
					( attribute "PN" "F73"
						( Origin gPackager )
					)
					( objectStatus "U2D1.F73" )
				)
				( pin "ddr1_dqs_dp(4)"
					( attribute "PN" "R42"
						( Origin gPackager )
					)
					( objectStatus "U2D1.R42" )
				)
				( pin "ddr1_dqs_dp(5)"
					( attribute "PN" "E34"
						( Origin gPackager )
					)
					( objectStatus "U2D1.E34" )
				)
				( pin "ddr1_dqs_dp(6)"
					( attribute "PN" "E28"
						( Origin gPackager )
					)
					( objectStatus "U2D1.E28" )
				)
				( pin "ddr1_dqs_dp(7)"
					( attribute "PN" "Y27"
						( Origin gPackager )
					)
					( objectStatus "U2D1.Y27" )
				)
				( pin "ddr1_dqs_dp(8)"
					( attribute "PN" "L68"
						( Origin gPackager )
					)
					( objectStatus "U2D1.L68" )
				)
				( pin "ddr1_dqs_dp(9)"
					( attribute "PN" "AT81"
						( Origin gPackager )
					)
					( objectStatus "U2D1.AT81" )
				)
				( pin "ddr1_dqs_dp(10)"
					( attribute "PN" "AF81"
						( Origin gPackager )
					)
					( objectStatus "U2D1.AF81" )
				)
				( pin "ddr1_dqs_dp(11)"
					( attribute "PN" "F79"
						( Origin gPackager )
					)
					( objectStatus "U2D1.F79" )
				)
				( pin "ddr1_dqs_dp(12)"
					( attribute "PN" "D73"
						( Origin gPackager )
					)
					( objectStatus "U2D1.D73" )
				)
				( pin "ddr1_dqs_dp(13)"
					( attribute "PN" "L42"
						( Origin gPackager )
					)
					( objectStatus "U2D1.L42" )
				)
				( pin "ddr1_dqs_dp(14)"
					( attribute "PN" "C34"
						( Origin gPackager )
					)
					( objectStatus "U2D1.C34" )
				)
				( pin "ddr1_dqs_dp(15)"
					( attribute "PN" "C28"
						( Origin gPackager )
					)
					( objectStatus "U2D1.C28" )
				)
				( pin "ddr1_dqs_dp(16)"
					( attribute "PN" "V27"
						( Origin gPackager )
					)
					( objectStatus "U2D1.V27" )
				)
				( pin "ddr1_dqs_dp(17)"
					( attribute "PN" "J68"
						( Origin gPackager )
					)
					( objectStatus "U2D1.J68" )
				)
				( pin "ddr1_ecc(0)"
					( attribute "PN" "J70"
						( Origin gPackager )
					)
					( objectStatus "U2D1.J70" )
				)
				( pin "ddr1_ecc(1)"
					( attribute "PN" "H69"
						( Origin gPackager )
					)
					( objectStatus "U2D1.H69" )
				)
				( pin "ddr1_ecc(2)"
					( attribute "PN" "J66"
						( Origin gPackager )
					)
					( objectStatus "U2D1.J66" )
				)
				( pin "ddr1_ecc(3)"
					( attribute "PN" "L66"
						( Origin gPackager )
					)
					( objectStatus "U2D1.L66" )
				)
				( pin "ddr1_ecc(4)"
					( attribute "PN" "L70"
						( Origin gPackager )
					)
					( objectStatus "U2D1.L70" )
				)
				( pin "ddr1_ecc(5)"
					( attribute "PN" "M69"
						( Origin gPackager )
					)
					( objectStatus "U2D1.M69" )
				)
				( pin "ddr1_ecc(6)"
					( attribute "PN" "H67"
						( Origin gPackager )
					)
					( objectStatus "U2D1.H67" )
				)
				( pin "ddr1_ecc(7)"
					( attribute "PN" "M67"
						( Origin gPackager )
					)
					( objectStatus "U2D1.M67" )
				)
				( pin "ddr1_ma(0)"
					( attribute "PN" "J52"
						( Origin gPackager )
					)
					( objectStatus "U2D1.J52" )
				)
				( pin "ddr1_ma(1)"
					( attribute "PN" "J58"
						( Origin gPackager )
					)
					( objectStatus "U2D1.J58" )
				)
				( pin "ddr1_ma(2)"
					( attribute "PN" "K57"
						( Origin gPackager )
					)
					( objectStatus "U2D1.K57" )
				)
				( pin "ddr1_ma(3)"
					( attribute "PN" "N58"
						( Origin gPackager )
					)
					( objectStatus "U2D1.N58" )
				)
				( pin "ddr1_ma(4)"
					( attribute "PN" "M59"
						( Origin gPackager )
					)
					( objectStatus "U2D1.M59" )
				)
				( pin "ddr1_ma(5)"
					( attribute "PN" "R58"
						( Origin gPackager )
					)
					( objectStatus "U2D1.R58" )
				)
				( pin "ddr1_ma(6)"
					( attribute "PN" "T59"
						( Origin gPackager )
					)
					( objectStatus "U2D1.T59" )
				)
				( pin "ddr1_ma(7)"
					( attribute "PN" "V61"
						( Origin gPackager )
					)
					( objectStatus "U2D1.V61" )
				)
				( pin "ddr1_ma(8)"
					( attribute "PN" "W60"
						( Origin gPackager )
					)
					( objectStatus "U2D1.W60" )
				)
				( pin "ddr1_ma(9)"
					( attribute "PN" "K59"
						( Origin gPackager )
					)
					( objectStatus "U2D1.K59" )
				)
				( pin "ddr1_ma(10)"
					( attribute "PN" "M55"
						( Origin gPackager )
					)
					( objectStatus "U2D1.M55" )
				)
				( pin "ddr1_ma(11)"
					( attribute "PN" "R60"
						( Origin gPackager )
					)
					( objectStatus "U2D1.R60" )
				)
				( pin "ddr1_ma(12)"
					( attribute "PN" "T61"
						( Origin gPackager )
					)
					( objectStatus "U2D1.T61" )
				)
				( pin "ddr1_ma(13)"
					( attribute "PN" "M51"
						( Origin gPackager )
					)
					( objectStatus "U2D1.M51" )
				)
				( pin "ddr1_ma(14)"
					( attribute "PN" "T51"
						( Origin gPackager )
					)
					( objectStatus "U2D1.T51" )
				)
				( pin "ddr1_ma(15)"
					( attribute "PN" "N52"
						( Origin gPackager )
					)
					( objectStatus "U2D1.N52" )
				)
				( pin "ddr1_ma(16)"
					( attribute "PN" "R52"
						( Origin gPackager )
					)
					( objectStatus "U2D1.R52" )
				)
				( pin "ddr1_ma(17)"
					( attribute "PN" "N48"
						( Origin gPackager )
					)
					( objectStatus "U2D1.N48" )
				)
				( pin "ddr1_odt(0)"
					( attribute "PN" "N50"
						( Origin gPackager )
					)
					( objectStatus "U2D1.N50" )
				)
				( pin "ddr1_odt(1)"
					( attribute "PN" "R48"
						( Origin gPackager )
					)
					( objectStatus "U2D1.R48" )
				)
				( pin "ddr1_odt(2)"
					( attribute "PN" "M49"
						( Origin gPackager )
					)
					( objectStatus "U2D1.M49" )
				)
				( pin "ddr1_odt(3)"
					( attribute "PN" "T47"
						( Origin gPackager )
					)
					( objectStatus "U2D1.T47" )
				)
				( pin "ddr1_par"
					( attribute "PN" "K53"
						( Origin gPackager )
					)
					( objectStatus "U2D1.K53" )
				)
			)
			( gate "@baseboard_fab2_lib.baseboard_fab2(sch_1):page59_i172"
				( attribute "CDS_LIB" "chpset_lib"
					( Origin gPackager )
				)
				( attribute "CDS_LOCATION" "U2D1"
					( Origin gPackager )
				)
				( attribute "CDS_SEC" "5"
					( Origin gPackager )
				)
				( attribute "LOCATION" "U2D1"
					( Origin gFrontEnd )
				)
				( attribute "MATERIAL" "IC"
					( Origin gFrontEnd )
				)
				( attribute "PACK_TYPE" "BGA1"
					( Origin gFrontEnd )
				)
				( attribute "PART_NUMBER" "TBD"
					( Origin gFrontEnd )
				)
				( attribute "PHYS_PAGE" "59"
					( Origin gFrontEnd )
				)
				( attribute "ROT" "0"
					( Origin gFrontEnd )
				)
				( attribute "SEC" "5"
					( Origin gFrontEnd )
				)
				( attribute "SEC_TYPE" "BGA1"
					( Origin gFrontEnd )
				)
				( attribute "VER" "5"
					( Origin gFrontEnd )
				)
				( attribute "XY" "(-4175,2550)"
					( Origin gFrontEnd )
				)
				( attribute "CHIPS_PART_NAME" "SKX_EXT_B"
					( Origin gPackager )
				)
				( attribute "CDS_PART_NAME" "SKX_EXT_B_BGA1-IC,TBD"
					( Origin gPackager )
				)
				( objectStatus "U2D1" )
				( pin "ddr2_act_n"
					( attribute "PN" "AB61"
						( Origin gPackager )
					)
					( objectStatus "U2D1.AB61" )
				)
				( pin "ddr2_alert_n"
					( attribute "PN" "AD61"
						( Origin gPackager )
					)
					( objectStatus "U2D1.AD61" )
				)
				( pin "ddr2_ba(0)"
					( attribute "PN" "W52"
						( Origin gPackager )
					)
					( objectStatus "U2D1.W52" )
				)
				( pin "ddr2_ba(1)"
					( attribute "PN" "AE56"
						( Origin gPackager )
					)
					( objectStatus "U2D1.AE56" )
				)
				( pin "ddr2_bg(0)"
					( attribute "PN" "AA60"
						( Origin gPackager )
					)
					( objectStatus "U2D1.AA60" )
				)
				( pin "ddr2_bg(1)"
					( attribute "PN" "AE62"
						( Origin gPackager )
					)
					( objectStatus "U2D1.AE62" )
				)
				( pin "ddr2_cid(2)"
					( attribute "PN" "AB45"
						( Origin gPackager )
					)
					( objectStatus "U2D1.AB45" )
				)
				( pin "ddr2_cke(0)"
					( attribute "PN" "AA62"
						( Origin gPackager )
					)
					( objectStatus "U2D1.AA62" )
				)
				( pin "ddr2_cke(1)"
					( attribute "PN" "AD63"
						( Origin gPackager )
					)
					( objectStatus "U2D1.AD63" )
				)
				( pin "ddr2_cke(2)"
					( attribute "PN" "V63"
						( Origin gPackager )
					)
					( objectStatus "U2D1.V63" )
				)
				( pin "ddr2_cke(3)"
					( attribute "PN" "AB63"
						( Origin gPackager )
					)
					( objectStatus "U2D1.AB63" )
				)
				( pin "ddr2_clk_dn(0)"
					( attribute "PN" "AA54"
						( Origin gPackager )
					)
					( objectStatus "U2D1.AA54" )
				)
				( pin "ddr2_clk_dn(1)"
					( attribute "PN" "W54"
						( Origin gPackager )
					)
					( objectStatus "U2D1.W54" )
				)
				( pin "ddr2_clk_dn(2)"
					( attribute "PN" "AA56"
						( Origin gPackager )
					)
					( objectStatus "U2D1.AA56" )
				)
				( pin "ddr2_clk_dn(3)"
					( attribute "PN" "W56"
						( Origin gPackager )
					)
					( objectStatus "U2D1.W56" )
				)
				( pin "ddr2_clk_dp(0)"
					( attribute "PN" "AB55"
						( Origin gPackager )
					)
					( objectStatus "U2D1.AB55" )
				)
				( pin "ddr2_clk_dp(1)"
					( attribute "PN" "V55"
						( Origin gPackager )
					)
					( objectStatus "U2D1.V55" )
				)
				( pin "ddr2_clk_dp(2)"
					( attribute "PN" "AB57"
						( Origin gPackager )
					)
					( objectStatus "U2D1.AB57" )
				)
				( pin "ddr2_clk_dp(3)"
					( attribute "PN" "V57"
						( Origin gPackager )
					)
					( objectStatus "U2D1.V57" )
				)
				( pin "ddr2_cs_n(0)"
					( attribute "PN" "V51"
						( Origin gPackager )
					)
					( objectStatus "U2D1.V51" )
				)
				( pin "ddr2_cs_n(1)"
					( attribute "PN" "AB49"
						( Origin gPackager )
					)
					( objectStatus "U2D1.AB49" )
				)
				( pin "ddr2_cs_n(2)"
					( attribute "PN" "W46"
						( Origin gPackager )
					)
					( objectStatus "U2D1.W46" )
				)
				( pin "ddr2_cs_n(3)"
					( attribute "PN" "AA46"
						( Origin gPackager )
					)
					( objectStatus "U2D1.AA46" )
				)
				( pin "ddr2_cs_n(4)"
					( attribute "PN" "AB51"
						( Origin gPackager )
					)
					( objectStatus "U2D1.AB51" )
				)
				( pin "ddr2_cs_n(5)"
					( attribute "PN" "W48"
						( Origin gPackager )
					)
					( objectStatus "U2D1.W48" )
				)
				( pin "ddr2_cs_n(6)"
					( attribute "PN" "T45"
						( Origin gPackager )
					)
					( objectStatus "U2D1.T45" )
				)
				( pin "ddr2_cs_n(7)"
					( attribute "PN" "V45"
						( Origin gPackager )
					)
					( objectStatus "U2D1.V45" )
				)
				( pin "ddr2_dq(0)"
					( attribute "PN" "AR76"
						( Origin gPackager )
					)
					( objectStatus "U2D1.AR76" )
				)
				( pin "ddr2_dq(1)"
					( attribute "PN" "AN74"
						( Origin gPackager )
					)
					( objectStatus "U2D1.AN74" )
				)
				( pin "ddr2_dq(2)"
					( attribute "PN" "AK77"
						( Origin gPackager )
					)
					( objectStatus "U2D1.AK77" )
				)
				( pin "ddr2_dq(3)"
					( attribute "PN" "AJ76"
						( Origin gPackager )
					)
					( objectStatus "U2D1.AJ76" )
				)
				( pin "ddr2_dq(4)"
					( attribute "PN" "AT75"
						( Origin gPackager )
					)
					( objectStatus "U2D1.AT75" )
				)
				( pin "ddr2_dq(5)"
					( attribute "PN" "AR74"
						( Origin gPackager )
					)
					( objectStatus "U2D1.AR74" )
				)
				( pin "ddr2_dq(6)"
					( attribute "PN" "AM77"
						( Origin gPackager )
					)
					( objectStatus "U2D1.AM77" )
				)
				( pin "ddr2_dq(7)"
					( attribute "PN" "AK75"
						( Origin gPackager )
					)
					( objectStatus "U2D1.AK75" )
				)
				( pin "ddr2_dq(8)"
					( attribute "PN" "AE76"
						( Origin gPackager )
					)
					( objectStatus "U2D1.AE76" )
				)
				( pin "ddr2_dq(9)"
					( attribute "PN" "AC74"
						( Origin gPackager )
					)
					( objectStatus "U2D1.AC74" )
				)
				( pin "ddr2_dq(10)"
					( attribute "PN" "Y77"
						( Origin gPackager )
					)
					( objectStatus "U2D1.Y77" )
				)
				( pin "ddr2_dq(11)"
					( attribute "PN" "W76"
						( Origin gPackager )
					)
					( objectStatus "U2D1.W76" )
				)
				( pin "ddr2_dq(12)"
					( attribute "PN" "AF75"
						( Origin gPackager )
					)
					( objectStatus "U2D1.AF75" )
				)
				( pin "ddr2_dq(13)"
					( attribute "PN" "AE74"
						( Origin gPackager )
					)
					( objectStatus "U2D1.AE74" )
				)
				( pin "ddr2_dq(14)"
					( attribute "PN" "AB77"
						( Origin gPackager )
					)
					( objectStatus "U2D1.AB77" )
				)
				( pin "ddr2_dq(15)"
					( attribute "PN" "Y75"
						( Origin gPackager )
					)
					( objectStatus "U2D1.Y75" )
				)
				( pin "ddr2_dq(16)"
					( attribute "PN" "W72"
						( Origin gPackager )
					)
					( objectStatus "U2D1.W72" )
				)
				( pin "ddr2_dq(17)"
					( attribute "PN" "AA70"
						( Origin gPackager )
					)
					( objectStatus "U2D1.AA70" )
				)
				( pin "ddr2_dq(18)"
					( attribute "PN" "R70"
						( Origin gPackager )
					)
					( objectStatus "U2D1.R70" )
				)
				( pin "ddr2_dq(19)"
					( attribute "PN" "T69"
						( Origin gPackager )
					)
					( objectStatus "U2D1.T69" )
				)
				( pin "ddr2_dq(20)"
					( attribute "PN" "AA72"
						( Origin gPackager )
					)
					( objectStatus "U2D1.AA72" )
				)
				( pin "ddr2_dq(21)"
					( attribute "PN" "AB71"
						( Origin gPackager )
					)
					( objectStatus "U2D1.AB71" )
				)
				( pin "ddr2_dq(22)"
					( attribute "PN" "T71"
						( Origin gPackager )
					)
					( objectStatus "U2D1.T71" )
				)
				( pin "ddr2_dq(23)"
					( attribute "PN" "V69"
						( Origin gPackager )
					)
					( objectStatus "U2D1.V69" )
				)
				( pin "ddr2_dq(24)"
					( attribute "PN" "AM67"
						( Origin gPackager )
					)
					( objectStatus "U2D1.AM67" )
				)
				( pin "ddr2_dq(25)"
					( attribute "PN" "AT67"
						( Origin gPackager )
					)
					( objectStatus "U2D1.AT67" )
				)
				( pin "ddr2_dq(26)"
					( attribute "PN" "AN64"
						( Origin gPackager )
					)
					( objectStatus "U2D1.AN64" )
				)
				( pin "ddr2_dq(27)"
					( attribute "PN" "AR64"
						( Origin gPackager )
					)
					( objectStatus "U2D1.AR64" )
				)
				( pin "ddr2_dq(28)"
					( attribute "PN" "AN68"
						( Origin gPackager )
					)
					( objectStatus "U2D1.AN68" )
				)
				( pin "ddr2_dq(29)"
					( attribute "PN" "AR68"
						( Origin gPackager )
					)
					( objectStatus "U2D1.AR68" )
				)
				( pin "ddr2_dq(30)"
					( attribute "PN" "AM65"
						( Origin gPackager )
					)
					( objectStatus "U2D1.AM65" )
				)
				( pin "ddr2_dq(31)"
					( attribute "PN" "AT65"
						( Origin gPackager )
					)
					( objectStatus "U2D1.AT65" )
				)
				( pin "ddr2_dq(32)"
					( attribute "PN" "U40"
						( Origin gPackager )
					)
					( objectStatus "U2D1.U40" )
				)
				( pin "ddr2_dq(33)"
					( attribute "PN" "AA40"
						( Origin gPackager )
					)
					( objectStatus "U2D1.AA40" )
				)
				( pin "ddr2_dq(34)"
					( attribute "PN" "V37"
						( Origin gPackager )
					)
					( objectStatus "U2D1.V37" )
				)
				( pin "ddr2_dq(35)"
					( attribute "PN" "Y37"
						( Origin gPackager )
					)
					( objectStatus "U2D1.Y37" )
				)
				( pin "ddr2_dq(36)"
					( attribute "PN" "V41"
						( Origin gPackager )
					)
					( objectStatus "U2D1.V41" )
				)
				( pin "ddr2_dq(37)"
					( attribute "PN" "Y41"
						( Origin gPackager )
					)
					( objectStatus "U2D1.Y41" )
				)
				( pin "ddr2_dq(38)"
					( attribute "PN" "U38"
						( Origin gPackager )
					)
					( objectStatus "U2D1.U38" )
				)
				( pin "ddr2_dq(39)"
					( attribute "PN" "AA38"
						( Origin gPackager )
					)
					( objectStatus "U2D1.AA38" )
				)
				( pin "ddr2_dq(40)"
					( attribute "PN" "U34"
						( Origin gPackager )
					)
					( objectStatus "U2D1.U34" )
				)
				( pin "ddr2_dq(41)"
					( attribute "PN" "AA34"
						( Origin gPackager )
					)
					( objectStatus "U2D1.AA34" )
				)
				( pin "ddr2_dq(42)"
					( attribute "PN" "V31"
						( Origin gPackager )
					)
					( objectStatus "U2D1.V31" )
				)
				( pin "ddr2_dq(43)"
					( attribute "PN" "Y31"
						( Origin gPackager )
					)
					( objectStatus "U2D1.Y31" )
				)
				( pin "ddr2_dq(44)"
					( attribute "PN" "V35"
						( Origin gPackager )
					)
					( objectStatus "U2D1.V35" )
				)
				( pin "ddr2_dq(45)"
					( attribute "PN" "Y35"
						( Origin gPackager )
					)
					( objectStatus "U2D1.Y35" )
				)
				( pin "ddr2_dq(46)"
					( attribute "PN" "U32"
						( Origin gPackager )
					)
					( objectStatus "U2D1.U32" )
				)
				( pin "ddr2_dq(47)"
					( attribute "PN" "AA32"
						( Origin gPackager )
					)
					( objectStatus "U2D1.AA32" )
				)
				( pin "ddr2_dq(48)"
					( attribute "PN" "AD31"
						( Origin gPackager )
					)
					( objectStatus "U2D1.AD31" )
				)
				( pin "ddr2_dq(49)"
					( attribute "PN" "AH31"
						( Origin gPackager )
					)
					( objectStatus "U2D1.AH31" )
				)
				( pin "ddr2_dq(50)"
					( attribute "PN" "AE28"
						( Origin gPackager )
					)
					( objectStatus "U2D1.AE28" )
				)
				( pin "ddr2_dq(51)"
					( attribute "PN" "AG28"
						( Origin gPackager )
					)
					( objectStatus "U2D1.AG28" )
				)
				( pin "ddr2_dq(52)"
					( attribute "PN" "AE32"
						( Origin gPackager )
					)
					( objectStatus "U2D1.AE32" )
				)
				( pin "ddr2_dq(53)"
					( attribute "PN" "AG32"
						( Origin gPackager )
					)
					( objectStatus "U2D1.AG32" )
				)
				( pin "ddr2_dq(54)"
					( attribute "PN" "AD29"
						( Origin gPackager )
					)
					( objectStatus "U2D1.AD29" )
				)
				( pin "ddr2_dq(55)"
					( attribute "PN" "AH29"
						( Origin gPackager )
					)
					( objectStatus "U2D1.AH29" )
				)
				( pin "ddr2_dq(56)"
					( attribute "PN" "AD25"
						( Origin gPackager )
					)
					( objectStatus "U2D1.AD25" )
				)
				( pin "ddr2_dq(57)"
					( attribute "PN" "AH25"
						( Origin gPackager )
					)
					( objectStatus "U2D1.AH25" )
				)
				( pin "ddr2_dq(58)"
					( attribute "PN" "AE22"
						( Origin gPackager )
					)
					( objectStatus "U2D1.AE22" )
				)
				( pin "ddr2_dq(59)"
					( attribute "PN" "AG22"
						( Origin gPackager )
					)
					( objectStatus "U2D1.AG22" )
				)
				( pin "ddr2_dq(60)"
					( attribute "PN" "AE26"
						( Origin gPackager )
					)
					( objectStatus "U2D1.AE26" )
				)
				( pin "ddr2_dq(61)"
					( attribute "PN" "AG26"
						( Origin gPackager )
					)
					( objectStatus "U2D1.AG26" )
				)
				( pin "ddr2_dq(62)"
					( attribute "PN" "AD23"
						( Origin gPackager )
					)
					( objectStatus "U2D1.AD23" )
				)
				( pin "ddr2_dq(63)"
					( attribute "PN" "AH23"
						( Origin gPackager )
					)
					( objectStatus "U2D1.AH23" )
				)
				( pin "ddr2_dqs_dn(0)"
					( attribute "PN" "AL74"
						( Origin gPackager )
					)
					( objectStatus "U2D1.AL74" )
				)
				( pin "ddr2_dqs_dn(1)"
					( attribute "PN" "AA74"
						( Origin gPackager )
					)
					( objectStatus "U2D1.AA74" )
				)
				( pin "ddr2_dqs_dn(2)"
					( attribute "PN" "Y69"
						( Origin gPackager )
					)
					( objectStatus "U2D1.Y69" )
				)
				( pin "ddr2_dqs_dn(3)"
					( attribute "PN" "AU66"
						( Origin gPackager )
					)
					( objectStatus "U2D1.AU66" )
				)
				( pin "ddr2_dqs_dn(4)"
					( attribute "PN" "AB39"
						( Origin gPackager )
					)
					( objectStatus "U2D1.AB39" )
				)
				( pin "ddr2_dqs_dn(5)"
					( attribute "PN" "AB33"
						( Origin gPackager )
					)
					( objectStatus "U2D1.AB33" )
				)
				( pin "ddr2_dqs_dn(6)"
					( attribute "PN" "AJ30"
						( Origin gPackager )
					)
					( objectStatus "U2D1.AJ30" )
				)
				( pin "ddr2_dqs_dn(7)"
					( attribute "PN" "AJ24"
						( Origin gPackager )
					)
					( objectStatus "U2D1.AJ24" )
				)
				( pin "ddr2_dqs_dn(8)"
					( attribute "PN" "BB71"
						( Origin gPackager )
					)
					( objectStatus "U2D1.BB71" )
				)
				( pin "ddr2_dqs_dn(9)"
					( attribute "PN" "AP77"
						( Origin gPackager )
					)
					( objectStatus "U2D1.AP77" )
				)
				( pin "ddr2_dqs_dn(10)"
					( attribute "PN" "AD77"
						( Origin gPackager )
					)
					( objectStatus "U2D1.AD77" )
				)
				( pin "ddr2_dqs_dn(11)"
					( attribute "PN" "U72"
						( Origin gPackager )
					)
					( objectStatus "U2D1.U72" )
				)
				( pin "ddr2_dqs_dn(12)"
					( attribute "PN" "AL66"
						( Origin gPackager )
					)
					( objectStatus "U2D1.AL66" )
				)
				( pin "ddr2_dqs_dn(13)"
					( attribute "PN" "T39"
						( Origin gPackager )
					)
					( objectStatus "U2D1.T39" )
				)
				( pin "ddr2_dqs_dn(14)"
					( attribute "PN" "T33"
						( Origin gPackager )
					)
					( objectStatus "U2D1.T33" )
				)
				( pin "ddr2_dqs_dn(15)"
					( attribute "PN" "AC30"
						( Origin gPackager )
					)
					( objectStatus "U2D1.AC30" )
				)
				( pin "ddr2_dqs_dn(16)"
					( attribute "PN" "AC24"
						( Origin gPackager )
					)
					( objectStatus "U2D1.AC24" )
				)
				( pin "ddr2_dqs_dn(17)"
					( attribute "PN" "AT71"
						( Origin gPackager )
					)
					( objectStatus "U2D1.AT71" )
				)
				( pin "ddr2_dqs_dp(0)"
					( attribute "PN" "AM75"
						( Origin gPackager )
					)
					( objectStatus "U2D1.AM75" )
				)
				( pin "ddr2_dqs_dp(1)"
					( attribute "PN" "AB75"
						( Origin gPackager )
					)
					( objectStatus "U2D1.AB75" )
				)
				( pin "ddr2_dqs_dp(2)"
					( attribute "PN" "W70"
						( Origin gPackager )
					)
					( objectStatus "U2D1.W70" )
				)
				( pin "ddr2_dqs_dp(3)"
					( attribute "PN" "AR66"
						( Origin gPackager )
					)
					( objectStatus "U2D1.AR66" )
				)
				( pin "ddr2_dqs_dp(4)"
					( attribute "PN" "Y39"
						( Origin gPackager )
					)
					( objectStatus "U2D1.Y39" )
				)
				( pin "ddr2_dqs_dp(5)"
					( attribute "PN" "Y33"
						( Origin gPackager )
					)
					( objectStatus "U2D1.Y33" )
				)
				( pin "ddr2_dqs_dp(6)"
					( attribute "PN" "AG30"
						( Origin gPackager )
					)
					( objectStatus "U2D1.AG30" )
				)
				( pin "ddr2_dqs_dp(7)"
					( attribute "PN" "AG24"
						( Origin gPackager )
					)
					( objectStatus "U2D1.AG24" )
				)
				( pin "ddr2_dqs_dp(8)"
					( attribute "PN" "AY71"
						( Origin gPackager )
					)
					( objectStatus "U2D1.AY71" )
				)
				( pin "ddr2_dqs_dp(9)"
					( attribute "PN" "AN76"
						( Origin gPackager )
					)
					( objectStatus "U2D1.AN76" )
				)
				( pin "ddr2_dqs_dp(10)"
					( attribute "PN" "AC76"
						( Origin gPackager )
					)
					( objectStatus "U2D1.AC76" )
				)
				( pin "ddr2_dqs_dp(11)"
					( attribute "PN" "V71"
						( Origin gPackager )
					)
					( objectStatus "U2D1.V71" )
				)
				( pin "ddr2_dqs_dp(12)"
					( attribute "PN" "AN66"
						( Origin gPackager )
					)
					( objectStatus "U2D1.AN66" )
				)
				( pin "ddr2_dqs_dp(13)"
					( attribute "PN" "V39"
						( Origin gPackager )
					)
					( objectStatus "U2D1.V39" )
				)
				( pin "ddr2_dqs_dp(14)"
					( attribute "PN" "V33"
						( Origin gPackager )
					)
					( objectStatus "U2D1.V33" )
				)
				( pin "ddr2_dqs_dp(15)"
					( attribute "PN" "AE30"
						( Origin gPackager )
					)
					( objectStatus "U2D1.AE30" )
				)
				( pin "ddr2_dqs_dp(16)"
					( attribute "PN" "AE24"
						( Origin gPackager )
					)
					( objectStatus "U2D1.AE24" )
				)
				( pin "ddr2_dqs_dp(17)"
					( attribute "PN" "AV71"
						( Origin gPackager )
					)
					( objectStatus "U2D1.AV71" )
				)
				( pin "ddr2_ecc(0)"
					( attribute "PN" "AU72"
						( Origin gPackager )
					)
					( objectStatus "U2D1.AU72" )
				)
				( pin "ddr2_ecc(1)"
					( attribute "PN" "BA72"
						( Origin gPackager )
					)
					( objectStatus "U2D1.BA72" )
				)
				( pin "ddr2_ecc(2)"
					( attribute "PN" "AV69"
						( Origin gPackager )
					)
					( objectStatus "U2D1.AV69" )
				)
				( pin "ddr2_ecc(3)"
					( attribute "PN" "AY69"
						( Origin gPackager )
					)
					( objectStatus "U2D1.AY69" )
				)
				( pin "ddr2_ecc(4)"
					( attribute "PN" "AV73"
						( Origin gPackager )
					)
					( objectStatus "U2D1.AV73" )
				)
				( pin "ddr2_ecc(5)"
					( attribute "PN" "AY73"
						( Origin gPackager )
					)
					( objectStatus "U2D1.AY73" )
				)
				( pin "ddr2_ecc(6)"
					( attribute "PN" "AU70"
						( Origin gPackager )
					)
					( objectStatus "U2D1.AU70" )
				)
				( pin "ddr2_ecc(7)"
					( attribute "PN" "BA70"
						( Origin gPackager )
					)
					( objectStatus "U2D1.BA70" )
				)
				( pin "ddr2_ma(0)"
					( attribute "PN" "AB53"
						( Origin gPackager )
					)
					( objectStatus "U2D1.AB53" )
				)
				( pin "ddr2_ma(1)"
					( attribute "PN" "AE58"
						( Origin gPackager )
					)
					( objectStatus "U2D1.AE58" )
				)
				( pin "ddr2_ma(2)"
					( attribute "PN" "AD57"
						( Origin gPackager )
					)
					( objectStatus "U2D1.AD57" )
				)
				( pin "ddr2_ma(3)"
					( attribute "PN" "W58"
						( Origin gPackager )
					)
					( objectStatus "U2D1.W58" )
				)
				( pin "ddr2_ma(4)"
					( attribute "PN" "AA58"
						( Origin gPackager )
					)
					( objectStatus "U2D1.AA58" )
				)
				( pin "ddr2_ma(5)"
					( attribute "PN" "V59"
						( Origin gPackager )
					)
					( objectStatus "U2D1.V59" )
				)
				( pin "ddr2_ma(6)"
					( attribute "PN" "AB59"
						( Origin gPackager )
					)
					( objectStatus "U2D1.AB59" )
				)
				( pin "ddr2_ma(7)"
					( attribute "PN" "AE60"
						( Origin gPackager )
					)
					( objectStatus "U2D1.AE60" )
				)
				( pin "ddr2_ma(8)"
					( attribute "PN" "AD59"
						( Origin gPackager )
					)
					( objectStatus "U2D1.AD59" )
				)
				( pin "ddr2_ma(9)"
					( attribute "PN" "AG58"
						( Origin gPackager )
					)
					( objectStatus "U2D1.AG58" )
				)
				( pin "ddr2_ma(10)"
					( attribute "PN" "AD55"
						( Origin gPackager )
					)
					( objectStatus "U2D1.AD55" )
				)
				( pin "ddr2_ma(11)"
					( attribute "PN" "AG60"
						( Origin gPackager )
					)
					( objectStatus "U2D1.AG60" )
				)
				( pin "ddr2_ma(12)"
					( attribute "PN" "AG62"
						( Origin gPackager )
					)
					( objectStatus "U2D1.AG62" )
				)
				( pin "ddr2_ma(13)"
					( attribute "PN" "AD53"
						( Origin gPackager )
					)
					( objectStatus "U2D1.AD53" )
				)
				( pin "ddr2_ma(14)"
					( attribute "PN" "W50"
						( Origin gPackager )
					)
					( objectStatus "U2D1.W50" )
				)
				( pin "ddr2_ma(15)"
					( attribute "PN" "AE54"
						( Origin gPackager )
					)
					( objectStatus "U2D1.AE54" )
				)
				( pin "ddr2_ma(16)"
					( attribute "PN" "AA52"
						( Origin gPackager )
					)
					( objectStatus "U2D1.AA52" )
				)
				( pin "ddr2_ma(17)"
					( attribute "PN" "AC46"
						( Origin gPackager )
					)
					( objectStatus "U2D1.AC46" )
				)
				( pin "ddr2_odt(0)"
					( attribute "PN" "AA50"
						( Origin gPackager )
					)
					( objectStatus "U2D1.AA50" )
				)
				( pin "ddr2_odt(1)"
					( attribute "PN" "AA48"
						( Origin gPackager )
					)
					( objectStatus "U2D1.AA48" )
				)
				( pin "ddr2_odt(2)"
					( attribute "PN" "V49"
						( Origin gPackager )
					)
					( objectStatus "U2D1.V49" )
				)
				( pin "ddr2_odt(3)"
					( attribute "PN" "AB47"
						( Origin gPackager )
					)
					( objectStatus "U2D1.AB47" )
				)
				( pin "ddr2_par"
					( attribute "PN" "V53"
						( Origin gPackager )
					)
					( objectStatus "U2D1.V53" )
				)
			)
			( gate "@baseboard_fab2_lib.baseboard_fab2(sch_1):page60_i172"
				( attribute "CDS_LIB" "chpset_lib"
					( Origin gPackager )
				)
				( attribute "CDS_LOCATION" "U2D1"
					( Origin gPackager )
				)
				( attribute "CDS_SEC" "6"
					( Origin gPackager )
				)
				( attribute "LOCATION" "U2D1"
					( Origin gFrontEnd )
				)
				( attribute "MATERIAL" "IC"
					( Origin gFrontEnd )
				)
				( attribute "PACK_TYPE" "BGA1"
					( Origin gFrontEnd )
				)
				( attribute "PART_NUMBER" "TBD"
					( Origin gFrontEnd )
				)
				( attribute "PHYS_PAGE" "60"
					( Origin gFrontEnd )
				)
				( attribute "ROT" "0"
					( Origin gFrontEnd )
				)
				( attribute "SEC" "6"
					( Origin gFrontEnd )
				)
				( attribute "SEC_TYPE" "BGA1"
					( Origin gFrontEnd )
				)
				( attribute "VER" "6"
					( Origin gFrontEnd )
				)
				( attribute "XY" "(-4175,2575)"
					( Origin gFrontEnd )
				)
				( attribute "CHIPS_PART_NAME" "SKX_EXT_B"
					( Origin gPackager )
				)
				( attribute "CDS_PART_NAME" "SKX_EXT_B_BGA1-IC,TBD"
					( Origin gPackager )
				)
				( objectStatus "U2D1" )
				( pin "ddr3_act_n"
					( attribute "PN" "DW60"
						( Origin gPackager )
					)
					( objectStatus "U2D1.DW60" )
				)
				( pin "ddr3_alert_n"
					( attribute "PN" "ED63"
						( Origin gPackager )
					)
					( objectStatus "U2D1.ED63" )
				)
				( pin "ddr3_ba(0)"
					( attribute "PN" "EE52"
						( Origin gPackager )
					)
					( objectStatus "U2D1.EE52" )
				)
				( pin "ddr3_ba(1)"
					( attribute "PN" "EA54"
						( Origin gPackager )
					)
					( objectStatus "U2D1.EA54" )
				)
				( pin "ddr3_bg(0)"
					( attribute "PN" "ED61"
						( Origin gPackager )
					)
					( objectStatus "U2D1.ED61" )
				)
				( pin "ddr3_bg(1)"
					( attribute "PN" "DW62"
						( Origin gPackager )
					)
					( objectStatus "U2D1.DW62" )
				)
				( pin "ddr3_cid(2)"
					( attribute "PN" "DV47"
						( Origin gPackager )
					)
					( objectStatus "U2D1.DV47" )
				)
				( pin "ddr3_cke(0)"
					( attribute "PN" "EE62"
						( Origin gPackager )
					)
					( objectStatus "U2D1.EE62" )
				)
				( pin "ddr3_cke(1)"
					( attribute "PN" "EF63"
						( Origin gPackager )
					)
					( objectStatus "U2D1.EF63" )
				)
				( pin "ddr3_cke(2)"
					( attribute "PN" "EA62"
						( Origin gPackager )
					)
					( objectStatus "U2D1.EA62" )
				)
				( pin "ddr3_cke(3)"
					( attribute "PN" "EB63"
						( Origin gPackager )
					)
					( objectStatus "U2D1.EB63" )
				)
				( pin "ddr3_clk_dn(0)"
					( attribute "PN" "ED55"
						( Origin gPackager )
					)
					( objectStatus "U2D1.ED55" )
				)
				( pin "ddr3_clk_dn(1)"
					( attribute "PN" "EF55"
						( Origin gPackager )
					)
					( objectStatus "U2D1.EF55" )
				)
				( pin "ddr3_clk_dn(2)"
					( attribute "PN" "DW56"
						( Origin gPackager )
					)
					( objectStatus "U2D1.DW56" )
				)
				( pin "ddr3_clk_dn(3)"
					( attribute "PN" "EF57"
						( Origin gPackager )
					)
					( objectStatus "U2D1.EF57" )
				)
				( pin "ddr3_clk_dp(0)"
					( attribute "PN" "EB55"
						( Origin gPackager )
					)
					( objectStatus "U2D1.EB55" )
				)
				( pin "ddr3_clk_dp(1)"
					( attribute "PN" "EE54"
						( Origin gPackager )
					)
					( objectStatus "U2D1.EE54" )
				)
				( pin "ddr3_clk_dp(2)"
					( attribute "PN" "EA56"
						( Origin gPackager )
					)
					( objectStatus "U2D1.EA56" )
				)
				( pin "ddr3_clk_dp(3)"
					( attribute "PN" "EE56"
						( Origin gPackager )
					)
					( objectStatus "U2D1.EE56" )
				)
				( pin "ddr3_cs_n(0)"
					( attribute "PN" "EF51"
						( Origin gPackager )
					)
					( objectStatus "U2D1.EF51" )
				)
				( pin "ddr3_cs_n(1)"
					( attribute "PN" "ED49"
						( Origin gPackager )
					)
					( objectStatus "U2D1.ED49" )
				)
				( pin "ddr3_cs_n(2)"
					( attribute "PN" "ED47"
						( Origin gPackager )
					)
					( objectStatus "U2D1.ED47" )
				)
				( pin "ddr3_cs_n(3)"
					( attribute "PN" "EB47"
						( Origin gPackager )
					)
					( objectStatus "U2D1.EB47" )
				)
				( pin "ddr3_cs_n(4)"
					( attribute "PN" "EB51"
						( Origin gPackager )
					)
					( objectStatus "U2D1.EB51" )
				)
				( pin "ddr3_cs_n(5)"
					( attribute "PN" "EB49"
						( Origin gPackager )
					)
					( objectStatus "U2D1.EB49" )
				)
				( pin "ddr3_cs_n(6)"
					( attribute "PN" "DV45"
						( Origin gPackager )
					)
					( objectStatus "U2D1.DV45" )
				)
				( pin "ddr3_cs_n(7)"
					( attribute "PN" "EB45"
						( Origin gPackager )
					)
					( objectStatus "U2D1.EB45" )
				)
				( pin "ddr3_dq(0)"
					( attribute "PN" "CN84"
						( Origin gPackager )
					)
					( objectStatus "U2D1.CN84" )
				)
				( pin "ddr3_dq(1)"
					( attribute "PN" "CN86"
						( Origin gPackager )
					)
					( objectStatus "U2D1.CN86" )
				)
				( pin "ddr3_dq(2)"
					( attribute "PN" "DA86"
						( Origin gPackager )
					)
					( objectStatus "U2D1.DA86" )
				)
				( pin "ddr3_dq(3)"
					( attribute "PN" "DA84"
						( Origin gPackager )
					)
					( objectStatus "U2D1.DA84" )
				)
				( pin "ddr3_dq(4)"
					( attribute "PN" "CL84"
						( Origin gPackager )
					)
					( objectStatus "U2D1.CL84" )
				)
				( pin "ddr3_dq(5)"
					( attribute "PN" "CL86"
						( Origin gPackager )
					)
					( objectStatus "U2D1.CL86" )
				)
				( pin "ddr3_dq(6)"
					( attribute "PN" "CW86"
						( Origin gPackager )
					)
					( objectStatus "U2D1.CW86" )
				)
				( pin "ddr3_dq(7)"
					( attribute "PN" "CW84"
						( Origin gPackager )
					)
					( objectStatus "U2D1.CW84" )
				)
				( pin "ddr3_dq(8)"
					( attribute "PN" "DG84"
						( Origin gPackager )
					)
					( objectStatus "U2D1.DG84" )
				)
				( pin "ddr3_dq(9)"
					( attribute "PN" "DH85"
						( Origin gPackager )
					)
					( objectStatus "U2D1.DH85" )
				)
				( pin "ddr3_dq(10)"
					( attribute "PN" "DV83"
						( Origin gPackager )
					)
					( objectStatus "U2D1.DV83" )
				)
				( pin "ddr3_dq(11)"
					( attribute "PN" "DY83"
						( Origin gPackager )
					)
					( objectStatus "U2D1.DY83" )
				)
				( pin "ddr3_dq(12)"
					( attribute "PN" "DD85"
						( Origin gPackager )
					)
					( objectStatus "U2D1.DD85" )
				)
				( pin "ddr3_dq(13)"
					( attribute "PN" "DE84"
						( Origin gPackager )
					)
					( objectStatus "U2D1.DE84" )
				)
				( pin "ddr3_dq(14)"
					( attribute "PN" "DR84"
						( Origin gPackager )
					)
					( objectStatus "U2D1.DR84" )
				)
				( pin "ddr3_dq(15)"
					( attribute "PN" "DV85"
						( Origin gPackager )
					)
					( objectStatus "U2D1.DV85" )
				)
				( pin "ddr3_dq(16)"
					( attribute "PN" "DM79"
						( Origin gPackager )
					)
					( objectStatus "U2D1.DM79" )
				)
				( pin "ddr3_dq(17)"
					( attribute "PN" "DK81"
						( Origin gPackager )
					)
					( objectStatus "U2D1.DK81" )
				)
				( pin "ddr3_dq(18)"
					( attribute "PN" "DT81"
						( Origin gPackager )
					)
					( objectStatus "U2D1.DT81" )
				)
				( pin "ddr3_dq(19)"
					( attribute "PN" "DR82"
						( Origin gPackager )
					)
					( objectStatus "U2D1.DR82" )
				)
				( pin "ddr3_dq(20)"
					( attribute "PN" "DK79"
						( Origin gPackager )
					)
					( objectStatus "U2D1.DK79" )
				)
				( pin "ddr3_dq(21)"
					( attribute "PN" "DJ80"
						( Origin gPackager )
					)
					( objectStatus "U2D1.DJ80" )
				)
				( pin "ddr3_dq(22)"
					( attribute "PN" "DR80"
						( Origin gPackager )
					)
					( objectStatus "U2D1.DR80" )
				)
				( pin "ddr3_dq(23)"
					( attribute "PN" "DN82"
						( Origin gPackager )
					)
					( objectStatus "U2D1.DN82" )
				)
				( pin "ddr3_dq(24)"
					( attribute "PN" "DN76"
						( Origin gPackager )
					)
					( objectStatus "U2D1.DN76" )
				)
				( pin "ddr3_dq(25)"
					( attribute "PN" "DU76"
						( Origin gPackager )
					)
					( objectStatus "U2D1.DU76" )
				)
				( pin "ddr3_dq(26)"
					( attribute "PN" "DP73"
						( Origin gPackager )
					)
					( objectStatus "U2D1.DP73" )
				)
				( pin "ddr3_dq(27)"
					( attribute "PN" "DT73"
						( Origin gPackager )
					)
					( objectStatus "U2D1.DT73" )
				)
				( pin "ddr3_dq(28)"
					( attribute "PN" "DP77"
						( Origin gPackager )
					)
					( objectStatus "U2D1.DP77" )
				)
				( pin "ddr3_dq(29)"
					( attribute "PN" "DT77"
						( Origin gPackager )
					)
					( objectStatus "U2D1.DT77" )
				)
				( pin "ddr3_dq(30)"
					( attribute "PN" "DN74"
						( Origin gPackager )
					)
					( objectStatus "U2D1.DN74" )
				)
				( pin "ddr3_dq(31)"
					( attribute "PN" "DU74"
						( Origin gPackager )
					)
					( objectStatus "U2D1.DU74" )
				)
				( pin "ddr3_dq(32)"
					( attribute "PN" "EC40"
						( Origin gPackager )
					)
					( objectStatus "U2D1.EC40" )
				)
				( pin "ddr3_dq(33)"
					( attribute "PN" "ED39"
						( Origin gPackager )
					)
					( objectStatus "U2D1.ED39" )
				)
				( pin "ddr3_dq(34)"
					( attribute "PN" "EA36"
						( Origin gPackager )
					)
					( objectStatus "U2D1.EA36" )
				)
				( pin "ddr3_dq(35)"
					( attribute "PN" "EC36"
						( Origin gPackager )
					)
					( objectStatus "U2D1.EC36" )
				)
				( pin "ddr3_dq(36)"
					( attribute "PN" "DY39"
						( Origin gPackager )
					)
					( objectStatus "U2D1.DY39" )
				)
				( pin "ddr3_dq(37)"
					( attribute "PN" "EA40"
						( Origin gPackager )
					)
					( objectStatus "U2D1.EA40" )
				)
				( pin "ddr3_dq(38)"
					( attribute "PN" "DY37"
						( Origin gPackager )
					)
					( objectStatus "U2D1.DY37" )
				)
				( pin "ddr3_dq(39)"
					( attribute "PN" "ED37"
						( Origin gPackager )
					)
					( objectStatus "U2D1.ED37" )
				)
				( pin "ddr3_dq(40)"
					( attribute "PN" "DN36"
						( Origin gPackager )
					)
					( objectStatus "U2D1.DN36" )
				)
				( pin "ddr3_dq(41)"
					( attribute "PN" "DU36"
						( Origin gPackager )
					)
					( objectStatus "U2D1.DU36" )
				)
				( pin "ddr3_dq(42)"
					( attribute "PN" "DP33"
						( Origin gPackager )
					)
					( objectStatus "U2D1.DP33" )
				)
				( pin "ddr3_dq(43)"
					( attribute "PN" "DT33"
						( Origin gPackager )
					)
					( objectStatus "U2D1.DT33" )
				)
				( pin "ddr3_dq(44)"
					( attribute "PN" "DP37"
						( Origin gPackager )
					)
					( objectStatus "U2D1.DP37" )
				)
				( pin "ddr3_dq(45)"
					( attribute "PN" "DT37"
						( Origin gPackager )
					)
					( objectStatus "U2D1.DT37" )
				)
				( pin "ddr3_dq(46)"
					( attribute "PN" "DN34"
						( Origin gPackager )
					)
					( objectStatus "U2D1.DN34" )
				)
				( pin "ddr3_dq(47)"
					( attribute "PN" "DU34"
						( Origin gPackager )
					)
					( objectStatus "U2D1.DU34" )
				)
				( pin "ddr3_dq(48)"
					( attribute "PN" "DN30"
						( Origin gPackager )
					)
					( objectStatus "U2D1.DN30" )
				)
				( pin "ddr3_dq(49)"
					( attribute "PN" "DU30"
						( Origin gPackager )
					)
					( objectStatus "U2D1.DU30" )
				)
				( pin "ddr3_dq(50)"
					( attribute "PN" "DP27"
						( Origin gPackager )
					)
					( objectStatus "U2D1.DP27" )
				)
				( pin "ddr3_dq(51)"
					( attribute "PN" "DT27"
						( Origin gPackager )
					)
					( objectStatus "U2D1.DT27" )
				)
				( pin "ddr3_dq(52)"
					( attribute "PN" "DP31"
						( Origin gPackager )
					)
					( objectStatus "U2D1.DP31" )
				)
				( pin "ddr3_dq(53)"
					( attribute "PN" "DT31"
						( Origin gPackager )
					)
					( objectStatus "U2D1.DT31" )
				)
				( pin "ddr3_dq(54)"
					( attribute "PN" "DN28"
						( Origin gPackager )
					)
					( objectStatus "U2D1.DN28" )
				)
				( pin "ddr3_dq(55)"
					( attribute "PN" "DU28"
						( Origin gPackager )
					)
					( objectStatus "U2D1.DU28" )
				)
				( pin "ddr3_dq(56)"
					( attribute "PN" "DN24"
						( Origin gPackager )
					)
					( objectStatus "U2D1.DN24" )
				)
				( pin "ddr3_dq(57)"
					( attribute "PN" "DU24"
						( Origin gPackager )
					)
					( objectStatus "U2D1.DU24" )
				)
				( pin "ddr3_dq(58)"
					( attribute "PN" "DY21"
						( Origin gPackager )
					)
					( objectStatus "U2D1.DY21" )
				)
				( pin "ddr3_dq(59)"
					( attribute "PN" "EB21"
						( Origin gPackager )
					)
					( objectStatus "U2D1.EB21" )
				)
				( pin "ddr3_dq(60)"
					( attribute "PN" "DP25"
						( Origin gPackager )
					)
					( objectStatus "U2D1.DP25" )
				)
				( pin "ddr3_dq(61)"
					( attribute "PN" "DT25"
						( Origin gPackager )
					)
					( objectStatus "U2D1.DT25" )
				)
				( pin "ddr3_dq(62)"
					( attribute "PN" "EC22"
						( Origin gPackager )
					)
					( objectStatus "U2D1.EC22" )
				)
				( pin "ddr3_dq(63)"
					( attribute "PN" "DW22"
						( Origin gPackager )
					)
					( objectStatus "U2D1.DW22" )
				)
				( pin "ddr3_dqs_dn(0)"
					( attribute "PN" "CU84"
						( Origin gPackager )
					)
					( objectStatus "U2D1.CU84" )
				)
				( pin "ddr3_dqs_dn(1)"
					( attribute "PN" "DN84"
						( Origin gPackager )
					)
					( objectStatus "U2D1.DN84" )
				)
				( pin "ddr3_dqs_dn(2)"
					( attribute "PN" "DL82"
						( Origin gPackager )
					)
					( objectStatus "U2D1.DL82" )
				)
				( pin "ddr3_dqs_dn(3)"
					( attribute "PN" "DV75"
						( Origin gPackager )
					)
					( objectStatus "U2D1.DV75" )
				)
				( pin "ddr3_dqs_dn(4)"
					( attribute "PN" "EE38"
						( Origin gPackager )
					)
					( objectStatus "U2D1.EE38" )
				)
				( pin "ddr3_dqs_dn(5)"
					( attribute "PN" "DV35"
						( Origin gPackager )
					)
					( objectStatus "U2D1.DV35" )
				)
				( pin "ddr3_dqs_dn(6)"
					( attribute "PN" "DV29"
						( Origin gPackager )
					)
					( objectStatus "U2D1.DV29" )
				)
				( pin "ddr3_dqs_dn(7)"
					( attribute "PN" "DV23"
						( Origin gPackager )
					)
					( objectStatus "U2D1.DV23" )
				)
				( pin "ddr3_dqs_dn(8)"
					( attribute "PN" "DF67"
						( Origin gPackager )
					)
					( objectStatus "U2D1.DF67" )
				)
				( pin "ddr3_dqs_dn(9)"
					( attribute "PN" "CR84"
						( Origin gPackager )
					)
					( objectStatus "U2D1.CR84" )
				)
				( pin "ddr3_dqs_dn(10)"
					( attribute "PN" "DM85"
						( Origin gPackager )
					)
					( objectStatus "U2D1.DM85" )
				)
				( pin "ddr3_dqs_dn(11)"
					( attribute "PN" "DN80"
						( Origin gPackager )
					)
					( objectStatus "U2D1.DN80" )
				)
				( pin "ddr3_dqs_dn(12)"
					( attribute "PN" "DP75"
						( Origin gPackager )
					)
					( objectStatus "U2D1.DP75" )
				)
				( pin "ddr3_dqs_dn(13)"
					( attribute "PN" "EA38"
						( Origin gPackager )
					)
					( objectStatus "U2D1.EA38" )
				)
				( pin "ddr3_dqs_dn(14)"
					( attribute "PN" "DP35"
						( Origin gPackager )
					)
					( objectStatus "U2D1.DP35" )
				)
				( pin "ddr3_dqs_dn(15)"
					( attribute "PN" "DM29"
						( Origin gPackager )
					)
					( objectStatus "U2D1.DM29" )
				)
				( pin "ddr3_dqs_dn(16)"
					( attribute "PN" "DM23"
						( Origin gPackager )
					)
					( objectStatus "U2D1.DM23" )
				)
				( pin "ddr3_dqs_dn(17)"
					( attribute "PN" "DB67"
						( Origin gPackager )
					)
					( objectStatus "U2D1.DB67" )
				)
				( pin "ddr3_dqs_dp(0)"
					( attribute "PN" "CV85"
						( Origin gPackager )
					)
					( objectStatus "U2D1.CV85" )
				)
				( pin "ddr3_dqs_dp(1)"
					( attribute "PN" "DP85"
						( Origin gPackager )
					)
					( objectStatus "U2D1.DP85" )
				)
				( pin "ddr3_dqs_dp(2)"
					( attribute "PN" "DM81"
						( Origin gPackager )
					)
					( objectStatus "U2D1.DM81" )
				)
				( pin "ddr3_dqs_dp(3)"
					( attribute "PN" "DT75"
						( Origin gPackager )
					)
					( objectStatus "U2D1.DT75" )
				)
				( pin "ddr3_dqs_dp(4)"
					( attribute "PN" "EC38"
						( Origin gPackager )
					)
					( objectStatus "U2D1.EC38" )
				)
				( pin "ddr3_dqs_dp(5)"
					( attribute "PN" "DT35"
						( Origin gPackager )
					)
					( objectStatus "U2D1.DT35" )
				)
				( pin "ddr3_dqs_dp(6)"
					( attribute "PN" "DT29"
						( Origin gPackager )
					)
					( objectStatus "U2D1.DT29" )
				)
				( pin "ddr3_dqs_dp(7)"
					( attribute "PN" "DT23"
						( Origin gPackager )
					)
					( objectStatus "U2D1.DT23" )
				)
				( pin "ddr3_dqs_dp(8)"
					( attribute "PN" "DD67"
						( Origin gPackager )
					)
					( objectStatus "U2D1.DD67" )
				)
				( pin "ddr3_dqs_dp(9)"
					( attribute "PN" "CP85"
						( Origin gPackager )
					)
					( objectStatus "U2D1.CP85" )
				)
				( pin "ddr3_dqs_dp(10)"
					( attribute "PN" "DL84"
						( Origin gPackager )
					)
					( objectStatus "U2D1.DL84" )
				)
				( pin "ddr3_dqs_dp(11)"
					( attribute "PN" "DP79"
						( Origin gPackager )
					)
					( objectStatus "U2D1.DP79" )
				)
				( pin "ddr3_dqs_dp(12)"
					( attribute "PN" "DM75"
						( Origin gPackager )
					)
					( objectStatus "U2D1.DM75" )
				)
				( pin "ddr3_dqs_dp(13)"
					( attribute "PN" "DW38"
						( Origin gPackager )
					)
					( objectStatus "U2D1.DW38" )
				)
				( pin "ddr3_dqs_dp(14)"
					( attribute "PN" "DM35"
						( Origin gPackager )
					)
					( objectStatus "U2D1.DM35" )
				)
				( pin "ddr3_dqs_dp(15)"
					( attribute "PN" "DP29"
						( Origin gPackager )
					)
					( objectStatus "U2D1.DP29" )
				)
				( pin "ddr3_dqs_dp(16)"
					( attribute "PN" "DP23"
						( Origin gPackager )
					)
					( objectStatus "U2D1.DP23" )
				)
				( pin "ddr3_dqs_dp(17)"
					( attribute "PN" "CY67"
						( Origin gPackager )
					)
					( objectStatus "U2D1.CY67" )
				)
				( pin "ddr3_ecc(0)"
					( attribute "PN" "DA68"
						( Origin gPackager )
					)
					( objectStatus "U2D1.DA68" )
				)
				( pin "ddr3_ecc(1)"
					( attribute "PN" "DE68"
						( Origin gPackager )
					)
					( objectStatus "U2D1.DE68" )
				)
				( pin "ddr3_ecc(2)"
					( attribute "PN" "DB65"
						( Origin gPackager )
					)
					( objectStatus "U2D1.DB65" )
				)
				( pin "ddr3_ecc(3)"
					( attribute "PN" "DD65"
						( Origin gPackager )
					)
					( objectStatus "U2D1.DD65" )
				)
				( pin "ddr3_ecc(4)"
					( attribute "PN" "DB69"
						( Origin gPackager )
					)
					( objectStatus "U2D1.DB69" )
				)
				( pin "ddr3_ecc(5)"
					( attribute "PN" "DD69"
						( Origin gPackager )
					)
					( objectStatus "U2D1.DD69" )
				)
				( pin "ddr3_ecc(6)"
					( attribute "PN" "DA66"
						( Origin gPackager )
					)
					( objectStatus "U2D1.DA66" )
				)
				( pin "ddr3_ecc(7)"
					( attribute "PN" "DE66"
						( Origin gPackager )
					)
					( objectStatus "U2D1.DE66" )
				)
				( pin "ddr3_ma(0)"
					( attribute "PN" "EB53"
						( Origin gPackager )
					)
					( objectStatus "U2D1.EB53" )
				)
				( pin "ddr3_ma(1)"
					( attribute "PN" "ED57"
						( Origin gPackager )
					)
					( objectStatus "U2D1.ED57" )
				)
				( pin "ddr3_ma(2)"
					( attribute "PN" "EE58"
						( Origin gPackager )
					)
					( objectStatus "U2D1.EE58" )
				)
				( pin "ddr3_ma(3)"
					( attribute "PN" "EB57"
						( Origin gPackager )
					)
					( objectStatus "U2D1.EB57" )
				)
				( pin "ddr3_ma(4)"
					( attribute "PN" "ED59"
						( Origin gPackager )
					)
					( objectStatus "U2D1.ED59" )
				)
				( pin "ddr3_ma(5)"
					( attribute "PN" "EA58"
						( Origin gPackager )
					)
					( objectStatus "U2D1.EA58" )
				)
				( pin "ddr3_ma(6)"
					( attribute "PN" "EE60"
						( Origin gPackager )
					)
					( objectStatus "U2D1.EE60" )
				)
				( pin "ddr3_ma(7)"
					( attribute "PN" "EA60"
						( Origin gPackager )
					)
					( objectStatus "U2D1.EA60" )
				)
				( pin "ddr3_ma(8)"
					( attribute "PN" "EB59"
						( Origin gPackager )
					)
					( objectStatus "U2D1.EB59" )
				)
				( pin "ddr3_ma(9)"
					( attribute "PN" "EF61"
						( Origin gPackager )
					)
					( objectStatus "U2D1.EF61" )
				)
				( pin "ddr3_ma(10)"
					( attribute "PN" "DW54"
						( Origin gPackager )
					)
					( objectStatus "U2D1.DW54" )
				)
				( pin "ddr3_ma(11)"
					( attribute "PN" "EB61"
						( Origin gPackager )
					)
					( objectStatus "U2D1.EB61" )
				)
				( pin "ddr3_ma(12)"
					( attribute "PN" "DT63"
						( Origin gPackager )
					)
					( objectStatus "U2D1.DT63" )
				)
				( pin "ddr3_ma(13)"
					( attribute "PN" "DW48"
						( Origin gPackager )
					)
					( objectStatus "U2D1.DW48" )
				)
				( pin "ddr3_ma(14)"
					( attribute "PN" "ED51"
						( Origin gPackager )
					)
					( objectStatus "U2D1.ED51" )
				)
				( pin "ddr3_ma(15)"
					( attribute "PN" "DV49"
						( Origin gPackager )
					)
					( objectStatus "U2D1.DV49" )
				)
				( pin "ddr3_ma(16)"
					( attribute "PN" "EA52"
						( Origin gPackager )
					)
					( objectStatus "U2D1.EA52" )
				)
				( pin "ddr3_ma(17)"
					( attribute "PN" "EA46"
						( Origin gPackager )
					)
					( objectStatus "U2D1.EA46" )
				)
				( pin "ddr3_odt(0)"
					( attribute "PN" "EE50"
						( Origin gPackager )
					)
					( objectStatus "U2D1.EE50" )
				)
				( pin "ddr3_odt(1)"
					( attribute "PN" "EE48"
						( Origin gPackager )
					)
					( objectStatus "U2D1.EE48" )
				)
				( pin "ddr3_odt(2)"
					( attribute "PN" "EA50"
						( Origin gPackager )
					)
					( objectStatus "U2D1.EA50" )
				)
				( pin "ddr3_odt(3)"
					( attribute "PN" "EA48"
						( Origin gPackager )
					)
					( objectStatus "U2D1.EA48" )
				)
				( pin "ddr3_par"
					( attribute "PN" "ED53"
						( Origin gPackager )
					)
					( objectStatus "U2D1.ED53" )
				)
			)
			( gate "@baseboard_fab2_lib.baseboard_fab2(sch_1):page61_i172"
				( attribute "CDS_LIB" "chpset_lib"
					( Origin gPackager )
				)
				( attribute "CDS_LOCATION" "U2D1"
					( Origin gPackager )
				)
				( attribute "CDS_SEC" "7"
					( Origin gPackager )
				)
				( attribute "LOCATION" "U2D1"
					( Origin gFrontEnd )
				)
				( attribute "MATERIAL" "IC"
					( Origin gFrontEnd )
				)
				( attribute "PACK_TYPE" "BGA1"
					( Origin gFrontEnd )
				)
				( attribute "PART_NUMBER" "TBD"
					( Origin gFrontEnd )
				)
				( attribute "PHYS_PAGE" "61"
					( Origin gFrontEnd )
				)
				( attribute "ROT" "0"
					( Origin gFrontEnd )
				)
				( attribute "SEC" "7"
					( Origin gFrontEnd )
				)
				( attribute "SEC_TYPE" "BGA1"
					( Origin gFrontEnd )
				)
				( attribute "VER" "7"
					( Origin gFrontEnd )
				)
				( attribute "XY" "(-4175,2575)"
					( Origin gFrontEnd )
				)
				( attribute "CHIPS_PART_NAME" "SKX_EXT_B"
					( Origin gPackager )
				)
				( attribute "CDS_PART_NAME" "SKX_EXT_B_BGA1-IC,TBD"
					( Origin gPackager )
				)
				( objectStatus "U2D1" )
				( pin "ddr4_act_n"
					( attribute "PN" "DR62"
						( Origin gPackager )
					)
					( objectStatus "U2D1.DR62" )
				)
				( pin "ddr4_alert_n"
					( attribute "PN" "DT61"
						( Origin gPackager )
					)
					( objectStatus "U2D1.DT61" )
				)
				( pin "ddr4_ba(0)"
					( attribute "PN" "DM53"
						( Origin gPackager )
					)
					( objectStatus "U2D1.DM53" )
				)
				( pin "ddr4_ba(1)"
					( attribute "PN" "DV55"
						( Origin gPackager )
					)
					( objectStatus "U2D1.DV55" )
				)
				( pin "ddr4_bg(0)"
					( attribute "PN" "DJ62"
						( Origin gPackager )
					)
					( objectStatus "U2D1.DJ62" )
				)
				( pin "ddr4_bg(1)"
					( attribute "PN" "DM61"
						( Origin gPackager )
					)
					( objectStatus "U2D1.DM61" )
				)
				( pin "ddr4_cid(2)"
					( attribute "PN" "DT47"
						( Origin gPackager )
					)
					( objectStatus "U2D1.DT47" )
				)
				( pin "ddr4_cke(0)"
					( attribute "PN" "DM63"
						( Origin gPackager )
					)
					( objectStatus "U2D1.DM63" )
				)
				( pin "ddr4_cke(1)"
					( attribute "PN" "DN64"
						( Origin gPackager )
					)
					( objectStatus "U2D1.DN64" )
				)
				( pin "ddr4_cke(2)"
					( attribute "PN" "DL64"
						( Origin gPackager )
					)
					( objectStatus "U2D1.DL64" )
				)
				( pin "ddr4_cke(3)"
					( attribute "PN" "DR64"
						( Origin gPackager )
					)
					( objectStatus "U2D1.DR64" )
				)
				( pin "ddr4_clk_dn(0)"
					( attribute "PN" "DM55"
						( Origin gPackager )
					)
					( objectStatus "U2D1.DM55" )
				)
				( pin "ddr4_clk_dn(1)"
					( attribute "PN" "DR54"
						( Origin gPackager )
					)
					( objectStatus "U2D1.DR54" )
				)
				( pin "ddr4_clk_dn(2)"
					( attribute "PN" "DM57"
						( Origin gPackager )
					)
					( objectStatus "U2D1.DM57" )
				)
				( pin "ddr4_clk_dn(3)"
					( attribute "PN" "DT57"
						( Origin gPackager )
					)
					( objectStatus "U2D1.DT57" )
				)
				( pin "ddr4_clk_dp(0)"
					( attribute "PN" "DN54"
						( Origin gPackager )
					)
					( objectStatus "U2D1.DN54" )
				)
				( pin "ddr4_clk_dp(1)"
					( attribute "PN" "DT53"
						( Origin gPackager )
					)
					( objectStatus "U2D1.DT53" )
				)
				( pin "ddr4_clk_dp(2)"
					( attribute "PN" "DN56"
						( Origin gPackager )
					)
					( objectStatus "U2D1.DN56" )
				)
				( pin "ddr4_clk_dp(3)"
					( attribute "PN" "DR56"
						( Origin gPackager )
					)
					( objectStatus "U2D1.DR56" )
				)
				( pin "ddr4_cs_n(0)"
					( attribute "PN" "DV51"
						( Origin gPackager )
					)
					( objectStatus "U2D1.DV51" )
				)
				( pin "ddr4_cs_n(1)"
					( attribute "PN" "DN50"
						( Origin gPackager )
					)
					( objectStatus "U2D1.DN50" )
				)
				( pin "ddr4_cs_n(2)"
					( attribute "PN" "DR46"
						( Origin gPackager )
					)
					( objectStatus "U2D1.DR46" )
				)
				( pin "ddr4_cs_n(3)"
					( attribute "PN" "DK47"
						( Origin gPackager )
					)
					( objectStatus "U2D1.DK47" )
				)
				( pin "ddr4_cs_n(4)"
					( attribute "PN" "DW50"
						( Origin gPackager )
					)
					( objectStatus "U2D1.DW50" )
				)
				( pin "ddr4_cs_n(5)"
					( attribute "PN" "DM49"
						( Origin gPackager )
					)
					( objectStatus "U2D1.DM49" )
				)
				( pin "ddr4_cs_n(6)"
					( attribute "PN" "DT45"
						( Origin gPackager )
					)
					( objectStatus "U2D1.DT45" )
				)
				( pin "ddr4_cs_n(7)"
					( attribute "PN" "DN46"
						( Origin gPackager )
					)
					( objectStatus "U2D1.DN46" )
				)
				( pin "ddr4_dq(0)"
					( attribute "PN" "CM79"
						( Origin gPackager )
					)
					( objectStatus "U2D1.CM79" )
				)
				( pin "ddr4_dq(1)"
					( attribute "PN" "CK81"
						( Origin gPackager )
					)
					( objectStatus "U2D1.CK81" )
				)
				( pin "ddr4_dq(2)"
					( attribute "PN" "CT81"
						( Origin gPackager )
					)
					( objectStatus "U2D1.CT81" )
				)
				( pin "ddr4_dq(3)"
					( attribute "PN" "CR82"
						( Origin gPackager )
					)
					( objectStatus "U2D1.CR82" )
				)
				( pin "ddr4_dq(4)"
					( attribute "PN" "CK79"
						( Origin gPackager )
					)
					( objectStatus "U2D1.CK79" )
				)
				( pin "ddr4_dq(5)"
					( attribute "PN" "CJ80"
						( Origin gPackager )
					)
					( objectStatus "U2D1.CJ80" )
				)
				( pin "ddr4_dq(6)"
					( attribute "PN" "CR80"
						( Origin gPackager )
					)
					( objectStatus "U2D1.CR80" )
				)
				( pin "ddr4_dq(7)"
					( attribute "PN" "CN82"
						( Origin gPackager )
					)
					( objectStatus "U2D1.CN82" )
				)
				( pin "ddr4_dq(8)"
					( attribute "PN" "DB79"
						( Origin gPackager )
					)
					( objectStatus "U2D1.DB79" )
				)
				( pin "ddr4_dq(9)"
					( attribute "PN" "CY81"
						( Origin gPackager )
					)
					( objectStatus "U2D1.CY81" )
				)
				( pin "ddr4_dq(10)"
					( attribute "PN" "DE80"
						( Origin gPackager )
					)
					( objectStatus "U2D1.DE80" )
				)
				( pin "ddr4_dq(11)"
					( attribute "PN" "DF81"
						( Origin gPackager )
					)
					( objectStatus "U2D1.DF81" )
				)
				( pin "ddr4_dq(12)"
					( attribute "PN" "CY79"
						( Origin gPackager )
					)
					( objectStatus "U2D1.CY79" )
				)
				( pin "ddr4_dq(13)"
					( attribute "PN" "CW80"
						( Origin gPackager )
					)
					( objectStatus "U2D1.CW80" )
				)
				( pin "ddr4_dq(14)"
					( attribute "PN" "DC82"
						( Origin gPackager )
					)
					( objectStatus "U2D1.DC82" )
				)
				( pin "ddr4_dq(15)"
					( attribute "PN" "DE82"
						( Origin gPackager )
					)
					( objectStatus "U2D1.DE82" )
				)
				( pin "ddr4_dq(16)"
					( attribute "PN" "DW80"
						( Origin gPackager )
					)
					( objectStatus "U2D1.DW80" )
				)
				( pin "ddr4_dq(17)"
					( attribute "PN" "EC80"
						( Origin gPackager )
					)
					( objectStatus "U2D1.EC80" )
				)
				( pin "ddr4_dq(18)"
					( attribute "PN" "DY77"
						( Origin gPackager )
					)
					( objectStatus "U2D1.DY77" )
				)
				( pin "ddr4_dq(19)"
					( attribute "PN" "EB77"
						( Origin gPackager )
					)
					( objectStatus "U2D1.EB77" )
				)
				( pin "ddr4_dq(20)"
					( attribute "PN" "DY81"
						( Origin gPackager )
					)
					( objectStatus "U2D1.DY81" )
				)
				( pin "ddr4_dq(21)"
					( attribute "PN" "EB81"
						( Origin gPackager )
					)
					( objectStatus "U2D1.EB81" )
				)
				( pin "ddr4_dq(22)"
					( attribute "PN" "DW78"
						( Origin gPackager )
					)
					( objectStatus "U2D1.DW78" )
				)
				( pin "ddr4_dq(23)"
					( attribute "PN" "EC78"
						( Origin gPackager )
					)
					( objectStatus "U2D1.EC78" )
				)
				( pin "ddr4_dq(24)"
					( attribute "PN" "ED75"
						( Origin gPackager )
					)
					( objectStatus "U2D1.ED75" )
				)
				( pin "ddr4_dq(25)"
					( attribute "PN" "EE74"
						( Origin gPackager )
					)
					( objectStatus "U2D1.EE74" )
				)
				( pin "ddr4_dq(26)"
					( attribute "PN" "EB71"
						( Origin gPackager )
					)
					( objectStatus "U2D1.EB71" )
				)
				( pin "ddr4_dq(27)"
					( attribute "PN" "ED71"
						( Origin gPackager )
					)
					( objectStatus "U2D1.ED71" )
				)
				( pin "ddr4_dq(28)"
					( attribute "PN" "EA74"
						( Origin gPackager )
					)
					( objectStatus "U2D1.EA74" )
				)
				( pin "ddr4_dq(29)"
					( attribute "PN" "EB75"
						( Origin gPackager )
					)
					( objectStatus "U2D1.EB75" )
				)
				( pin "ddr4_dq(30)"
					( attribute "PN" "EA72"
						( Origin gPackager )
					)
					( objectStatus "U2D1.EA72" )
				)
				( pin "ddr4_dq(31)"
					( attribute "PN" "EE72"
						( Origin gPackager )
					)
					( objectStatus "U2D1.EE72" )
				)
				( pin "ddr4_dq(32)"
					( attribute "PN" "DU42"
						( Origin gPackager )
					)
					( objectStatus "U2D1.DU42" )
				)
				( pin "ddr4_dq(33)"
					( attribute "PN" "DW42"
						( Origin gPackager )
					)
					( objectStatus "U2D1.DW42" )
				)
				( pin "ddr4_dq(34)"
					( attribute "PN" "DP39"
						( Origin gPackager )
					)
					( objectStatus "U2D1.DP39" )
				)
				( pin "ddr4_dq(35)"
					( attribute "PN" "DT39"
						( Origin gPackager )
					)
					( objectStatus "U2D1.DT39" )
				)
				( pin "ddr4_dq(36)"
					( attribute "PN" "DL42"
						( Origin gPackager )
					)
					( objectStatus "U2D1.DL42" )
				)
				( pin "ddr4_dq(37)"
					( attribute "PN" "DN42"
						( Origin gPackager )
					)
					( objectStatus "U2D1.DN42" )
				)
				( pin "ddr4_dq(38)"
					( attribute "PN" "DN40"
						( Origin gPackager )
					)
					( objectStatus "U2D1.DN40" )
				)
				( pin "ddr4_dq(39)"
					( attribute "PN" "DU40"
						( Origin gPackager )
					)
					( objectStatus "U2D1.DU40" )
				)
				( pin "ddr4_dq(40)"
					( attribute "PN" "EC34"
						( Origin gPackager )
					)
					( objectStatus "U2D1.EC34" )
				)
				( pin "ddr4_dq(41)"
					( attribute "PN" "ED33"
						( Origin gPackager )
					)
					( objectStatus "U2D1.ED33" )
				)
				( pin "ddr4_dq(42)"
					( attribute "PN" "EA30"
						( Origin gPackager )
					)
					( objectStatus "U2D1.EA30" )
				)
				( pin "ddr4_dq(43)"
					( attribute "PN" "EC30"
						( Origin gPackager )
					)
					( objectStatus "U2D1.EC30" )
				)
				( pin "ddr4_dq(44)"
					( attribute "PN" "DY33"
						( Origin gPackager )
					)
					( objectStatus "U2D1.DY33" )
				)
				( pin "ddr4_dq(45)"
					( attribute "PN" "EA34"
						( Origin gPackager )
					)
					( objectStatus "U2D1.EA34" )
				)
				( pin "ddr4_dq(46)"
					( attribute "PN" "DY31"
						( Origin gPackager )
					)
					( objectStatus "U2D1.DY31" )
				)
				( pin "ddr4_dq(47)"
					( attribute "PN" "ED31"
						( Origin gPackager )
					)
					( objectStatus "U2D1.ED31" )
				)
				( pin "ddr4_dq(48)"
					( attribute "PN" "EC28"
						( Origin gPackager )
					)
					( objectStatus "U2D1.EC28" )
				)
				( pin "ddr4_dq(49)"
					( attribute "PN" "ED27"
						( Origin gPackager )
					)
					( objectStatus "U2D1.ED27" )
				)
				( pin "ddr4_dq(50)"
					( attribute "PN" "EA24"
						( Origin gPackager )
					)
					( objectStatus "U2D1.EA24" )
				)
				( pin "ddr4_dq(51)"
					( attribute "PN" "EC24"
						( Origin gPackager )
					)
					( objectStatus "U2D1.EC24" )
				)
				( pin "ddr4_dq(52)"
					( attribute "PN" "DY27"
						( Origin gPackager )
					)
					( objectStatus "U2D1.DY27" )
				)
				( pin "ddr4_dq(53)"
					( attribute "PN" "EA28"
						( Origin gPackager )
					)
					( objectStatus "U2D1.EA28" )
				)
				( pin "ddr4_dq(54)"
					( attribute "PN" "DY25"
						( Origin gPackager )
					)
					( objectStatus "U2D1.DY25" )
				)
				( pin "ddr4_dq(55)"
					( attribute "PN" "ED25"
						( Origin gPackager )
					)
					( objectStatus "U2D1.ED25" )
				)
				( pin "ddr4_dq(56)"
					( attribute "PN" "DF27"
						( Origin gPackager )
					)
					( objectStatus "U2D1.DF27" )
				)
				( pin "ddr4_dq(57)"
					( attribute "PN" "DK27"
						( Origin gPackager )
					)
					( objectStatus "U2D1.DK27" )
				)
				( pin "ddr4_dq(58)"
					( attribute "PN" "DD25"
						( Origin gPackager )
					)
					( objectStatus "U2D1.DD25" )
				)
				( pin "ddr4_dq(59)"
					( attribute "PN" "DJ24"
						( Origin gPackager )
					)
					( objectStatus "U2D1.DJ24" )
				)
				( pin "ddr4_dq(60)"
					( attribute "PN" "DG28"
						( Origin gPackager )
					)
					( objectStatus "U2D1.DG28" )
				)
				( pin "ddr4_dq(61)"
					( attribute "PN" "DJ28"
						( Origin gPackager )
					)
					( objectStatus "U2D1.DJ28" )
				)
				( pin "ddr4_dq(62)"
					( attribute "PN" "DF25"
						( Origin gPackager )
					)
					( objectStatus "U2D1.DF25" )
				)
				( pin "ddr4_dq(63)"
					( attribute "PN" "DK25"
						( Origin gPackager )
					)
					( objectStatus "U2D1.DK25" )
				)
				( pin "ddr4_dqs_dn(0)"
					( attribute "PN" "CL82"
						( Origin gPackager )
					)
					( objectStatus "U2D1.CL82" )
				)
				( pin "ddr4_dqs_dn(1)"
					( attribute "PN" "DA82"
						( Origin gPackager )
					)
					( objectStatus "U2D1.DA82" )
				)
				( pin "ddr4_dqs_dn(2)"
					( attribute "PN" "ED79"
						( Origin gPackager )
					)
					( objectStatus "U2D1.ED79" )
				)
				( pin "ddr4_dqs_dn(3)"
					( attribute "PN" "EF73"
						( Origin gPackager )
					)
					( objectStatus "U2D1.EF73" )
				)
				( pin "ddr4_dqs_dn(4)"
					( attribute "PN" "DV41"
						( Origin gPackager )
					)
					( objectStatus "U2D1.DV41" )
				)
				( pin "ddr4_dqs_dn(5)"
					( attribute "PN" "EE32"
						( Origin gPackager )
					)
					( objectStatus "U2D1.EE32" )
				)
				( pin "ddr4_dqs_dn(6)"
					( attribute "PN" "EE26"
						( Origin gPackager )
					)
					( objectStatus "U2D1.EE26" )
				)
				( pin "ddr4_dqs_dn(7)"
					( attribute "PN" "DL26"
						( Origin gPackager )
					)
					( objectStatus "U2D1.DL26" )
				)
				( pin "ddr4_dqs_dn(8)"
					( attribute "PN" "EB67"
						( Origin gPackager )
					)
					( objectStatus "U2D1.EB67" )
				)
				( pin "ddr4_dqs_dn(9)"
					( attribute "PN" "CN80"
						( Origin gPackager )
					)
					( objectStatus "U2D1.CN80" )
				)
				( pin "ddr4_dqs_dn(10)"
					( attribute "PN" "DC80"
						( Origin gPackager )
					)
					( objectStatus "U2D1.DC80" )
				)
				( pin "ddr4_dqs_dn(11)"
					( attribute "PN" "DY79"
						( Origin gPackager )
					)
					( objectStatus "U2D1.DY79" )
				)
				( pin "ddr4_dqs_dn(12)"
					( attribute "PN" "EB73"
						( Origin gPackager )
					)
					( objectStatus "U2D1.EB73" )
				)
				( pin "ddr4_dqs_dn(13)"
					( attribute "PN" "DP41"
						( Origin gPackager )
					)
					( objectStatus "U2D1.DP41" )
				)
				( pin "ddr4_dqs_dn(14)"
					( attribute "PN" "EA32"
						( Origin gPackager )
					)
					( objectStatus "U2D1.EA32" )
				)
				( pin "ddr4_dqs_dn(15)"
					( attribute "PN" "EA26"
						( Origin gPackager )
					)
					( objectStatus "U2D1.EA26" )
				)
				( pin "ddr4_dqs_dn(16)"
					( attribute "PN" "DG26"
						( Origin gPackager )
					)
					( objectStatus "U2D1.DG26" )
				)
				( pin "ddr4_dqs_dn(17)"
					( attribute "PN" "DV67"
						( Origin gPackager )
					)
					( objectStatus "U2D1.DV67" )
				)
				( pin "ddr4_dqs_dp(0)"
					( attribute "PN" "CM81"
						( Origin gPackager )
					)
					( objectStatus "U2D1.CM81" )
				)
				( pin "ddr4_dqs_dp(1)"
					( attribute "PN" "DB81"
						( Origin gPackager )
					)
					( objectStatus "U2D1.DB81" )
				)
				( pin "ddr4_dqs_dp(2)"
					( attribute "PN" "EB79"
						( Origin gPackager )
					)
					( objectStatus "U2D1.EB79" )
				)
				( pin "ddr4_dqs_dp(3)"
					( attribute "PN" "ED73"
						( Origin gPackager )
					)
					( objectStatus "U2D1.ED73" )
				)
				( pin "ddr4_dqs_dp(4)"
					( attribute "PN" "DT41"
						( Origin gPackager )
					)
					( objectStatus "U2D1.DT41" )
				)
				( pin "ddr4_dqs_dp(5)"
					( attribute "PN" "EC32"
						( Origin gPackager )
					)
					( objectStatus "U2D1.EC32" )
				)
				( pin "ddr4_dqs_dp(6)"
					( attribute "PN" "EC26"
						( Origin gPackager )
					)
					( objectStatus "U2D1.EC26" )
				)
				( pin "ddr4_dqs_dp(7)"
					( attribute "PN" "DJ26"
						( Origin gPackager )
					)
					( objectStatus "U2D1.DJ26" )
				)
				( pin "ddr4_dqs_dp(8)"
					( attribute "PN" "DY67"
						( Origin gPackager )
					)
					( objectStatus "U2D1.DY67" )
				)
				( pin "ddr4_dqs_dp(9)"
					( attribute "PN" "CP79"
						( Origin gPackager )
					)
					( objectStatus "U2D1.CP79" )
				)
				( pin "ddr4_dqs_dp(10)"
					( attribute "PN" "DD79"
						( Origin gPackager )
					)
					( objectStatus "U2D1.DD79" )
				)
				( pin "ddr4_dqs_dp(11)"
					( attribute "PN" "DV79"
						( Origin gPackager )
					)
					( objectStatus "U2D1.DV79" )
				)
				( pin "ddr4_dqs_dp(12)"
					( attribute "PN" "DY73"
						( Origin gPackager )
					)
					( objectStatus "U2D1.DY73" )
				)
				( pin "ddr4_dqs_dp(13)"
					( attribute "PN" "DM41"
						( Origin gPackager )
					)
					( objectStatus "U2D1.DM41" )
				)
				( pin "ddr4_dqs_dp(14)"
					( attribute "PN" "DW32"
						( Origin gPackager )
					)
					( objectStatus "U2D1.DW32" )
				)
				( pin "ddr4_dqs_dp(15)"
					( attribute "PN" "DW26"
						( Origin gPackager )
					)
					( objectStatus "U2D1.DW26" )
				)
				( pin "ddr4_dqs_dp(16)"
					( attribute "PN" "DE26"
						( Origin gPackager )
					)
					( objectStatus "U2D1.DE26" )
				)
				( pin "ddr4_dqs_dp(17)"
					( attribute "PN" "DT67"
						( Origin gPackager )
					)
					( objectStatus "U2D1.DT67" )
				)
				( pin "ddr4_ecc(0)"
					( attribute "PN" "DY69"
						( Origin gPackager )
					)
					( objectStatus "U2D1.DY69" )
				)
				( pin "ddr4_ecc(1)"
					( attribute "PN" "EA68"
						( Origin gPackager )
					)
					( objectStatus "U2D1.EA68" )
				)
				( pin "ddr4_ecc(2)"
					( attribute "PN" "DV65"
						( Origin gPackager )
					)
					( objectStatus "U2D1.DV65" )
				)
				( pin "ddr4_ecc(3)"
					( attribute "PN" "DY65"
						( Origin gPackager )
					)
					( objectStatus "U2D1.DY65" )
				)
				( pin "ddr4_ecc(4)"
					( attribute "PN" "DU68"
						( Origin gPackager )
					)
					( objectStatus "U2D1.DU68" )
				)
				( pin "ddr4_ecc(5)"
					( attribute "PN" "DV69"
						( Origin gPackager )
					)
					( objectStatus "U2D1.DV69" )
				)
				( pin "ddr4_ecc(6)"
					( attribute "PN" "DU66"
						( Origin gPackager )
					)
					( objectStatus "U2D1.DU66" )
				)
				( pin "ddr4_ecc(7)"
					( attribute "PN" "EA66"
						( Origin gPackager )
					)
					( objectStatus "U2D1.EA66" )
				)
				( pin "ddr4_ma(0)"
					( attribute "PN" "DW52"
						( Origin gPackager )
					)
					( objectStatus "U2D1.DW52" )
				)
				( pin "ddr4_ma(1)"
					( attribute "PN" "DW58"
						( Origin gPackager )
					)
					( objectStatus "U2D1.DW58" )
				)
				( pin "ddr4_ma(2)"
					( attribute "PN" "DV57"
						( Origin gPackager )
					)
					( objectStatus "U2D1.DV57" )
				)
				( pin "ddr4_ma(3)"
					( attribute "PN" "DR58"
						( Origin gPackager )
					)
					( objectStatus "U2D1.DR58" )
				)
				( pin "ddr4_ma(4)"
					( attribute "PN" "DT59"
						( Origin gPackager )
					)
					( objectStatus "U2D1.DT59" )
				)
				( pin "ddr4_ma(5)"
					( attribute "PN" "DN58"
						( Origin gPackager )
					)
					( objectStatus "U2D1.DN58" )
				)
				( pin "ddr4_ma(6)"
					( attribute "PN" "DM59"
						( Origin gPackager )
					)
					( objectStatus "U2D1.DM59" )
				)
				( pin "ddr4_ma(7)"
					( attribute "PN" "DK61"
						( Origin gPackager )
					)
					( objectStatus "U2D1.DK61" )
				)
				( pin "ddr4_ma(8)"
					( attribute "PN" "DJ60"
						( Origin gPackager )
					)
					( objectStatus "U2D1.DJ60" )
				)
				( pin "ddr4_ma(9)"
					( attribute "PN" "DV59"
						( Origin gPackager )
					)
					( objectStatus "U2D1.DV59" )
				)
				( pin "ddr4_ma(10)"
					( attribute "PN" "DT55"
						( Origin gPackager )
					)
					( objectStatus "U2D1.DT55" )
				)
				( pin "ddr4_ma(11)"
					( attribute "PN" "DR60"
						( Origin gPackager )
					)
					( objectStatus "U2D1.DR60" )
				)
				( pin "ddr4_ma(12)"
					( attribute "PN" "DN60"
						( Origin gPackager )
					)
					( objectStatus "U2D1.DN60" )
				)
				( pin "ddr4_ma(13)"
					( attribute "PN" "DT51"
						( Origin gPackager )
					)
					( objectStatus "U2D1.DT51" )
				)
				( pin "ddr4_ma(14)"
					( attribute "PN" "DM51"
						( Origin gPackager )
					)
					( objectStatus "U2D1.DM51" )
				)
				( pin "ddr4_ma(15)"
					( attribute "PN" "DR52"
						( Origin gPackager )
					)
					( objectStatus "U2D1.DR52" )
				)
				( pin "ddr4_ma(16)"
					( attribute "PN" "DN52"
						( Origin gPackager )
					)
					( objectStatus "U2D1.DN52" )
				)
				( pin "ddr4_ma(17)"
					( attribute "PN" "DR48"
						( Origin gPackager )
					)
					( objectStatus "U2D1.DR48" )
				)
				( pin "ddr4_odt(0)"
					( attribute "PN" "DR50"
						( Origin gPackager )
					)
					( objectStatus "U2D1.DR50" )
				)
				( pin "ddr4_odt(1)"
					( attribute "PN" "DN48"
						( Origin gPackager )
					)
					( objectStatus "U2D1.DN48" )
				)
				( pin "ddr4_odt(2)"
					( attribute "PN" "DT49"
						( Origin gPackager )
					)
					( objectStatus "U2D1.DT49" )
				)
				( pin "ddr4_odt(3)"
					( attribute "PN" "DM47"
						( Origin gPackager )
					)
					( objectStatus "U2D1.DM47" )
				)
				( pin "ddr4_par"
					( attribute "PN" "DV53"
						( Origin gPackager )
					)
					( objectStatus "U2D1.DV53" )
				)
			)
			( gate "@baseboard_fab2_lib.baseboard_fab2(sch_1):page62_i172"
				( attribute "CDS_LIB" "chpset_lib"
					( Origin gPackager )
				)
				( attribute "CDS_LOCATION" "U2D1"
					( Origin gPackager )
				)
				( attribute "CDS_SEC" "8"
					( Origin gPackager )
				)
				( attribute "LOCATION" "U2D1"
					( Origin gFrontEnd )
				)
				( attribute "MATERIAL" "IC"
					( Origin gFrontEnd )
				)
				( attribute "PACK_TYPE" "BGA1"
					( Origin gFrontEnd )
				)
				( attribute "PART_NUMBER" "TBD"
					( Origin gFrontEnd )
				)
				( attribute "PHYS_PAGE" "62"
					( Origin gFrontEnd )
				)
				( attribute "ROT" "0"
					( Origin gFrontEnd )
				)
				( attribute "SEC" "8"
					( Origin gFrontEnd )
				)
				( attribute "SEC_TYPE" "BGA1"
					( Origin gFrontEnd )
				)
				( attribute "VER" "8"
					( Origin gFrontEnd )
				)
				( attribute "XY" "(-4200,2550)"
					( Origin gFrontEnd )
				)
				( attribute "CHIPS_PART_NAME" "SKX_EXT_B"
					( Origin gPackager )
				)
				( attribute "CDS_PART_NAME" "SKX_EXT_B_BGA1-IC,TBD"
					( Origin gPackager )
				)
				( objectStatus "U2D1" )
				( pin "ddr5_act_n"
					( attribute "PN" "DC62"
						( Origin gPackager )
					)
					( objectStatus "U2D1.DC62" )
				)
				( pin "ddr5_alert_n"
					( attribute "PN" "DD61"
						( Origin gPackager )
					)
					( objectStatus "U2D1.DD61" )
				)
				( pin "ddr5_ba(0)"
					( attribute "PN" "DJ52"
						( Origin gPackager )
					)
					( objectStatus "U2D1.DJ52" )
				)
				( pin "ddr5_ba(1)"
					( attribute "PN" "DC56"
						( Origin gPackager )
					)
					( objectStatus "U2D1.DC56" )
				)
				( pin "ddr5_bg(0)"
					( attribute "PN" "DA62"
						( Origin gPackager )
					)
					( objectStatus "U2D1.DA62" )
				)
				( pin "ddr5_bg(1)"
					( attribute "PN" "DF61"
						( Origin gPackager )
					)
					( objectStatus "U2D1.DF61" )
				)
				( pin "ddr5_cid(2)"
					( attribute "PN" "DF45"
						( Origin gPackager )
					)
					( objectStatus "U2D1.DF45" )
				)
				( pin "ddr5_cke(0)"
					( attribute "PN" "DG62"
						( Origin gPackager )
					)
					( objectStatus "U2D1.DG62" )
				)
				( pin "ddr5_cke(1)"
					( attribute "PN" "DD63"
						( Origin gPackager )
					)
					( objectStatus "U2D1.DD63" )
				)
				( pin "ddr5_cke(2)"
					( attribute "PN" "DK63"
						( Origin gPackager )
					)
					( objectStatus "U2D1.DK63" )
				)
				( pin "ddr5_cke(3)"
					( attribute "PN" "DF63"
						( Origin gPackager )
					)
					( objectStatus "U2D1.DF63" )
				)
				( pin "ddr5_clk_dn(0)"
					( attribute "PN" "DK55"
						( Origin gPackager )
					)
					( objectStatus "U2D1.DK55" )
				)
				( pin "ddr5_clk_dn(1)"
					( attribute "PN" "DF55"
						( Origin gPackager )
					)
					( objectStatus "U2D1.DF55" )
				)
				( pin "ddr5_clk_dn(2)"
					( attribute "PN" "DK57"
						( Origin gPackager )
					)
					( objectStatus "U2D1.DK57" )
				)
				( pin "ddr5_clk_dn(3)"
					( attribute "PN" "DF57"
						( Origin gPackager )
					)
					( objectStatus "U2D1.DF57" )
				)
				( pin "ddr5_clk_dp(0)"
					( attribute "PN" "DJ54"
						( Origin gPackager )
					)
					( objectStatus "U2D1.DJ54" )
				)
				( pin "ddr5_clk_dp(1)"
					( attribute "PN" "DG54"
						( Origin gPackager )
					)
					( objectStatus "U2D1.DG54" )
				)
				( pin "ddr5_clk_dp(2)"
					( attribute "PN" "DJ56"
						( Origin gPackager )
					)
					( objectStatus "U2D1.DJ56" )
				)
				( pin "ddr5_clk_dp(3)"
					( attribute "PN" "DG56"
						( Origin gPackager )
					)
					( objectStatus "U2D1.DG56" )
				)
				( pin "ddr5_cs_n(0)"
					( attribute "PN" "DK51"
						( Origin gPackager )
					)
					( objectStatus "U2D1.DK51" )
				)
				( pin "ddr5_cs_n(1)"
					( attribute "PN" "DF49"
						( Origin gPackager )
					)
					( objectStatus "U2D1.DF49" )
				)
				( pin "ddr5_cs_n(2)"
					( attribute "PN" "DJ46"
						( Origin gPackager )
					)
					( objectStatus "U2D1.DJ46" )
				)
				( pin "ddr5_cs_n(3)"
					( attribute "PN" "DG46"
						( Origin gPackager )
					)
					( objectStatus "U2D1.DG46" )
				)
				( pin "ddr5_cs_n(4)"
					( attribute "PN" "DF51"
						( Origin gPackager )
					)
					( objectStatus "U2D1.DF51" )
				)
				( pin "ddr5_cs_n(5)"
					( attribute "PN" "DJ48"
						( Origin gPackager )
					)
					( objectStatus "U2D1.DJ48" )
				)
				( pin "ddr5_cs_n(6)"
					( attribute "PN" "DM45"
						( Origin gPackager )
					)
					( objectStatus "U2D1.DM45" )
				)
				( pin "ddr5_cs_n(7)"
					( attribute "PN" "DK45"
						( Origin gPackager )
					)
					( objectStatus "U2D1.DK45" )
				)
				( pin "ddr5_dq(0)"
					( attribute "PN" "CR74"
						( Origin gPackager )
					)
					( objectStatus "U2D1.CR74" )
				)
				( pin "ddr5_dq(1)"
					( attribute "PN" "CN76"
						( Origin gPackager )
					)
					( objectStatus "U2D1.CN76" )
				)
				( pin "ddr5_dq(2)"
					( attribute "PN" "CW76"
						( Origin gPackager )
					)
					( objectStatus "U2D1.CW76" )
				)
				( pin "ddr5_dq(3)"
					( attribute "PN" "CV77"
						( Origin gPackager )
					)
					( objectStatus "U2D1.CV77" )
				)
				( pin "ddr5_dq(4)"
					( attribute "PN" "CN74"
						( Origin gPackager )
					)
					( objectStatus "U2D1.CN74" )
				)
				( pin "ddr5_dq(5)"
					( attribute "PN" "CM75"
						( Origin gPackager )
					)
					( objectStatus "U2D1.CM75" )
				)
				( pin "ddr5_dq(6)"
					( attribute "PN" "CV75"
						( Origin gPackager )
					)
					( objectStatus "U2D1.CV75" )
				)
				( pin "ddr5_dq(7)"
					( attribute "PN" "CT77"
						( Origin gPackager )
					)
					( objectStatus "U2D1.CT77" )
				)
				( pin "ddr5_dq(8)"
					( attribute "PN" "DE74"
						( Origin gPackager )
					)
					( objectStatus "U2D1.DE74" )
				)
				( pin "ddr5_dq(9)"
					( attribute "PN" "DC76"
						( Origin gPackager )
					)
					( objectStatus "U2D1.DC76" )
				)
				( pin "ddr5_dq(10)"
					( attribute "PN" "DH75"
						( Origin gPackager )
					)
					( objectStatus "U2D1.DH75" )
				)
				( pin "ddr5_dq(11)"
					( attribute "PN" "DJ76"
						( Origin gPackager )
					)
					( objectStatus "U2D1.DJ76" )
				)
				( pin "ddr5_dq(12)"
					( attribute "PN" "DC74"
						( Origin gPackager )
					)
					( objectStatus "U2D1.DC74" )
				)
				( pin "ddr5_dq(13)"
					( attribute "PN" "DB75"
						( Origin gPackager )
					)
					( objectStatus "U2D1.DB75" )
				)
				( pin "ddr5_dq(14)"
					( attribute "PN" "DF77"
						( Origin gPackager )
					)
					( objectStatus "U2D1.DF77" )
				)
				( pin "ddr5_dq(15)"
					( attribute "PN" "DH77"
						( Origin gPackager )
					)
					( objectStatus "U2D1.DH77" )
				)
				( pin "ddr5_dq(16)"
					( attribute "PN" "DG70"
						( Origin gPackager )
					)
					( objectStatus "U2D1.DG70" )
				)
				( pin "ddr5_dq(17)"
					( attribute "PN" "DJ72"
						( Origin gPackager )
					)
					( objectStatus "U2D1.DJ72" )
				)
				( pin "ddr5_dq(18)"
					( attribute "PN" "DM69"
						( Origin gPackager )
					)
					( objectStatus "U2D1.DM69" )
				)
				( pin "ddr5_dq(19)"
					( attribute "PN" "DN70"
						( Origin gPackager )
					)
					( objectStatus "U2D1.DN70" )
				)
				( pin "ddr5_dq(20)"
					( attribute "PN" "DF71"
						( Origin gPackager )
					)
					( objectStatus "U2D1.DF71" )
				)
				( pin "ddr5_dq(21)"
					( attribute "PN" "DG72"
						( Origin gPackager )
					)
					( objectStatus "U2D1.DG72" )
				)
				( pin "ddr5_dq(22)"
					( attribute "PN" "DK69"
						( Origin gPackager )
					)
					( objectStatus "U2D1.DK69" )
				)
				( pin "ddr5_dq(23)"
					( attribute "PN" "DM71"
						( Origin gPackager )
					)
					( objectStatus "U2D1.DM71" )
				)
				( pin "ddr5_dq(24)"
					( attribute "PN" "CN66"
						( Origin gPackager )
					)
					( objectStatus "U2D1.CN66" )
				)
				( pin "ddr5_dq(25)"
					( attribute "PN" "CU66"
						( Origin gPackager )
					)
					( objectStatus "U2D1.CU66" )
				)
				( pin "ddr5_dq(26)"
					( attribute "PN" "CP63"
						( Origin gPackager )
					)
					( objectStatus "U2D1.CP63" )
				)
				( pin "ddr5_dq(27)"
					( attribute "PN" "CT63"
						( Origin gPackager )
					)
					( objectStatus "U2D1.CT63" )
				)
				( pin "ddr5_dq(28)"
					( attribute "PN" "CP67"
						( Origin gPackager )
					)
					( objectStatus "U2D1.CP67" )
				)
				( pin "ddr5_dq(29)"
					( attribute "PN" "CT67"
						( Origin gPackager )
					)
					( objectStatus "U2D1.CT67" )
				)
				( pin "ddr5_dq(30)"
					( attribute "PN" "CN64"
						( Origin gPackager )
					)
					( objectStatus "U2D1.CN64" )
				)
				( pin "ddr5_dq(31)"
					( attribute "PN" "CU64"
						( Origin gPackager )
					)
					( objectStatus "U2D1.CU64" )
				)
				( pin "ddr5_dq(32)"
					( attribute "PN" "DD41"
						( Origin gPackager )
					)
					( objectStatus "U2D1.DD41" )
				)
				( pin "ddr5_dq(33)"
					( attribute "PN" "DG42"
						( Origin gPackager )
					)
					( objectStatus "U2D1.DG42" )
				)
				( pin "ddr5_dq(34)"
					( attribute "PN" "DE38"
						( Origin gPackager )
					)
					( objectStatus "U2D1.DE38" )
				)
				( pin "ddr5_dq(35)"
					( attribute "PN" "DG38"
						( Origin gPackager )
					)
					( objectStatus "U2D1.DG38" )
				)
				( pin "ddr5_dq(36)"
					( attribute "PN" "DA42"
						( Origin gPackager )
					)
					( objectStatus "U2D1.DA42" )
				)
				( pin "ddr5_dq(37)"
					( attribute "PN" "DE42"
						( Origin gPackager )
					)
					( objectStatus "U2D1.DE42" )
				)
				( pin "ddr5_dq(38)"
					( attribute "PN" "DD39"
						( Origin gPackager )
					)
					( objectStatus "U2D1.DD39" )
				)
				( pin "ddr5_dq(39)"
					( attribute "PN" "DH39"
						( Origin gPackager )
					)
					( objectStatus "U2D1.DH39" )
				)
				( pin "ddr5_dq(40)"
					( attribute "PN" "DF33"
						( Origin gPackager )
					)
					( objectStatus "U2D1.DF33" )
				)
				( pin "ddr5_dq(41)"
					( attribute "PN" "DK33"
						( Origin gPackager )
					)
					( objectStatus "U2D1.DK33" )
				)
				( pin "ddr5_dq(42)"
					( attribute "PN" "DG30"
						( Origin gPackager )
					)
					( objectStatus "U2D1.DG30" )
				)
				( pin "ddr5_dq(43)"
					( attribute "PN" "DJ30"
						( Origin gPackager )
					)
					( objectStatus "U2D1.DJ30" )
				)
				( pin "ddr5_dq(44)"
					( attribute "PN" "DG34"
						( Origin gPackager )
					)
					( objectStatus "U2D1.DG34" )
				)
				( pin "ddr5_dq(45)"
					( attribute "PN" "DJ34"
						( Origin gPackager )
					)
					( objectStatus "U2D1.DJ34" )
				)
				( pin "ddr5_dq(46)"
					( attribute "PN" "DF31"
						( Origin gPackager )
					)
					( objectStatus "U2D1.DF31" )
				)
				( pin "ddr5_dq(47)"
					( attribute "PN" "DK31"
						( Origin gPackager )
					)
					( objectStatus "U2D1.DK31" )
				)
				( pin "ddr5_dq(48)"
					( attribute "PN" "CW36"
						( Origin gPackager )
					)
					( objectStatus "U2D1.CW36" )
				)
				( pin "ddr5_dq(49)"
					( attribute "PN" "DC36"
						( Origin gPackager )
					)
					( objectStatus "U2D1.DC36" )
				)
				( pin "ddr5_dq(50)"
					( attribute "PN" "CY33"
						( Origin gPackager )
					)
					( objectStatus "U2D1.CY33" )
				)
				( pin "ddr5_dq(51)"
					( attribute "PN" "DB33"
						( Origin gPackager )
					)
					( objectStatus "U2D1.DB33" )
				)
				( pin "ddr5_dq(52)"
					( attribute "PN" "CY37"
						( Origin gPackager )
					)
					( objectStatus "U2D1.CY37" )
				)
				( pin "ddr5_dq(53)"
					( attribute "PN" "DB37"
						( Origin gPackager )
					)
					( objectStatus "U2D1.DB37" )
				)
				( pin "ddr5_dq(54)"
					( attribute "PN" "CW34"
						( Origin gPackager )
					)
					( objectStatus "U2D1.CW34" )
				)
				( pin "ddr5_dq(55)"
					( attribute "PN" "DC34"
						( Origin gPackager )
					)
					( objectStatus "U2D1.DC34" )
				)
				( pin "ddr5_dq(56)"
					( attribute "PN" "CW30"
						( Origin gPackager )
					)
					( objectStatus "U2D1.CW30" )
				)
				( pin "ddr5_dq(57)"
					( attribute "PN" "DC30"
						( Origin gPackager )
					)
					( objectStatus "U2D1.DC30" )
				)
				( pin "ddr5_dq(58)"
					( attribute "PN" "CY27"
						( Origin gPackager )
					)
					( objectStatus "U2D1.CY27" )
				)
				( pin "ddr5_dq(59)"
					( attribute "PN" "DB27"
						( Origin gPackager )
					)
					( objectStatus "U2D1.DB27" )
				)
				( pin "ddr5_dq(60)"
					( attribute "PN" "CY31"
						( Origin gPackager )
					)
					( objectStatus "U2D1.CY31" )
				)
				( pin "ddr5_dq(61)"
					( attribute "PN" "DB31"
						( Origin gPackager )
					)
					( objectStatus "U2D1.DB31" )
				)
				( pin "ddr5_dq(62)"
					( attribute "PN" "CW28"
						( Origin gPackager )
					)
					( objectStatus "U2D1.CW28" )
				)
				( pin "ddr5_dq(63)"
					( attribute "PN" "DC28"
						( Origin gPackager )
					)
					( objectStatus "U2D1.DC28" )
				)
				( pin "ddr5_dqs_dn(0)"
					( attribute "PN" "CP77"
						( Origin gPackager )
					)
					( objectStatus "U2D1.CP77" )
				)
				( pin "ddr5_dqs_dn(1)"
					( attribute "PN" "DD77"
						( Origin gPackager )
					)
					( objectStatus "U2D1.DD77" )
				)
				( pin "ddr5_dqs_dn(2)"
					( attribute "PN" "DL72"
						( Origin gPackager )
					)
					( objectStatus "U2D1.DL72" )
				)
				( pin "ddr5_dqs_dn(3)"
					( attribute "PN" "CV65"
						( Origin gPackager )
					)
					( objectStatus "U2D1.CV65" )
				)
				( pin "ddr5_dqs_dn(4)"
					( attribute "PN" "DG40"
						( Origin gPackager )
					)
					( objectStatus "U2D1.DG40" )
				)
				( pin "ddr5_dqs_dn(5)"
					( attribute "PN" "DL32"
						( Origin gPackager )
					)
					( objectStatus "U2D1.DL32" )
				)
				( pin "ddr5_dqs_dn(6)"
					( attribute "PN" "DD35"
						( Origin gPackager )
					)
					( objectStatus "U2D1.DD35" )
				)
				( pin "ddr5_dqs_dn(7)"
					( attribute "PN" "DD29"
						( Origin gPackager )
					)
					( objectStatus "U2D1.DD29" )
				)
				( pin "ddr5_dqs_dn(8)"
					( attribute "PN" "CN70"
						( Origin gPackager )
					)
					( objectStatus "U2D1.CN70" )
				)
				( pin "ddr5_dqs_dn(9)"
					( attribute "PN" "CT75"
						( Origin gPackager )
					)
					( objectStatus "U2D1.CT75" )
				)
				( pin "ddr5_dqs_dn(10)"
					( attribute "PN" "DF75"
						( Origin gPackager )
					)
					( objectStatus "U2D1.DF75" )
				)
				( pin "ddr5_dqs_dn(11)"
					( attribute "PN" "DJ70"
						( Origin gPackager )
					)
					( objectStatus "U2D1.DJ70" )
				)
				( pin "ddr5_dqs_dn(12)"
					( attribute "PN" "CP65"
						( Origin gPackager )
					)
					( objectStatus "U2D1.CP65" )
				)
				( pin "ddr5_dqs_dn(13)"
					( attribute "PN" "DE40"
						( Origin gPackager )
					)
					( objectStatus "U2D1.DE40" )
				)
				( pin "ddr5_dqs_dn(14)"
					( attribute "PN" "DG32"
						( Origin gPackager )
					)
					( objectStatus "U2D1.DG32" )
				)
				( pin "ddr5_dqs_dn(15)"
					( attribute "PN" "CY35"
						( Origin gPackager )
					)
					( objectStatus "U2D1.CY35" )
				)
				( pin "ddr5_dqs_dn(16)"
					( attribute "PN" "CY29"
						( Origin gPackager )
					)
					( objectStatus "U2D1.CY29" )
				)
				( pin "ddr5_dqs_dn(17)"
					( attribute "PN" "CJ70"
						( Origin gPackager )
					)
					( objectStatus "U2D1.CJ70" )
				)
				( pin "ddr5_dqs_dp(0)"
					( attribute "PN" "CR76"
						( Origin gPackager )
					)
					( objectStatus "U2D1.CR76" )
				)
				( pin "ddr5_dqs_dp(1)"
					( attribute "PN" "DE76"
						( Origin gPackager )
					)
					( objectStatus "U2D1.DE76" )
				)
				( pin "ddr5_dqs_dp(2)"
					( attribute "PN" "DK71"
						( Origin gPackager )
					)
					( objectStatus "U2D1.DK71" )
				)
				( pin "ddr5_dqs_dp(3)"
					( attribute "PN" "CT65"
						( Origin gPackager )
					)
					( objectStatus "U2D1.CT65" )
				)
				( pin "ddr5_dqs_dp(4)"
					( attribute "PN" "DJ40"
						( Origin gPackager )
					)
					( objectStatus "U2D1.DJ40" )
				)
				( pin "ddr5_dqs_dp(5)"
					( attribute "PN" "DJ32"
						( Origin gPackager )
					)
					( objectStatus "U2D1.DJ32" )
				)
				( pin "ddr5_dqs_dp(6)"
					( attribute "PN" "DB35"
						( Origin gPackager )
					)
					( objectStatus "U2D1.DB35" )
				)
				( pin "ddr5_dqs_dp(7)"
					( attribute "PN" "DB29"
						( Origin gPackager )
					)
					( objectStatus "U2D1.DB29" )
				)
				( pin "ddr5_dqs_dp(8)"
					( attribute "PN" "CL70"
						( Origin gPackager )
					)
					( objectStatus "U2D1.CL70" )
				)
				( pin "ddr5_dqs_dp(9)"
					( attribute "PN" "CU74"
						( Origin gPackager )
					)
					( objectStatus "U2D1.CU74" )
				)
				( pin "ddr5_dqs_dp(10)"
					( attribute "PN" "DG74"
						( Origin gPackager )
					)
					( objectStatus "U2D1.DG74" )
				)
				( pin "ddr5_dqs_dp(11)"
					( attribute "PN" "DH69"
						( Origin gPackager )
					)
					( objectStatus "U2D1.DH69" )
				)
				( pin "ddr5_dqs_dp(12)"
					( attribute "PN" "CM65"
						( Origin gPackager )
					)
					( objectStatus "U2D1.CM65" )
				)
				( pin "ddr5_dqs_dp(13)"
					( attribute "PN" "DC40"
						( Origin gPackager )
					)
					( objectStatus "U2D1.DC40" )
				)
				( pin "ddr5_dqs_dp(14)"
					( attribute "PN" "DE32"
						( Origin gPackager )
					)
					( objectStatus "U2D1.DE32" )
				)
				( pin "ddr5_dqs_dp(15)"
					( attribute "PN" "CV35"
						( Origin gPackager )
					)
					( objectStatus "U2D1.CV35" )
				)
				( pin "ddr5_dqs_dp(16)"
					( attribute "PN" "CV29"
						( Origin gPackager )
					)
					( objectStatus "U2D1.CV29" )
				)
				( pin "ddr5_dqs_dp(17)"
					( attribute "PN" "CG70"
						( Origin gPackager )
					)
					( objectStatus "U2D1.CG70" )
				)
				( pin "ddr5_ecc(0)"
					( attribute "PN" "CH71"
						( Origin gPackager )
					)
					( objectStatus "U2D1.CH71" )
				)
				( pin "ddr5_ecc(1)"
					( attribute "PN" "CM71"
						( Origin gPackager )
					)
					( objectStatus "U2D1.CM71" )
				)
				( pin "ddr5_ecc(2)"
					( attribute "PN" "CJ68"
						( Origin gPackager )
					)
					( objectStatus "U2D1.CJ68" )
				)
				( pin "ddr5_ecc(3)"
					( attribute "PN" "CL68"
						( Origin gPackager )
					)
					( objectStatus "U2D1.CL68" )
				)
				( pin "ddr5_ecc(4)"
					( attribute "PN" "CJ72"
						( Origin gPackager )
					)
					( objectStatus "U2D1.CJ72" )
				)
				( pin "ddr5_ecc(5)"
					( attribute "PN" "CL72"
						( Origin gPackager )
					)
					( objectStatus "U2D1.CL72" )
				)
				( pin "ddr5_ecc(6)"
					( attribute "PN" "CH69"
						( Origin gPackager )
					)
					( objectStatus "U2D1.CH69" )
				)
				( pin "ddr5_ecc(7)"
					( attribute "PN" "CM69"
						( Origin gPackager )
					)
					( objectStatus "U2D1.CM69" )
				)
				( pin "ddr5_ma(0)"
					( attribute "PN" "DF53"
						( Origin gPackager )
					)
					( objectStatus "U2D1.DF53" )
				)
				( pin "ddr5_ma(1)"
					( attribute "PN" "DC58"
						( Origin gPackager )
					)
					( objectStatus "U2D1.DC58" )
				)
				( pin "ddr5_ma(2)"
					( attribute "PN" "DD57"
						( Origin gPackager )
					)
					( objectStatus "U2D1.DD57" )
				)
				( pin "ddr5_ma(3)"
					( attribute "PN" "DG58"
						( Origin gPackager )
					)
					( objectStatus "U2D1.DG58" )
				)
				( pin "ddr5_ma(4)"
					( attribute "PN" "DJ58"
						( Origin gPackager )
					)
					( objectStatus "U2D1.DJ58" )
				)
				( pin "ddr5_ma(5)"
					( attribute "PN" "DF59"
						( Origin gPackager )
					)
					( objectStatus "U2D1.DF59" )
				)
				( pin "ddr5_ma(6)"
					( attribute "PN" "DK59"
						( Origin gPackager )
					)
					( objectStatus "U2D1.DK59" )
				)
				( pin "ddr5_ma(7)"
					( attribute "PN" "DC60"
						( Origin gPackager )
					)
					( objectStatus "U2D1.DC60" )
				)
				( pin "ddr5_ma(8)"
					( attribute "PN" "DD59"
						( Origin gPackager )
					)
					( objectStatus "U2D1.DD59" )
				)
				( pin "ddr5_ma(9)"
					( attribute "PN" "DA58"
						( Origin gPackager )
					)
					( objectStatus "U2D1.DA58" )
				)
				( pin "ddr5_ma(10)"
					( attribute "PN" "DD55"
						( Origin gPackager )
					)
					( objectStatus "U2D1.DD55" )
				)
				( pin "ddr5_ma(11)"
					( attribute "PN" "DA60"
						( Origin gPackager )
					)
					( objectStatus "U2D1.DA60" )
				)
				( pin "ddr5_ma(12)"
					( attribute "PN" "DG60"
						( Origin gPackager )
					)
					( objectStatus "U2D1.DG60" )
				)
				( pin "ddr5_ma(13)"
					( attribute "PN" "DD53"
						( Origin gPackager )
					)
					( objectStatus "U2D1.DD53" )
				)
				( pin "ddr5_ma(14)"
					( attribute "PN" "DJ50"
						( Origin gPackager )
					)
					( objectStatus "U2D1.DJ50" )
				)
				( pin "ddr5_ma(15)"
					( attribute "PN" "DC54"
						( Origin gPackager )
					)
					( objectStatus "U2D1.DC54" )
				)
				( pin "ddr5_ma(16)"
					( attribute "PN" "DG52"
						( Origin gPackager )
					)
					( objectStatus "U2D1.DG52" )
				)
				( pin "ddr5_ma(17)"
					( attribute "PN" "DE46"
						( Origin gPackager )
					)
					( objectStatus "U2D1.DE46" )
				)
				( pin "ddr5_odt(0)"
					( attribute "PN" "DG50"
						( Origin gPackager )
					)
					( objectStatus "U2D1.DG50" )
				)
				( pin "ddr5_odt(1)"
					( attribute "PN" "DG48"
						( Origin gPackager )
					)
					( objectStatus "U2D1.DG48" )
				)
				( pin "ddr5_odt(2)"
					( attribute "PN" "DK49"
						( Origin gPackager )
					)
					( objectStatus "U2D1.DK49" )
				)
				( pin "ddr5_odt(3)"
					( attribute "PN" "DF47"
						( Origin gPackager )
					)
					( objectStatus "U2D1.DF47" )
				)
				( pin "ddr5_par"
					( attribute "PN" "DK53"
						( Origin gPackager )
					)
					( objectStatus "U2D1.DK53" )
				)
			)
			( gate "@baseboard_fab2_lib.baseboard_fab2(sch_1):page63_i23"
				( attribute "CDS_LIB" "chpset_lib"
					( Origin gPackager )
				)
				( attribute "CDS_LOCATION" "U2D1"
					( Origin gPackager )
				)
				( attribute "CDS_SEC" "9"
					( Origin gPackager )
				)
				( attribute "LOCATION" "U2D1"
					( Origin gFrontEnd )
				)
				( attribute "MATERIAL" "IC"
					( Origin gFrontEnd )
				)
				( attribute "PACK_TYPE" "BGA1"
					( Origin gFrontEnd )
				)
				( attribute "PART_NUMBER" "TBD"
					( Origin gFrontEnd )
				)
				( attribute "PHYS_PAGE" "63"
					( Origin gFrontEnd )
				)
				( attribute "ROT" "0"
					( Origin gFrontEnd )
				)
				( attribute "SEC" "9"
					( Origin gFrontEnd )
				)
				( attribute "SEC_TYPE" "BGA1"
					( Origin gFrontEnd )
				)
				( attribute "VER" "9"
					( Origin gFrontEnd )
				)
				( attribute "XY" "(-4075,2500)"
					( Origin gFrontEnd )
				)
				( attribute "CHIPS_PART_NAME" "SKX_EXT_B"
					( Origin gPackager )
				)
				( attribute "CDS_PART_NAME" "SKX_EXT_B_BGA1-IC,TBD"
					( Origin gPackager )
				)
				( objectStatus "U2D1" )
				( pin "cd_hfi0_i2cclk"
					( attribute "PN" "BN22"
						( Origin gPackager )
					)
					( objectStatus "U2D1.BN22" )
				)
				( pin "cd_hfi0_i2cdat"
					( attribute "PN" "BP23"
						( Origin gPackager )
					)
					( objectStatus "U2D1.BP23" )
				)
				( pin "cd_hfi0_int_n"
					( attribute "PN" "BP19"
						( Origin gPackager )
					)
					( objectStatus "U2D1.BP19" )
				)
				( pin "cd_hfi0_led_n"
					( attribute "PN" "BK21"
						( Origin gPackager )
					)
					( objectStatus "U2D1.BK21" )
				)
				( pin "cd_hfi0_modprst_n"
					( attribute "PN" "BR20"
						( Origin gPackager )
					)
					( objectStatus "U2D1.BR20" )
				)
				( pin "cd_hfi0_reset_n"
					( attribute "PN" "BN24"
						( Origin gPackager )
					)
					( objectStatus "U2D1.BN24" )
				)
				( pin "cd_hfi1_i2cclk"
					( attribute "PN" "BJ22"
						( Origin gPackager )
					)
					( objectStatus "U2D1.BJ22" )
				)
				( pin "cd_hfi1_i2cdat"
					( attribute "PN" "BH23"
						( Origin gPackager )
					)
					( objectStatus "U2D1.BH23" )
				)
				( pin "cd_hfi1_int_n"
					( attribute "PN" "BM21"
						( Origin gPackager )
					)
					( objectStatus "U2D1.BM21" )
				)
				( pin "cd_hfi1_led_n"
					( attribute "PN" "BM23"
						( Origin gPackager )
					)
					( objectStatus "U2D1.BM23" )
				)
				( pin "cd_hfi1_modprst_n"
					( attribute "PN" "BT19"
						( Origin gPackager )
					)
					( objectStatus "U2D1.BT19" )
				)
				( pin "cd_hfi1_reset_n"
					( attribute "PN" "BK23"
						( Origin gPackager )
					)
					( objectStatus "U2D1.BK23" )
				)
				( pin "cd_hfi_refclk_dn"
					( attribute "PN" "BE16"
						( Origin gPackager )
					)
					( objectStatus "U2D1.BE16" )
				)
				( pin "cd_hfi_refclk_dp"
					( attribute "PN" "BG16"
						( Origin gPackager )
					)
					( objectStatus "U2D1.BG16" )
				)
				( pin "cd_pe_refclk_dn"
					( attribute "PN" "BU24"
						( Origin gPackager )
					)
					( objectStatus "U2D1.BU24" )
				)
				( pin "cd_pe_refclk_dp"
					( attribute "PN" "BW24"
						( Origin gPackager )
					)
					( objectStatus "U2D1.BW24" )
				)
				( pin "cd_por_n"
					( attribute "PN" "CF25"
						( Origin gPackager )
					)
					( objectStatus "U2D1.CF25" )
				)
				( pin "cd_tclk"
					( attribute "PN" "CB23"
						( Origin gPackager )
					)
					( objectStatus "U2D1.CB23" )
				)
				( pin "cd_tdi"
					( attribute "PN" "BY21"
						( Origin gPackager )
					)
					( objectStatus "U2D1.BY21" )
				)
				( pin "cd_tdo"
					( attribute "PN" "CC22"
						( Origin gPackager )
					)
					( objectStatus "U2D1.CC22" )
				)
				( pin "cd_tms"
					( attribute "PN" "CE24"
						( Origin gPackager )
					)
					( objectStatus "U2D1.CE24" )
				)
				( pin "cd_trst_n"
					( attribute "PN" "CD23"
						( Origin gPackager )
					)
					( objectStatus "U2D1.CD23" )
				)
				( pin "dmi_rx_dn(0)"
					( attribute "PN" "CK9"
						( Origin gPackager )
					)
					( objectStatus "U2D1.CK9" )
				)
				( pin "dmi_rx_dn(1)"
					( attribute "PN" "CM11"
						( Origin gPackager )
					)
					( objectStatus "U2D1.CM11" )
				)
				( pin "dmi_rx_dn(2)"
					( attribute "PN" "CR12"
						( Origin gPackager )
					)
					( objectStatus "U2D1.CR12" )
				)
				( pin "dmi_rx_dn(3)"
					( attribute "PN" "CT11"
						( Origin gPackager )
					)
					( objectStatus "U2D1.CT11" )
				)
				( pin "dmi_rx_dp(0)"
					( attribute "PN" "CL10"
						( Origin gPackager )
					)
					( objectStatus "U2D1.CL10" )
				)
				( pin "dmi_rx_dp(1)"
					( attribute "PN" "CN10"
						( Origin gPackager )
					)
					( objectStatus "U2D1.CN10" )
				)
				( pin "dmi_rx_dp(2)"
					( attribute "PN" "CP11"
						( Origin gPackager )
					)
					( objectStatus "U2D1.CP11" )
				)
				( pin "dmi_rx_dp(3)"
					( attribute "PN" "CV11"
						( Origin gPackager )
					)
					( objectStatus "U2D1.CV11" )
				)
				( pin "dmi_tx_dn(0)"
					( attribute "PN" "CG4"
						( Origin gPackager )
					)
					( objectStatus "U2D1.CG4" )
				)
				( pin "dmi_tx_dn(1)"
					( attribute "PN" "CJ4"
						( Origin gPackager )
					)
					( objectStatus "U2D1.CJ4" )
				)
				( pin "dmi_tx_dn(2)"
					( attribute "PN" "CN4"
						( Origin gPackager )
					)
					( objectStatus "U2D1.CN4" )
				)
				( pin "dmi_tx_dn(3)"
					( attribute "PN" "CP5"
						( Origin gPackager )
					)
					( objectStatus "U2D1.CP5" )
				)
				( pin "dmi_tx_dp(0)"
					( attribute "PN" "CH5"
						( Origin gPackager )
					)
					( objectStatus "U2D1.CH5" )
				)
				( pin "dmi_tx_dp(1)"
					( attribute "PN" "CL4"
						( Origin gPackager )
					)
					( objectStatus "U2D1.CL4" )
				)
				( pin "dmi_tx_dp(2)"
					( attribute "PN" "CM3"
						( Origin gPackager )
					)
					( objectStatus "U2D1.CM3" )
				)
				( pin "dmi_tx_dp(3)"
					( attribute "PN" "CR4"
						( Origin gPackager )
					)
					( objectStatus "U2D1.CR4" )
				)
				( pin "rsvd(172)"
					( attribute "PN" "BA76"
						( Origin gPackager )
					)
					( objectStatus "U2D1.BA76" )
				)
				( pin "rsvd(173)"
					( attribute "PN" "BA66"
						( Origin gPackager )
					)
					( objectStatus "U2D1.BA66" )
				)
				( pin "rsvd(174)"
					( attribute "PN" "BA64"
						( Origin gPackager )
					)
					( objectStatus "U2D1.BA64" )
				)
				( pin "rsvd(175)"
					( attribute "PN" "BA22"
						( Origin gPackager )
					)
					( objectStatus "U2D1.BA22" )
				)
				( pin "rsvd(176)"
					( attribute "PN" "BA18"
						( Origin gPackager )
					)
					( objectStatus "U2D1.BA18" )
				)
				( pin "rsvd(177)"
					( attribute "PN" "BA16"
						( Origin gPackager )
					)
					( objectStatus "U2D1.BA16" )
				)
				( pin "rsvd(178)"
					( attribute "PN" "BA14"
						( Origin gPackager )
					)
					( objectStatus "U2D1.BA14" )
				)
				( pin "rsvd(179)"
					( attribute "PN" "AY77"
						( Origin gPackager )
					)
					( objectStatus "U2D1.AY77" )
				)
				( pin "rsvd(180)"
					( attribute "PN" "AY75"
						( Origin gPackager )
					)
					( objectStatus "U2D1.AY75" )
				)
				( pin "rsvd(181)"
					( attribute "PN" "AY67"
						( Origin gPackager )
					)
					( objectStatus "U2D1.AY67" )
				)
				( pin "rsvd(182)"
					( attribute "PN" "AY65"
						( Origin gPackager )
					)
					( objectStatus "U2D1.AY65" )
				)
				( pin "rsvd(183)"
					( attribute "PN" "AW76"
						( Origin gPackager )
					)
					( objectStatus "U2D1.AW76" )
				)
				( pin "rsvd(184)"
					( attribute "PN" "AW64"
						( Origin gPackager )
					)
					( objectStatus "U2D1.AW64" )
				)
				( pin "rsvd(185)"
					( attribute "CDS_NOT_ON_SYM" "TRUE"
						( Origin gFrontEnd )
					)
				)
				( pin "rsvd(186)"
					( attribute "PN" "AV77"
						( Origin gPackager )
					)
					( objectStatus "U2D1.AV77" )
				)
				( pin "rsvd(187)"
					( attribute "PN" "AT25"
						( Origin gPackager )
					)
					( objectStatus "U2D1.AT25" )
				)
				( pin "rsvd(188)"
					( attribute "PN" "AT23"
						( Origin gPackager )
					)
					( objectStatus "U2D1.AT23" )
				)
				( pin "rsvd(189)"
					( attribute "PN" "AT13"
						( Origin gPackager )
					)
					( objectStatus "U2D1.AT13" )
				)
				( pin "rsvd(190)"
					( attribute "PN" "AR62"
						( Origin gPackager )
					)
					( objectStatus "U2D1.AR62" )
				)
				( pin "rsvd(191)"
					( attribute "PN" "AR26"
						( Origin gPackager )
					)
					( objectStatus "U2D1.AR26" )
				)
				( pin "rsvd(192)"
					( attribute "PN" "AR22"
						( Origin gPackager )
					)
					( objectStatus "U2D1.AR22" )
				)
				( pin "rsvd(193)"
					( attribute "PN" "AR20"
						( Origin gPackager )
					)
					( objectStatus "U2D1.AR20" )
				)
			)
			( gate "@baseboard_fab2_lib.baseboard_fab2(sch_1):page64_i68"
				( attribute "CDS_LIB" "chpset_lib"
					( Origin gPackager )
				)
				( attribute "CDS_LOCATION" "U2D1"
					( Origin gPackager )
				)
				( attribute "CDS_SEC" "10"
					( Origin gPackager )
				)
				( attribute "LOCATION" "U2D1"
					( Origin gFrontEnd )
				)
				( attribute "MATERIAL" "IC"
					( Origin gFrontEnd )
				)
				( attribute "PACK_TYPE" "BGA1"
					( Origin gFrontEnd )
				)
				( attribute "PART_NUMBER" "TBD"
					( Origin gFrontEnd )
				)
				( attribute "PHYS_PAGE" "64"
					( Origin gFrontEnd )
				)
				( attribute "ROT" "0"
					( Origin gFrontEnd )
				)
				( attribute "SEC" "10"
					( Origin gFrontEnd )
				)
				( attribute "SEC_TYPE" "BGA1"
					( Origin gFrontEnd )
				)
				( attribute "VER" "10"
					( Origin gFrontEnd )
				)
				( attribute "XY" "(-4075,2575)"
					( Origin gFrontEnd )
				)
				( attribute "CHIPS_PART_NAME" "SKX_EXT_B"
					( Origin gPackager )
				)
				( attribute "CDS_PART_NAME" "SKX_EXT_B_BGA1-IC,TBD"
					( Origin gPackager )
				)
				( objectStatus "U2D1" )
				( pin "pe1_rx_dn(0)"
					( attribute "PN" "CW8"
						( Origin gPackager )
					)
					( objectStatus "U2D1.CW8" )
				)
				( pin "pe1_rx_dn(1)"
					( attribute "PN" "DA8"
						( Origin gPackager )
					)
					( objectStatus "U2D1.DA8" )
				)
				( pin "pe1_rx_dn(2)"
					( attribute "PN" "DC8"
						( Origin gPackager )
					)
					( objectStatus "U2D1.DC8" )
				)
				( pin "pe1_rx_dn(3)"
					( attribute "PN" "DC10"
						( Origin gPackager )
					)
					( objectStatus "U2D1.DC10" )
				)
				( pin "pe1_rx_dn(4)"
					( attribute "PN" "DE10"
						( Origin gPackager )
					)
					( objectStatus "U2D1.DE10" )
				)
				( pin "pe1_rx_dn(5)"
					( attribute "PN" "DH9"
						( Origin gPackager )
					)
					( objectStatus "U2D1.DH9" )
				)
				( pin "pe1_rx_dn(6)"
					( attribute "PN" "DK9"
						( Origin gPackager )
					)
					( objectStatus "U2D1.DK9" )
				)
				( pin "pe1_rx_dn(7)"
					( attribute "PN" "DM9"
						( Origin gPackager )
					)
					( objectStatus "U2D1.DM9" )
				)
				( pin "pe1_rx_dn(8)"
					( attribute "PN" "DM11"
						( Origin gPackager )
					)
					( objectStatus "U2D1.DM11" )
				)
				( pin "pe1_rx_dn(9)"
					( attribute "PN" "DP11"
						( Origin gPackager )
					)
					( objectStatus "U2D1.DP11" )
				)
				( pin "pe1_rx_dn(10)"
					( attribute "PN" "DT11"
						( Origin gPackager )
					)
					( objectStatus "U2D1.DT11" )
				)
				( pin "pe1_rx_dn(11)"
					( attribute "PN" "DT13"
						( Origin gPackager )
					)
					( objectStatus "U2D1.DT13" )
				)
				( pin "pe1_rx_dn(12)"
					( attribute "PN" "DV13"
						( Origin gPackager )
					)
					( objectStatus "U2D1.DV13" )
				)
				( pin "pe1_rx_dn(13)"
					( attribute "PN" "DW14"
						( Origin gPackager )
					)
					( objectStatus "U2D1.DW14" )
				)
				( pin "pe1_rx_dn(14)"
					( attribute "PN" "DY15"
						( Origin gPackager )
					)
					( objectStatus "U2D1.DY15" )
				)
				( pin "pe1_rx_dn(15)"
					( attribute "PN" "DU16"
						( Origin gPackager )
					)
					( objectStatus "U2D1.DU16" )
				)
				( pin "pe1_rx_dp(0)"
					( attribute "PN" "CU8"
						( Origin gPackager )
					)
					( objectStatus "U2D1.CU8" )
				)
				( pin "pe1_rx_dp(1)"
					( attribute "PN" "CY7"
						( Origin gPackager )
					)
					( objectStatus "U2D1.CY7" )
				)
				( pin "pe1_rx_dp(2)"
					( attribute "PN" "DB9"
						( Origin gPackager )
					)
					( objectStatus "U2D1.DB9" )
				)
				( pin "pe1_rx_dp(3)"
					( attribute "PN" "DA10"
						( Origin gPackager )
					)
					( objectStatus "U2D1.DA10" )
				)
				( pin "pe1_rx_dp(4)"
					( attribute "PN" "DD9"
						( Origin gPackager )
					)
					( objectStatus "U2D1.DD9" )
				)
				( pin "pe1_rx_dp(5)"
					( attribute "PN" "DF9"
						( Origin gPackager )
					)
					( objectStatus "U2D1.DF9" )
				)
				( pin "pe1_rx_dp(6)"
					( attribute "PN" "DJ8"
						( Origin gPackager )
					)
					( objectStatus "U2D1.DJ8" )
				)
				( pin "pe1_rx_dp(7)"
					( attribute "PN" "DL10"
						( Origin gPackager )
					)
					( objectStatus "U2D1.DL10" )
				)
				( pin "pe1_rx_dp(8)"
					( attribute "PN" "DK11"
						( Origin gPackager )
					)
					( objectStatus "U2D1.DK11" )
				)
				( pin "pe1_rx_dp(9)"
					( attribute "PN" "DN10"
						( Origin gPackager )
					)
					( objectStatus "U2D1.DN10" )
				)
				( pin "pe1_rx_dp(10)"
					( attribute "PN" "DR12"
						( Origin gPackager )
					)
					( objectStatus "U2D1.DR12" )
				)
				( pin "pe1_rx_dp(11)"
					( attribute "PN" "DP13"
						( Origin gPackager )
					)
					( objectStatus "U2D1.DP13" )
				)
				( pin "pe1_rx_dp(12)"
					( attribute "PN" "DU12"
						( Origin gPackager )
					)
					( objectStatus "U2D1.DU12" )
				)
				( pin "pe1_rx_dp(13)"
					( attribute "PN" "DY13"
						( Origin gPackager )
					)
					( objectStatus "U2D1.DY13" )
				)
				( pin "pe1_rx_dp(14)"
					( attribute "PN" "DV15"
						( Origin gPackager )
					)
					( objectStatus "U2D1.DV15" )
				)
				( pin "pe1_rx_dp(15)"
					( attribute "PN" "DT15"
						( Origin gPackager )
					)
					( objectStatus "U2D1.DT15" )
				)
				( pin "pe1_tx_dn(0)"
					( attribute "PN" "DA2"
						( Origin gPackager )
					)
					( objectStatus "U2D1.DA2" )
				)
				( pin "pe1_tx_dn(1)"
					( attribute "PN" "DC2"
						( Origin gPackager )
					)
					( objectStatus "U2D1.DC2" )
				)
				( pin "pe1_tx_dn(2)"
					( attribute "PN" "DE2"
						( Origin gPackager )
					)
					( objectStatus "U2D1.DE2" )
				)
				( pin "pe1_tx_dn(3)"
					( attribute "PN" "DE4"
						( Origin gPackager )
					)
					( objectStatus "U2D1.DE4" )
				)
				( pin "pe1_tx_dn(4)"
					( attribute "PN" "DG4"
						( Origin gPackager )
					)
					( objectStatus "U2D1.DG4" )
				)
				( pin "pe1_tx_dn(5)"
					( attribute "PN" "DK3"
						( Origin gPackager )
					)
					( objectStatus "U2D1.DK3" )
				)
				( pin "pe1_tx_dn(6)"
					( attribute "PN" "DM3"
						( Origin gPackager )
					)
					( objectStatus "U2D1.DM3" )
				)
				( pin "pe1_tx_dn(7)"
					( attribute "PN" "DN4"
						( Origin gPackager )
					)
					( objectStatus "U2D1.DN4" )
				)
				( pin "pe1_tx_dn(8)"
					( attribute "PN" "DT5"
						( Origin gPackager )
					)
					( objectStatus "U2D1.DT5" )
				)
				( pin "pe1_tx_dn(9)"
					( attribute "PN" "DV3"
						( Origin gPackager )
					)
					( objectStatus "U2D1.DV3" )
				)
				( pin "pe1_tx_dn(10)"
					( attribute "PN" "DW4"
						( Origin gPackager )
					)
					( objectStatus "U2D1.DW4" )
				)
				( pin "pe1_tx_dn(11)"
					( attribute "PN" "DU6"
						( Origin gPackager )
					)
					( objectStatus "U2D1.DU6" )
				)
				( pin "pe1_tx_dn(12)"
					( attribute "PN" "DV7"
						( Origin gPackager )
					)
					( objectStatus "U2D1.DV7" )
				)
				( pin "pe1_tx_dn(13)"
					( attribute "PN" "DY7"
						( Origin gPackager )
					)
					( objectStatus "U2D1.DY7" )
				)
				( pin "pe1_tx_dn(14)"
					( attribute "PN" "EA8"
						( Origin gPackager )
					)
					( objectStatus "U2D1.EA8" )
				)
				( pin "pe1_tx_dn(15)"
					( attribute "PN" "ED9"
						( Origin gPackager )
					)
					( objectStatus "U2D1.ED9" )
				)
				( pin "pe1_tx_dp(0)"
					( attribute "PN" "CW2"
						( Origin gPackager )
					)
					( objectStatus "U2D1.CW2" )
				)
				( pin "pe1_tx_dp(1)"
					( attribute "PN" "DB1"
						( Origin gPackager )
					)
					( objectStatus "U2D1.DB1" )
				)
				( pin "pe1_tx_dp(2)"
					( attribute "PN" "DD3"
						( Origin gPackager )
					)
					( objectStatus "U2D1.DD3" )
				)
				( pin "pe1_tx_dp(3)"
					( attribute "PN" "DC4"
						( Origin gPackager )
					)
					( objectStatus "U2D1.DC4" )
				)
				( pin "pe1_tx_dp(4)"
					( attribute "PN" "DF3"
						( Origin gPackager )
					)
					( objectStatus "U2D1.DF3" )
				)
				( pin "pe1_tx_dp(5)"
					( attribute "PN" "DH3"
						( Origin gPackager )
					)
					( objectStatus "U2D1.DH3" )
				)
				( pin "pe1_tx_dp(6)"
					( attribute "PN" "DL2"
						( Origin gPackager )
					)
					( objectStatus "U2D1.DL2" )
				)
				( pin "pe1_tx_dp(7)"
					( attribute "PN" "DP3"
						( Origin gPackager )
					)
					( objectStatus "U2D1.DP3" )
				)
				( pin "pe1_tx_dp(8)"
					( attribute "PN" "DR4"
						( Origin gPackager )
					)
					( objectStatus "U2D1.DR4" )
				)
				( pin "pe1_tx_dp(9)"
					( attribute "PN" "DU2"
						( Origin gPackager )
					)
					( objectStatus "U2D1.DU2" )
				)
				( pin "pe1_tx_dp(10)"
					( attribute "PN" "DU4"
						( Origin gPackager )
					)
					( objectStatus "U2D1.DU4" )
				)
				( pin "pe1_tx_dp(11)"
					( attribute "PN" "DV5"
						( Origin gPackager )
					)
					( objectStatus "U2D1.DV5" )
				)
				( pin "pe1_tx_dp(12)"
					( attribute "PN" "DT7"
						( Origin gPackager )
					)
					( objectStatus "U2D1.DT7" )
				)
				( pin "pe1_tx_dp(13)"
					( attribute "PN" "DW6"
						( Origin gPackager )
					)
					( objectStatus "U2D1.DW6" )
				)
				( pin "pe1_tx_dp(14)"
					( attribute "PN" "EB7"
						( Origin gPackager )
					)
					( objectStatus "U2D1.EB7" )
				)
				( pin "pe1_tx_dp(15)"
					( attribute "PN" "EC8"
						( Origin gPackager )
					)
					( objectStatus "U2D1.EC8" )
				)
			)
			( gate "@baseboard_fab2_lib.baseboard_fab2(sch_1):page65_i68"
				( attribute "CDS_LIB" "chpset_lib"
					( Origin gPackager )
				)
				( attribute "CDS_LOCATION" "U2D1"
					( Origin gPackager )
				)
				( attribute "CDS_SEC" "11"
					( Origin gPackager )
				)
				( attribute "LOCATION" "U2D1"
					( Origin gFrontEnd )
				)
				( attribute "MATERIAL" "IC"
					( Origin gFrontEnd )
				)
				( attribute "PACK_TYPE" "BGA1"
					( Origin gFrontEnd )
				)
				( attribute "PART_NUMBER" "TBD"
					( Origin gFrontEnd )
				)
				( attribute "PHYS_PAGE" "65"
					( Origin gFrontEnd )
				)
				( attribute "ROT" "0"
					( Origin gFrontEnd )
				)
				( attribute "SEC" "11"
					( Origin gFrontEnd )
				)
				( attribute "SEC_TYPE" "BGA1"
					( Origin gFrontEnd )
				)
				( attribute "VER" "11"
					( Origin gFrontEnd )
				)
				( attribute "XY" "(-4150,2575)"
					( Origin gFrontEnd )
				)
				( attribute "CHIPS_PART_NAME" "SKX_EXT_B"
					( Origin gPackager )
				)
				( attribute "CDS_PART_NAME" "SKX_EXT_B_BGA1-IC,TBD"
					( Origin gPackager )
				)
				( objectStatus "U2D1" )
				( pin "pe2_rx_dn(0)"
					( attribute "PN" "CT9"
						( Origin gPackager )
					)
					( objectStatus "U2D1.CT9" )
				)
				( pin "pe2_rx_dn(1)"
					( attribute "PN" "CP9"
						( Origin gPackager )
					)
					( objectStatus "U2D1.CP9" )
				)
				( pin "pe2_rx_dn(2)"
					( attribute "PN" "CP7"
						( Origin gPackager )
					)
					( objectStatus "U2D1.CP7" )
				)
				( pin "pe2_rx_dn(3)"
					( attribute "PN" "CM7"
						( Origin gPackager )
					)
					( objectStatus "U2D1.CM7" )
				)
				( pin "pe2_rx_dn(4)"
					( attribute "PN" "CK7"
						( Origin gPackager )
					)
					( objectStatus "U2D1.CK7" )
				)
				( pin "pe2_rx_dn(5)"
					( attribute "PN" "CG8"
						( Origin gPackager )
					)
					( objectStatus "U2D1.CG8" )
				)
				( pin "pe2_rx_dn(6)"
					( attribute "PN" "CE6"
						( Origin gPackager )
					)
					( objectStatus "U2D1.CE6" )
				)
				( pin "pe2_rx_dn(7)"
					( attribute "PN" "CE8"
						( Origin gPackager )
					)
					( objectStatus "U2D1.CE8" )
				)
				( pin "pe2_rx_dn(8)"
					( attribute "PN" "BY9"
						( Origin gPackager )
					)
					( objectStatus "U2D1.BY9" )
				)
				( pin "pe2_rx_dn(9)"
					( attribute "PN" "BY7"
						( Origin gPackager )
					)
					( objectStatus "U2D1.BY7" )
				)
				( pin "pe2_rx_dn(10)"
					( attribute "PN" "BV7"
						( Origin gPackager )
					)
					( objectStatus "U2D1.BV7" )
				)
				( pin "pe2_rx_dn(11)"
					( attribute "PN" "BT7"
						( Origin gPackager )
					)
					( objectStatus "U2D1.BT7" )
				)
				( pin "pe2_rx_dn(12)"
					( attribute "PN" "BR8"
						( Origin gPackager )
					)
					( objectStatus "U2D1.BR8" )
				)
				( pin "pe2_rx_dn(13)"
					( attribute "PN" "BN8"
						( Origin gPackager )
					)
					( objectStatus "U2D1.BN8" )
				)
				( pin "pe2_rx_dn(14)"
					( attribute "PN" "BL8"
						( Origin gPackager )
					)
					( objectStatus "U2D1.BL8" )
				)
				( pin "pe2_rx_dn(15)"
					( attribute "PN" "BK9"
						( Origin gPackager )
					)
					( objectStatus "U2D1.BK9" )
				)
				( pin "pe2_rx_dp(0)"
					( attribute "PN" "CR8"
						( Origin gPackager )
					)
					( objectStatus "U2D1.CR8" )
				)
				( pin "pe2_rx_dp(1)"
					( attribute "PN" "CM9"
						( Origin gPackager )
					)
					( objectStatus "U2D1.CM9" )
				)
				( pin "pe2_rx_dp(2)"
					( attribute "PN" "CN8"
						( Origin gPackager )
					)
					( objectStatus "U2D1.CN8" )
				)
				( pin "pe2_rx_dp(3)"
					( attribute "PN" "CL6"
						( Origin gPackager )
					)
					( objectStatus "U2D1.CL6" )
				)
				( pin "pe2_rx_dp(4)"
					( attribute "PN" "CH7"
						( Origin gPackager )
					)
					( objectStatus "U2D1.CH7" )
				)
				( pin "pe2_rx_dp(5)"
					( attribute "PN" "CF7"
						( Origin gPackager )
					)
					( objectStatus "U2D1.CF7" )
				)
				( pin "pe2_rx_dp(6)"
					( attribute "PN" "CD7"
						( Origin gPackager )
					)
					( objectStatus "U2D1.CD7" )
				)
				( pin "pe2_rx_dp(7)"
					( attribute "PN" "CC8"
						( Origin gPackager )
					)
					( objectStatus "U2D1.CC8" )
				)
				( pin "pe2_rx_dp(8)"
					( attribute "PN" "BV9"
						( Origin gPackager )
					)
					( objectStatus "U2D1.BV9" )
				)
				( pin "pe2_rx_dp(9)"
					( attribute "PN" "BW8"
						( Origin gPackager )
					)
					( objectStatus "U2D1.BW8" )
				)
				( pin "pe2_rx_dp(10)"
					( attribute "PN" "BU6"
						( Origin gPackager )
					)
					( objectStatus "U2D1.BU6" )
				)
				( pin "pe2_rx_dp(11)"
					( attribute "PN" "BP7"
						( Origin gPackager )
					)
					( objectStatus "U2D1.BP7" )
				)
				( pin "pe2_rx_dp(12)"
					( attribute "PN" "BP9"
						( Origin gPackager )
					)
					( objectStatus "U2D1.BP9" )
				)
				( pin "pe2_rx_dp(13)"
					( attribute "PN" "BM7"
						( Origin gPackager )
					)
					( objectStatus "U2D1.BM7" )
				)
				( pin "pe2_rx_dp(14)"
					( attribute "PN" "BJ8"
						( Origin gPackager )
					)
					( objectStatus "U2D1.BJ8" )
				)
				( pin "pe2_rx_dp(15)"
					( attribute "PN" "BJ10"
						( Origin gPackager )
					)
					( objectStatus "U2D1.BJ10" )
				)
				( pin "pe2_tx_dn(0)"
					( attribute "PN" "CY3"
						( Origin gPackager )
					)
					( objectStatus "U2D1.CY3" )
				)
				( pin "pe2_tx_dn(1)"
					( attribute "PN" "CV3"
						( Origin gPackager )
					)
					( objectStatus "U2D1.CV3" )
				)
				( pin "pe2_tx_dn(2)"
					( attribute "PN" "CT1"
						( Origin gPackager )
					)
					( objectStatus "U2D1.CT1" )
				)
				( pin "pe2_tx_dn(3)"
					( attribute "PN" "CT3"
						( Origin gPackager )
					)
					( objectStatus "U2D1.CT3" )
				)
				( pin "pe2_tx_dn(4)"
					( attribute "PN" "CM1"
						( Origin gPackager )
					)
					( objectStatus "U2D1.CM1" )
				)
				( pin "pe2_tx_dn(5)"
					( attribute "PN" "CL2"
						( Origin gPackager )
					)
					( objectStatus "U2D1.CL2" )
				)
				( pin "pe2_tx_dn(6)"
					( attribute "PN" "CG2"
						( Origin gPackager )
					)
					( objectStatus "U2D1.CG2" )
				)
				( pin "pe2_tx_dn(7)"
					( attribute "PN" "CF3"
						( Origin gPackager )
					)
					( objectStatus "U2D1.CF3" )
				)
				( pin "pe2_tx_dn(8)"
					( attribute "PN" "CC2"
						( Origin gPackager )
					)
					( objectStatus "U2D1.CC2" )
				)
				( pin "pe2_tx_dn(9)"
					( attribute "PN" "CB3"
						( Origin gPackager )
					)
					( objectStatus "U2D1.CB3" )
				)
				( pin "pe2_tx_dn(10)"
					( attribute "PN" "CA4"
						( Origin gPackager )
					)
					( objectStatus "U2D1.CA4" )
				)
				( pin "pe2_tx_dn(11)"
					( attribute "PN" "BW4"
						( Origin gPackager )
					)
					( objectStatus "U2D1.BW4" )
				)
				( pin "pe2_tx_dn(12)"
					( attribute "PN" "BU4"
						( Origin gPackager )
					)
					( objectStatus "U2D1.BU4" )
				)
				( pin "pe2_tx_dn(13)"
					( attribute "PN" "BP5"
						( Origin gPackager )
					)
					( objectStatus "U2D1.BP5" )
				)
				( pin "pe2_tx_dn(14)"
					( attribute "PN" "BL4"
						( Origin gPackager )
					)
					( objectStatus "U2D1.BL4" )
				)
				( pin "pe2_tx_dn(15)"
					( attribute "PN" "BM5"
						( Origin gPackager )
					)
					( objectStatus "U2D1.BM5" )
				)
				( pin "pe2_tx_dp(0)"
					( attribute "PN" "CW4"
						( Origin gPackager )
					)
					( objectStatus "U2D1.CW4" )
				)
				( pin "pe2_tx_dp(1)"
					( attribute "PN" "CU2"
						( Origin gPackager )
					)
					( objectStatus "U2D1.CU2" )
				)
				( pin "pe2_tx_dp(2)"
					( attribute "PN" "CR2"
						( Origin gPackager )
					)
					( objectStatus "U2D1.CR2" )
				)
				( pin "pe2_tx_dp(3)"
					( attribute "PN" "CP3"
						( Origin gPackager )
					)
					( objectStatus "U2D1.CP3" )
				)
				( pin "pe2_tx_dp(4)"
					( attribute "PN" "CK1"
						( Origin gPackager )
					)
					( objectStatus "U2D1.CK1" )
				)
				( pin "pe2_tx_dp(5)"
					( attribute "PN" "CK3"
						( Origin gPackager )
					)
					( objectStatus "U2D1.CK3" )
				)
				( pin "pe2_tx_dp(6)"
					( attribute "PN" "CE2"
						( Origin gPackager )
					)
					( objectStatus "U2D1.CE2" )
				)
				( pin "pe2_tx_dp(7)"
					( attribute "PN" "CE4"
						( Origin gPackager )
					)
					( objectStatus "U2D1.CE4" )
				)
				( pin "pe2_tx_dp(8)"
					( attribute "PN" "CD3"
						( Origin gPackager )
					)
					( objectStatus "U2D1.CD3" )
				)
				( pin "pe2_tx_dp(9)"
					( attribute "PN" "BY3"
						( Origin gPackager )
					)
					( objectStatus "U2D1.BY3" )
				)
				( pin "pe2_tx_dp(10)"
					( attribute "PN" "BY5"
						( Origin gPackager )
					)
					( objectStatus "U2D1.BY5" )
				)
				( pin "pe2_tx_dp(11)"
					( attribute "PN" "BV3"
						( Origin gPackager )
					)
					( objectStatus "U2D1.BV3" )
				)
				( pin "pe2_tx_dp(12)"
					( attribute "PN" "BR4"
						( Origin gPackager )
					)
					( objectStatus "U2D1.BR4" )
				)
				( pin "pe2_tx_dp(13)"
					( attribute "PN" "BN4"
						( Origin gPackager )
					)
					( objectStatus "U2D1.BN4" )
				)
				( pin "pe2_tx_dp(14)"
					( attribute "PN" "BM3"
						( Origin gPackager )
					)
					( objectStatus "U2D1.BM3" )
				)
				( pin "pe2_tx_dp(15)"
					( attribute "PN" "BK5"
						( Origin gPackager )
					)
					( objectStatus "U2D1.BK5" )
				)
			)
			( gate "@baseboard_fab2_lib.baseboard_fab2(sch_1):page66_i84"
				( attribute "CDS_LIB" "chpset_lib"
					( Origin gPackager )
				)
				( attribute "CDS_LOCATION" "U2D1"
					( Origin gPackager )
				)
				( attribute "CDS_SEC" "12"
					( Origin gPackager )
				)
				( attribute "LOCATION" "U2D1"
					( Origin gFrontEnd )
				)
				( attribute "MATERIAL" "IC"
					( Origin gFrontEnd )
				)
				( attribute "PACK_TYPE" "BGA1"
					( Origin gFrontEnd )
				)
				( attribute "PART_NUMBER" "TBD"
					( Origin gFrontEnd )
				)
				( attribute "PHYS_PAGE" "66"
					( Origin gFrontEnd )
				)
				( attribute "ROT" "0"
					( Origin gFrontEnd )
				)
				( attribute "SEC" "12"
					( Origin gFrontEnd )
				)
				( attribute "SEC_TYPE" "BGA1"
					( Origin gFrontEnd )
				)
				( attribute "VER" "12"
					( Origin gFrontEnd )
				)
				( attribute "XY" "(-4125,2575)"
					( Origin gFrontEnd )
				)
				( attribute "CHIPS_PART_NAME" "SKX_EXT_B"
					( Origin gPackager )
				)
				( attribute "CDS_PART_NAME" "SKX_EXT_B_BGA1-IC,TBD"
					( Origin gPackager )
				)
				( objectStatus "U2D1" )
				( pin "pe3_rx_dn(0)"
					( attribute "PN" "EA18"
						( Origin gPackager )
					)
					( objectStatus "U2D1.EA18" )
				)
				( pin "pe3_rx_dn(1)"
					( attribute "PN" "DW18"
						( Origin gPackager )
					)
					( objectStatus "U2D1.DW18" )
				)
				( pin "pe3_rx_dn(2)"
					( attribute "PN" "DW16"
						( Origin gPackager )
					)
					( objectStatus "U2D1.DW16" )
				)
				( pin "pe3_rx_dn(3)"
					( attribute "PN" "DT19"
						( Origin gPackager )
					)
					( objectStatus "U2D1.DT19" )
				)
				( pin "pe3_rx_dn(4)"
					( attribute "PN" "DR16"
						( Origin gPackager )
					)
					( objectStatus "U2D1.DR16" )
				)
				( pin "pe3_rx_dn(5)"
					( attribute "PN" "DR14"
						( Origin gPackager )
					)
					( objectStatus "U2D1.DR14" )
				)
				( pin "pe3_rx_dn(6)"
					( attribute "PN" "DN14"
						( Origin gPackager )
					)
					( objectStatus "U2D1.DN14" )
				)
				( pin "pe3_rx_dn(7)"
					( attribute "PN" "DL14"
						( Origin gPackager )
					)
					( objectStatus "U2D1.DL14" )
				)
				( pin "pe3_rx_dn(8)"
					( attribute "PN" "DL12"
						( Origin gPackager )
					)
					( objectStatus "U2D1.DL12" )
				)
				( pin "pe3_rx_dn(9)"
					( attribute "PN" "DJ12"
						( Origin gPackager )
					)
					( objectStatus "U2D1.DJ12" )
				)
				( pin "pe3_rx_dn(10)"
					( attribute "PN" "DG12"
						( Origin gPackager )
					)
					( objectStatus "U2D1.DG12" )
				)
				( pin "pe3_rx_dn(11)"
					( attribute "PN" "DG10"
						( Origin gPackager )
					)
					( objectStatus "U2D1.DG10" )
				)
				( pin "pe3_rx_dn(12)"
					( attribute "PN" "DD13"
						( Origin gPackager )
					)
					( objectStatus "U2D1.DD13" )
				)
				( pin "pe3_rx_dn(13)"
					( attribute "PN" "DB11"
						( Origin gPackager )
					)
					( objectStatus "U2D1.DB11" )
				)
				( pin "pe3_rx_dn(14)"
					( attribute "PN" "CY11"
						( Origin gPackager )
					)
					( objectStatus "U2D1.CY11" )
				)
				( pin "pe3_rx_dn(15)"
					( attribute "PN" "CV9"
						( Origin gPackager )
					)
					( objectStatus "U2D1.CV9" )
				)
				( pin "pe3_rx_dp(0)"
					( attribute "PN" "DY17"
						( Origin gPackager )
					)
					( objectStatus "U2D1.DY17" )
				)
				( pin "pe3_rx_dp(1)"
					( attribute "PN" "DU18"
						( Origin gPackager )
					)
					( objectStatus "U2D1.DU18" )
				)
				( pin "pe3_rx_dp(2)"
					( attribute "PN" "DV17"
						( Origin gPackager )
					)
					( objectStatus "U2D1.DV17" )
				)
				( pin "pe3_rx_dp(3)"
					( attribute "PN" "DR18"
						( Origin gPackager )
					)
					( objectStatus "U2D1.DR18" )
				)
				( pin "pe3_rx_dp(4)"
					( attribute "PN" "DN16"
						( Origin gPackager )
					)
					( objectStatus "U2D1.DN16" )
				)
				( pin "pe3_rx_dp(5)"
					( attribute "PN" "DP15"
						( Origin gPackager )
					)
					( objectStatus "U2D1.DP15" )
				)
				( pin "pe3_rx_dp(6)"
					( attribute "PN" "DM13"
						( Origin gPackager )
					)
					( objectStatus "U2D1.DM13" )
				)
				( pin "pe3_rx_dp(7)"
					( attribute "PN" "DJ14"
						( Origin gPackager )
					)
					( objectStatus "U2D1.DJ14" )
				)
				( pin "pe3_rx_dp(8)"
					( attribute "PN" "DK13"
						( Origin gPackager )
					)
					( objectStatus "U2D1.DK13" )
				)
				( pin "pe3_rx_dp(9)"
					( attribute "PN" "DH11"
						( Origin gPackager )
					)
					( objectStatus "U2D1.DH11" )
				)
				( pin "pe3_rx_dp(10)"
					( attribute "PN" "DE12"
						( Origin gPackager )
					)
					( objectStatus "U2D1.DE12" )
				)
				( pin "pe3_rx_dp(11)"
					( attribute "PN" "DF11"
						( Origin gPackager )
					)
					( objectStatus "U2D1.DF11" )
				)
				( pin "pe3_rx_dp(12)"
					( attribute "PN" "DC12"
						( Origin gPackager )
					)
					( objectStatus "U2D1.DC12" )
				)
				( pin "pe3_rx_dp(13)"
					( attribute "PN" "DA12"
						( Origin gPackager )
					)
					( objectStatus "U2D1.DA12" )
				)
				( pin "pe3_rx_dp(14)"
					( attribute "PN" "CW10"
						( Origin gPackager )
					)
					( objectStatus "U2D1.CW10" )
				)
				( pin "pe3_rx_dp(15)"
					( attribute "PN" "CU10"
						( Origin gPackager )
					)
					( objectStatus "U2D1.CU10" )
				)
				( pin "pe3_tx_dn(0)"
					( attribute "PN" "EE14"
						( Origin gPackager )
					)
					( objectStatus "U2D1.EE14" )
				)
				( pin "pe3_tx_dn(1)"
					( attribute "PN" "EE12"
						( Origin gPackager )
					)
					( objectStatus "U2D1.EE12" )
				)
				( pin "pe3_tx_dn(2)"
					( attribute "PN" "EC12"
						( Origin gPackager )
					)
					( objectStatus "U2D1.EC12" )
				)
				( pin "pe3_tx_dn(3)"
					( attribute "PN" "DY11"
						( Origin gPackager )
					)
					( objectStatus "U2D1.DY11" )
				)
				( pin "pe3_tx_dn(4)"
					( attribute "PN" "EB9"
						( Origin gPackager )
					)
					( objectStatus "U2D1.EB9" )
				)
				( pin "pe3_tx_dn(5)"
					( attribute "PN" "DW10"
						( Origin gPackager )
					)
					( objectStatus "U2D1.DW10" )
				)
				( pin "pe3_tx_dn(6)"
					( attribute "PN" "DU8"
						( Origin gPackager )
					)
					( objectStatus "U2D1.DU8" )
				)
				( pin "pe3_tx_dn(7)"
					( attribute "PN" "DR8"
						( Origin gPackager )
					)
					( objectStatus "U2D1.DR8" )
				)
				( pin "pe3_tx_dn(8)"
					( attribute "PN" "DM7"
						( Origin gPackager )
					)
					( objectStatus "U2D1.DM7" )
				)
				( pin "pe3_tx_dn(9)"
					( attribute "PN" "DP5"
						( Origin gPackager )
					)
					( objectStatus "U2D1.DP5" )
				)
				( pin "pe3_tx_dn(10)"
					( attribute "PN" "DL6"
						( Origin gPackager )
					)
					( objectStatus "U2D1.DL6" )
				)
				( pin "pe3_tx_dn(11)"
					( attribute "PN" "DJ4"
						( Origin gPackager )
					)
					( objectStatus "U2D1.DJ4" )
				)
				( pin "pe3_tx_dn(12)"
					( attribute "PN" "DJ6"
						( Origin gPackager )
					)
					( objectStatus "U2D1.DJ6" )
				)
				( pin "pe3_tx_dn(13)"
					( attribute "PN" "DD5"
						( Origin gPackager )
					)
					( objectStatus "U2D1.DD5" )
				)
				( pin "pe3_tx_dn(14)"
					( attribute "PN" "DB5"
						( Origin gPackager )
					)
					( objectStatus "U2D1.DB5" )
				)
				( pin "pe3_tx_dn(15)"
					( attribute "PN" "CY5"
						( Origin gPackager )
					)
					( objectStatus "U2D1.CY5" )
				)
				( pin "pe3_tx_dp(0)"
					( attribute "PN" "EC14"
						( Origin gPackager )
					)
					( objectStatus "U2D1.EC14" )
				)
				( pin "pe3_tx_dp(1)"
					( attribute "PN" "ED13"
						( Origin gPackager )
					)
					( objectStatus "U2D1.ED13" )
				)
				( pin "pe3_tx_dp(2)"
					( attribute "PN" "EB11"
						( Origin gPackager )
					)
					( objectStatus "U2D1.EB11" )
				)
				( pin "pe3_tx_dp(3)"
					( attribute "PN" "EA10"
						( Origin gPackager )
					)
					( objectStatus "U2D1.EA10" )
				)
				( pin "pe3_tx_dp(4)"
					( attribute "PN" "DY9"
						( Origin gPackager )
					)
					( objectStatus "U2D1.DY9" )
				)
				( pin "pe3_tx_dp(5)"
					( attribute "PN" "DV9"
						( Origin gPackager )
					)
					( objectStatus "U2D1.DV9" )
				)
				( pin "pe3_tx_dp(6)"
					( attribute "PN" "DT9"
						( Origin gPackager )
					)
					( objectStatus "U2D1.DT9" )
				)
				( pin "pe3_tx_dp(7)"
					( attribute "PN" "DP7"
						( Origin gPackager )
					)
					( objectStatus "U2D1.DP7" )
				)
				( pin "pe3_tx_dp(8)"
					( attribute "PN" "DN6"
						( Origin gPackager )
					)
					( objectStatus "U2D1.DN6" )
				)
				( pin "pe3_tx_dp(9)"
					( attribute "PN" "DM5"
						( Origin gPackager )
					)
					( objectStatus "U2D1.DM5" )
				)
				( pin "pe3_tx_dp(10)"
					( attribute "PN" "DK5"
						( Origin gPackager )
					)
					( objectStatus "U2D1.DK5" )
				)
				( pin "pe3_tx_dp(11)"
					( attribute "PN" "DH5"
						( Origin gPackager )
					)
					( objectStatus "U2D1.DH5" )
				)
				( pin "pe3_tx_dp(12)"
					( attribute "PN" "DG6"
						( Origin gPackager )
					)
					( objectStatus "U2D1.DG6" )
				)
				( pin "pe3_tx_dp(13)"
					( attribute "PN" "DC6"
						( Origin gPackager )
					)
					( objectStatus "U2D1.DC6" )
				)
				( pin "pe3_tx_dp(14)"
					( attribute "PN" "DA4"
						( Origin gPackager )
					)
					( objectStatus "U2D1.DA4" )
				)
				( pin "pe3_tx_dp(15)"
					( attribute "PN" "CV5"
						( Origin gPackager )
					)
					( objectStatus "U2D1.CV5" )
				)
			)
			( gate "@baseboard_fab2_lib.baseboard_fab2(sch_1):page67_i132"
				( attribute "CDS_LIB" "chpset_lib"
					( Origin gPackager )
				)
				( attribute "CDS_LOCATION" "U2D1"
					( Origin gPackager )
				)
				( attribute "CDS_SEC" "13"
					( Origin gPackager )
				)
				( attribute "LOCATION" "U2D1"
					( Origin gFrontEnd )
				)
				( attribute "MATERIAL" "IC"
					( Origin gFrontEnd )
				)
				( attribute "PACK_TYPE" "BGA1"
					( Origin gFrontEnd )
				)
				( attribute "PART_NUMBER" "TBD"
					( Origin gFrontEnd )
				)
				( attribute "PHYS_PAGE" "67"
					( Origin gFrontEnd )
				)
				( attribute "ROT" "0"
					( Origin gFrontEnd )
				)
				( attribute "SEC" "13"
					( Origin gFrontEnd )
				)
				( attribute "SEC_TYPE" "BGA1"
					( Origin gFrontEnd )
				)
				( attribute "VER" "13"
					( Origin gFrontEnd )
				)
				( attribute "XY" "(-4050,2575)"
					( Origin gFrontEnd )
				)
				( attribute "CHIPS_PART_NAME" "SKX_EXT_B"
					( Origin gPackager )
				)
				( attribute "CDS_PART_NAME" "SKX_EXT_B_BGA1-IC,TBD"
					( Origin gPackager )
				)
				( objectStatus "U2D1" )
				( pin "upi0_rx_dn(0)"
					( attribute "PN" "AC10"
						( Origin gPackager )
					)
					( objectStatus "U2D1.AC10" )
				)
				( pin "upi0_rx_dn(1)"
					( attribute "PN" "AA8"
						( Origin gPackager )
					)
					( objectStatus "U2D1.AA8" )
				)
				( pin "upi0_rx_dn(2)"
					( attribute "PN" "AB7"
						( Origin gPackager )
					)
					( objectStatus "U2D1.AB7" )
				)
				( pin "upi0_rx_dn(3)"
					( attribute "PN" "AD5"
						( Origin gPackager )
					)
					( objectStatus "U2D1.AD5" )
				)
				( pin "upi0_rx_dn(4)"
					( attribute "PN" "AE6"
						( Origin gPackager )
					)
					( objectStatus "U2D1.AE6" )
				)
				( pin "upi0_rx_dn(5)"
					( attribute "PN" "AG8"
						( Origin gPackager )
					)
					( objectStatus "U2D1.AG8" )
				)
				( pin "upi0_rx_dn(6)"
					( attribute "PN" "AJ6"
						( Origin gPackager )
					)
					( objectStatus "U2D1.AJ6" )
				)
				( pin "upi0_rx_dn(7)"
					( attribute "PN" "AL6"
						( Origin gPackager )
					)
					( objectStatus "U2D1.AL6" )
				)
				( pin "upi0_rx_dn(8)"
					( attribute "PN" "AK7"
						( Origin gPackager )
					)
					( objectStatus "U2D1.AK7" )
				)
				( pin "upi0_rx_dn(9)"
					( attribute "PN" "AM9"
						( Origin gPackager )
					)
					( objectStatus "U2D1.AM9" )
				)
				( pin "upi0_rx_dn(10)"
					( attribute "PN" "AP7"
						( Origin gPackager )
					)
					( objectStatus "U2D1.AP7" )
				)
				( pin "upi0_rx_dn(11)"
					( attribute "PN" "AR8"
						( Origin gPackager )
					)
					( objectStatus "U2D1.AR8" )
				)
				( pin "upi0_rx_dn(12)"
					( attribute "PN" "AU10"
						( Origin gPackager )
					)
					( objectStatus "U2D1.AU10" )
				)
				( pin "upi0_rx_dn(13)"
					( attribute "PN" "BA8"
						( Origin gPackager )
					)
					( objectStatus "U2D1.BA8" )
				)
				( pin "upi0_rx_dn(14)"
					( attribute "PN" "BC6"
						( Origin gPackager )
					)
					( objectStatus "U2D1.BC6" )
				)
				( pin "upi0_rx_dn(15)"
					( attribute "PN" "BD7"
						( Origin gPackager )
					)
					( objectStatus "U2D1.BD7" )
				)
				( pin "upi0_rx_dn(16)"
					( attribute "PN" "AW8"
						( Origin gPackager )
					)
					( objectStatus "U2D1.AW8" )
				)
				( pin "upi0_rx_dn(17)"
					( attribute "PN" "AY9"
						( Origin gPackager )
					)
					( objectStatus "U2D1.AY9" )
				)
				( pin "upi0_rx_dn(18)"
					( attribute "PN" "BD9"
						( Origin gPackager )
					)
					( objectStatus "U2D1.BD9" )
				)
				( pin "upi0_rx_dn(19)"
					( attribute "PN" "BB11"
						( Origin gPackager )
					)
					( objectStatus "U2D1.BB11" )
				)
				( pin "upi0_rx_dp(0)"
					( attribute "PN" "AB9"
						( Origin gPackager )
					)
					( objectStatus "U2D1.AB9" )
				)
				( pin "upi0_rx_dp(1)"
					( attribute "PN" "AC8"
						( Origin gPackager )
					)
					( objectStatus "U2D1.AC8" )
				)
				( pin "upi0_rx_dp(2)"
					( attribute "PN" "AA6"
						( Origin gPackager )
					)
					( objectStatus "U2D1.AA6" )
				)
				( pin "upi0_rx_dp(3)"
					( attribute "PN" "AC6"
						( Origin gPackager )
					)
					( objectStatus "U2D1.AC6" )
				)
				( pin "upi0_rx_dp(4)"
					( attribute "PN" "AG6"
						( Origin gPackager )
					)
					( objectStatus "U2D1.AG6" )
				)
				( pin "upi0_rx_dp(5)"
					( attribute "PN" "AF7"
						( Origin gPackager )
					)
					( objectStatus "U2D1.AF7" )
				)
				( pin "upi0_rx_dp(6)"
					( attribute "PN" "AH7"
						( Origin gPackager )
					)
					( objectStatus "U2D1.AH7" )
				)
				( pin "upi0_rx_dp(7)"
					( attribute "PN" "AK5"
						( Origin gPackager )
					)
					( objectStatus "U2D1.AK5" )
				)
				( pin "upi0_rx_dp(8)"
					( attribute "PN" "AM7"
						( Origin gPackager )
					)
					( objectStatus "U2D1.AM7" )
				)
				( pin "upi0_rx_dp(9)"
					( attribute "PN" "AL8"
						( Origin gPackager )
					)
					( objectStatus "U2D1.AL8" )
				)
				( pin "upi0_rx_dp(10)"
					( attribute "PN" "AN8"
						( Origin gPackager )
					)
					( objectStatus "U2D1.AN8" )
				)
				( pin "upi0_rx_dp(11)"
					( attribute "PN" "AU8"
						( Origin gPackager )
					)
					( objectStatus "U2D1.AU8" )
				)
				( pin "upi0_rx_dp(12)"
					( attribute "PN" "AT9"
						( Origin gPackager )
					)
					( objectStatus "U2D1.AT9" )
				)
				( pin "upi0_rx_dp(13)"
					( attribute "PN" "AY7"
						( Origin gPackager )
					)
					( objectStatus "U2D1.AY7" )
				)
				( pin "upi0_rx_dp(14)"
					( attribute "PN" "BB7"
						( Origin gPackager )
					)
					( objectStatus "U2D1.BB7" )
				)
				( pin "upi0_rx_dp(15)"
					( attribute "PN" "BF7"
						( Origin gPackager )
					)
					( objectStatus "U2D1.BF7" )
				)
				( pin "upi0_rx_dp(16)"
					( attribute "PN" "AV9"
						( Origin gPackager )
					)
					( objectStatus "U2D1.AV9" )
				)
				( pin "upi0_rx_dp(17)"
					( attribute "PN" "BB9"
						( Origin gPackager )
					)
					( objectStatus "U2D1.BB9" )
				)
				( pin "upi0_rx_dp(18)"
					( attribute "PN" "BC10"
						( Origin gPackager )
					)
					( objectStatus "U2D1.BC10" )
				)
				( pin "upi0_rx_dp(19)"
					( attribute "PN" "BA10"
						( Origin gPackager )
					)
					( objectStatus "U2D1.BA10" )
				)
				( pin "upi0_tx_dn(0)"
					( attribute "PN" "N2"
						( Origin gPackager )
					)
					( objectStatus "U2D1.N2" )
				)
				( pin "upi0_tx_dn(1)"
					( attribute "PN" "P1"
						( Origin gPackager )
					)
					( objectStatus "U2D1.P1" )
				)
				( pin "upi0_tx_dn(2)"
					( attribute "PN" "V3"
						( Origin gPackager )
					)
					( objectStatus "U2D1.V3" )
				)
				( pin "upi0_tx_dn(3)"
					( attribute "PN" "Y1"
						( Origin gPackager )
					)
					( objectStatus "U2D1.Y1" )
				)
				( pin "upi0_tx_dn(4)"
					( attribute "PN" "AB3"
						( Origin gPackager )
					)
					( objectStatus "U2D1.AB3" )
				)
				( pin "upi0_tx_dn(5)"
					( attribute "PN" "AC2"
						( Origin gPackager )
					)
					( objectStatus "U2D1.AC2" )
				)
				( pin "upi0_tx_dn(6)"
					( attribute "PN" "AG4"
						( Origin gPackager )
					)
					( objectStatus "U2D1.AG4" )
				)
				( pin "upi0_tx_dn(7)"
					( attribute "PN" "AE2"
						( Origin gPackager )
					)
					( objectStatus "U2D1.AE2" )
				)
				( pin "upi0_tx_dn(8)"
					( attribute "PN" "AH3"
						( Origin gPackager )
					)
					( objectStatus "U2D1.AH3" )
				)
				( pin "upi0_tx_dn(9)"
					( attribute "PN" "AL2"
						( Origin gPackager )
					)
					( objectStatus "U2D1.AL2" )
				)
				( pin "upi0_tx_dn(10)"
					( attribute "PN" "AM3"
						( Origin gPackager )
					)
					( objectStatus "U2D1.AM3" )
				)
				( pin "upi0_tx_dn(11)"
					( attribute "PN" "AN4"
						( Origin gPackager )
					)
					( objectStatus "U2D1.AN4" )
				)
				( pin "upi0_tx_dn(12)"
					( attribute "PN" "AT1"
						( Origin gPackager )
					)
					( objectStatus "U2D1.AT1" )
				)
				( pin "upi0_tx_dn(13)"
					( attribute "PN" "AT3"
						( Origin gPackager )
					)
					( objectStatus "U2D1.AT3" )
				)
				( pin "upi0_tx_dn(14)"
					( attribute "PN" "AU4"
						( Origin gPackager )
					)
					( objectStatus "U2D1.AU4" )
				)
				( pin "upi0_tx_dn(15)"
					( attribute "PN" "AV5"
						( Origin gPackager )
					)
					( objectStatus "U2D1.AV5" )
				)
				( pin "upi0_tx_dn(16)"
					( attribute "PN" "BA4"
						( Origin gPackager )
					)
					( objectStatus "U2D1.BA4" )
				)
				( pin "upi0_tx_dn(17)"
					( attribute "PN" "BB3"
						( Origin gPackager )
					)
					( objectStatus "U2D1.BB3" )
				)
				( pin "upi0_tx_dn(18)"
					( attribute "PN" "BF3"
						( Origin gPackager )
					)
					( objectStatus "U2D1.BF3" )
				)
				( pin "upi0_tx_dn(19)"
					( attribute "PN" "BG4"
						( Origin gPackager )
					)
					( objectStatus "U2D1.BG4" )
				)
				( pin "upi0_tx_dp(0)"
					( attribute "PN" "M1"
						( Origin gPackager )
					)
					( objectStatus "U2D1.M1" )
				)
				( pin "upi0_tx_dp(1)"
					( attribute "PN" "T1"
						( Origin gPackager )
					)
					( objectStatus "U2D1.T1" )
				)
				( pin "upi0_tx_dp(2)"
					( attribute "PN" "Y3"
						( Origin gPackager )
					)
					( objectStatus "U2D1.Y3" )
				)
				( pin "upi0_tx_dp(3)"
					( attribute "PN" "W2"
						( Origin gPackager )
					)
					( objectStatus "U2D1.W2" )
				)
				( pin "upi0_tx_dp(4)"
					( attribute "PN" "AA2"
						( Origin gPackager )
					)
					( objectStatus "U2D1.AA2" )
				)
				( pin "upi0_tx_dp(5)"
					( attribute "PN" "AD1"
						( Origin gPackager )
					)
					( objectStatus "U2D1.AD1" )
				)
				( pin "upi0_tx_dp(6)"
					( attribute "PN" "AF3"
						( Origin gPackager )
					)
					( objectStatus "U2D1.AF3" )
				)
				( pin "upi0_tx_dp(7)"
					( attribute "PN" "AG2"
						( Origin gPackager )
					)
					( objectStatus "U2D1.AG2" )
				)
				( pin "upi0_tx_dp(8)"
					( attribute "PN" "AJ2"
						( Origin gPackager )
					)
					( objectStatus "U2D1.AJ2" )
				)
				( pin "upi0_tx_dp(9)"
					( attribute "PN" "AK1"
						( Origin gPackager )
					)
					( objectStatus "U2D1.AK1" )
				)
				( pin "upi0_tx_dp(10)"
					( attribute "PN" "AK3"
						( Origin gPackager )
					)
					( objectStatus "U2D1.AK3" )
				)
				( pin "upi0_tx_dp(11)"
					( attribute "PN" "AP3"
						( Origin gPackager )
					)
					( objectStatus "U2D1.AP3" )
				)
				( pin "upi0_tx_dp(12)"
					( attribute "PN" "AP1"
						( Origin gPackager )
					)
					( objectStatus "U2D1.AP1" )
				)
				( pin "upi0_tx_dp(13)"
					( attribute "PN" "AR2"
						( Origin gPackager )
					)
					( objectStatus "U2D1.AR2" )
				)
				( pin "upi0_tx_dp(14)"
					( attribute "PN" "AR4"
						( Origin gPackager )
					)
					( objectStatus "U2D1.AR4" )
				)
				( pin "upi0_tx_dp(15)"
					( attribute "PN" "AW4"
						( Origin gPackager )
					)
					( objectStatus "U2D1.AW4" )
				)
				( pin "upi0_tx_dp(16)"
					( attribute "PN" "AY3"
						( Origin gPackager )
					)
					( objectStatus "U2D1.AY3" )
				)
				( pin "upi0_tx_dp(17)"
					( attribute "PN" "BC2"
						( Origin gPackager )
					)
					( objectStatus "U2D1.BC2" )
				)
				( pin "upi0_tx_dp(18)"
					( attribute "PN" "BD3"
						( Origin gPackager )
					)
					( objectStatus "U2D1.BD3" )
				)
				( pin "upi0_tx_dp(19)"
					( attribute "PN" "BH3"
						( Origin gPackager )
					)
					( objectStatus "U2D1.BH3" )
				)
			)
			( gate "@baseboard_fab2_lib.baseboard_fab2(sch_1):page68_i125"
				( attribute "CDS_LIB" "chpset_lib"
					( Origin gPackager )
				)
				( attribute "CDS_LOCATION" "U2D1"
					( Origin gPackager )
				)
				( attribute "CDS_SEC" "14"
					( Origin gPackager )
				)
				( attribute "LOCATION" "U2D1"
					( Origin gFrontEnd )
				)
				( attribute "MATERIAL" "IC"
					( Origin gFrontEnd )
				)
				( attribute "PACK_TYPE" "BGA1"
					( Origin gFrontEnd )
				)
				( attribute "PART_NUMBER" "TBD"
					( Origin gFrontEnd )
				)
				( attribute "PHYS_PAGE" "68"
					( Origin gFrontEnd )
				)
				( attribute "ROT" "0"
					( Origin gFrontEnd )
				)
				( attribute "SEC" "14"
					( Origin gFrontEnd )
				)
				( attribute "SEC_TYPE" "BGA1"
					( Origin gFrontEnd )
				)
				( attribute "VER" "14"
					( Origin gFrontEnd )
				)
				( attribute "XY" "(-4100,2650)"
					( Origin gFrontEnd )
				)
				( attribute "CHIPS_PART_NAME" "SKX_EXT_B"
					( Origin gPackager )
				)
				( attribute "CDS_PART_NAME" "SKX_EXT_B_BGA1-IC,TBD"
					( Origin gPackager )
				)
				( objectStatus "U2D1" )
				( pin "upi1_rx_dn(0)"
					( attribute "PN" "T5"
						( Origin gPackager )
					)
					( objectStatus "U2D1.T5" )
				)
				( pin "upi1_rx_dn(1)"
					( attribute "PN" "P7"
						( Origin gPackager )
					)
					( objectStatus "U2D1.P7" )
				)
				( pin "upi1_rx_dn(2)"
					( attribute "PN" "V7"
						( Origin gPackager )
					)
					( objectStatus "U2D1.V7" )
				)
				( pin "upi1_rx_dn(3)"
					( attribute "PN" "T9"
						( Origin gPackager )
					)
					( objectStatus "U2D1.T9" )
				)
				( pin "upi1_rx_dn(4)"
					( attribute "PN" "P9"
						( Origin gPackager )
					)
					( objectStatus "U2D1.P9" )
				)
				( pin "upi1_rx_dn(5)"
					( attribute "PN" "R10"
						( Origin gPackager )
					)
					( objectStatus "U2D1.R10" )
				)
				( pin "upi1_rx_dn(6)"
					( attribute "PN" "U12"
						( Origin gPackager )
					)
					( objectStatus "U2D1.U12" )
				)
				( pin "upi1_rx_dn(7)"
					( attribute "PN" "L12"
						( Origin gPackager )
					)
					( objectStatus "U2D1.L12" )
				)
				( pin "upi1_rx_dn(8)"
					( attribute "PN" "N14"
						( Origin gPackager )
					)
					( objectStatus "U2D1.N14" )
				)
				( pin "upi1_rx_dn(9)"
					( attribute "PN" "R12"
						( Origin gPackager )
					)
					( objectStatus "U2D1.R12" )
				)
				( pin "upi1_rx_dn(10)"
					( attribute "PN" "R16"
						( Origin gPackager )
					)
					( objectStatus "U2D1.R16" )
				)
				( pin "upi1_rx_dn(11)"
					( attribute "PN" "P17"
						( Origin gPackager )
					)
					( objectStatus "U2D1.P17" )
				)
				( pin "upi1_rx_dn(12)"
					( attribute "PN" "U16"
						( Origin gPackager )
					)
					( objectStatus "U2D1.U16" )
				)
				( pin "upi1_rx_dn(13)"
					( attribute "PN" "W18"
						( Origin gPackager )
					)
					( objectStatus "U2D1.W18" )
				)
				( pin "upi1_rx_dn(14)"
					( attribute "PN" "R20"
						( Origin gPackager )
					)
					( objectStatus "U2D1.R20" )
				)
				( pin "upi1_rx_dn(15)"
					( attribute "PN" "U18"
						( Origin gPackager )
					)
					( objectStatus "U2D1.U18" )
				)
				( pin "upi1_rx_dn(16)"
					( attribute "PN" "P21"
						( Origin gPackager )
					)
					( objectStatus "U2D1.P21" )
				)
				( pin "upi1_rx_dn(17)"
					( attribute "PN" "V19"
						( Origin gPackager )
					)
					( objectStatus "U2D1.V19" )
				)
				( pin "upi1_rx_dn(18)"
					( attribute "PN" "Y21"
						( Origin gPackager )
					)
					( objectStatus "U2D1.Y21" )
				)
				( pin "upi1_rx_dn(19)"
					( attribute "PN" "AB19"
						( Origin gPackager )
					)
					( objectStatus "U2D1.AB19" )
				)
				( pin "upi1_rx_dp(0)"
					( attribute "PN" "R6"
						( Origin gPackager )
					)
					( objectStatus "U2D1.R6" )
				)
				( pin "upi1_rx_dp(1)"
					( attribute "PN" "T7"
						( Origin gPackager )
					)
					( objectStatus "U2D1.T7" )
				)
				( pin "upi1_rx_dp(2)"
					( attribute "PN" "U8"
						( Origin gPackager )
					)
					( objectStatus "U2D1.U8" )
				)
				( pin "upi1_rx_dp(3)"
					( attribute "PN" "R8"
						( Origin gPackager )
					)
					( objectStatus "U2D1.R8" )
				)
				( pin "upi1_rx_dp(4)"
					( attribute "PN" "N10"
						( Origin gPackager )
					)
					( objectStatus "U2D1.N10" )
				)
				( pin "upi1_rx_dp(5)"
					( attribute "PN" "U10"
						( Origin gPackager )
					)
					( objectStatus "U2D1.U10" )
				)
				( pin "upi1_rx_dp(6)"
					( attribute "PN" "T11"
						( Origin gPackager )
					)
					( objectStatus "U2D1.T11" )
				)
				( pin "upi1_rx_dp(7)"
					( attribute "PN" "N12"
						( Origin gPackager )
					)
					( objectStatus "U2D1.N12" )
				)
				( pin "upi1_rx_dp(8)"
					( attribute "PN" "M13"
						( Origin gPackager )
					)
					( objectStatus "U2D1.M13" )
				)
				( pin "upi1_rx_dp(9)"
					( attribute "PN" "P13"
						( Origin gPackager )
					)
					( objectStatus "U2D1.P13" )
				)
				( pin "upi1_rx_dp(10)"
					( attribute "PN" "T15"
						( Origin gPackager )
					)
					( objectStatus "U2D1.T15" )
				)
				( pin "upi1_rx_dp(11)"
					( attribute "PN" "N16"
						( Origin gPackager )
					)
					( objectStatus "U2D1.N16" )
				)
				( pin "upi1_rx_dp(12)"
					( attribute "PN" "W16"
						( Origin gPackager )
					)
					( objectStatus "U2D1.W16" )
				)
				( pin "upi1_rx_dp(13)"
					( attribute "PN" "V17"
						( Origin gPackager )
					)
					( objectStatus "U2D1.V17" )
				)
				( pin "upi1_rx_dp(14)"
					( attribute "PN" "P19"
						( Origin gPackager )
					)
					( objectStatus "U2D1.P19" )
				)
				( pin "upi1_rx_dp(15)"
					( attribute "PN" "T19"
						( Origin gPackager )
					)
					( objectStatus "U2D1.T19" )
				)
				( pin "upi1_rx_dp(16)"
					( attribute "PN" "T21"
						( Origin gPackager )
					)
					( objectStatus "U2D1.T21" )
				)
				( pin "upi1_rx_dp(17)"
					( attribute "PN" "Y19"
						( Origin gPackager )
					)
					( objectStatus "U2D1.Y19" )
				)
				( pin "upi1_rx_dp(18)"
					( attribute "PN" "W20"
						( Origin gPackager )
					)
					( objectStatus "U2D1.W20" )
				)
				( pin "upi1_rx_dp(19)"
					( attribute "PN" "AA20"
						( Origin gPackager )
					)
					( objectStatus "U2D1.AA20" )
				)
				( pin "upi1_tx_dn(0)"
					( attribute "PN" "M3"
						( Origin gPackager )
					)
					( objectStatus "U2D1.M3" )
				)
				( pin "upi1_tx_dn(1)"
					( attribute "PN" "L4"
						( Origin gPackager )
					)
					( objectStatus "U2D1.L4" )
				)
				( pin "upi1_tx_dn(2)"
					( attribute "PN" "K5"
						( Origin gPackager )
					)
					( objectStatus "U2D1.K5" )
				)
				( pin "upi1_tx_dn(3)"
					( attribute "PN" "J6"
						( Origin gPackager )
					)
					( objectStatus "U2D1.J6" )
				)
				( pin "upi1_tx_dn(4)"
					( attribute "PN" "G6"
						( Origin gPackager )
					)
					( objectStatus "U2D1.G6" )
				)
				( pin "upi1_tx_dn(5)"
					( attribute "PN" "H7"
						( Origin gPackager )
					)
					( objectStatus "U2D1.H7" )
				)
				( pin "upi1_tx_dn(6)"
					( attribute "PN" "K9"
						( Origin gPackager )
					)
					( objectStatus "U2D1.K9" )
				)
				( pin "upi1_tx_dn(7)"
					( attribute "PN" "D9"
						( Origin gPackager )
					)
					( objectStatus "U2D1.D9" )
				)
				( pin "upi1_tx_dn(8)"
					( attribute "PN" "F11"
						( Origin gPackager )
					)
					( objectStatus "U2D1.F11" )
				)
				( pin "upi1_tx_dn(9)"
					( attribute "PN" "G10"
						( Origin gPackager )
					)
					( objectStatus "U2D1.G10" )
				)
				( pin "upi1_tx_dn(10)"
					( attribute "PN" "E12"
						( Origin gPackager )
					)
					( objectStatus "U2D1.E12" )
				)
				( pin "upi1_tx_dn(11)"
					( attribute "PN" "G14"
						( Origin gPackager )
					)
					( objectStatus "U2D1.G14" )
				)
				( pin "upi1_tx_dn(12)"
					( attribute "PN" "D15"
						( Origin gPackager )
					)
					( objectStatus "U2D1.D15" )
				)
				( pin "upi1_tx_dn(13)"
					( attribute "PN" "F15"
						( Origin gPackager )
					)
					( objectStatus "U2D1.F15" )
				)
				( pin "upi1_tx_dn(14)"
					( attribute "PN" "H17"
						( Origin gPackager )
					)
					( objectStatus "U2D1.H17" )
				)
				( pin "upi1_tx_dn(15)"
					( attribute "PN" "K19"
						( Origin gPackager )
					)
					( objectStatus "U2D1.K19" )
				)
				( pin "upi1_tx_dn(16)"
					( attribute "PN" "G18"
						( Origin gPackager )
					)
					( objectStatus "U2D1.G18" )
				)
				( pin "upi1_tx_dn(17)"
					( attribute "PN" "J20"
						( Origin gPackager )
					)
					( objectStatus "U2D1.J20" )
				)
				( pin "upi1_tx_dn(18)"
					( attribute "PN" "F21"
						( Origin gPackager )
					)
					( objectStatus "U2D1.F21" )
				)
				( pin "upi1_tx_dn(19)"
					( attribute "PN" "H21"
						( Origin gPackager )
					)
					( objectStatus "U2D1.H21" )
				)
				( pin "upi1_tx_dp(0)"
					( attribute "PN" "P3"
						( Origin gPackager )
					)
					( objectStatus "U2D1.P3" )
				)
				( pin "upi1_tx_dp(1)"
					( attribute "PN" "K3"
						( Origin gPackager )
					)
					( objectStatus "U2D1.K3" )
				)
				( pin "upi1_tx_dp(2)"
					( attribute "PN" "M5"
						( Origin gPackager )
					)
					( objectStatus "U2D1.M5" )
				)
				( pin "upi1_tx_dp(3)"
					( attribute "PN" "H5"
						( Origin gPackager )
					)
					( objectStatus "U2D1.H5" )
				)
				( pin "upi1_tx_dp(4)"
					( attribute "PN" "F7"
						( Origin gPackager )
					)
					( objectStatus "U2D1.F7" )
				)
				( pin "upi1_tx_dp(5)"
					( attribute "PN" "K7"
						( Origin gPackager )
					)
					( objectStatus "U2D1.K7" )
				)
				( pin "upi1_tx_dp(6)"
					( attribute "PN" "J8"
						( Origin gPackager )
					)
					( objectStatus "U2D1.J8" )
				)
				( pin "upi1_tx_dp(7)"
					( attribute "PN" "F9"
						( Origin gPackager )
					)
					( objectStatus "U2D1.F9" )
				)
				( pin "upi1_tx_dp(8)"
					( attribute "PN" "E10"
						( Origin gPackager )
					)
					( objectStatus "U2D1.E10" )
				)
				( pin "upi1_tx_dp(9)"
					( attribute "PN" "H9"
						( Origin gPackager )
					)
					( objectStatus "U2D1.H9" )
				)
				( pin "upi1_tx_dp(10)"
					( attribute "PN" "G12"
						( Origin gPackager )
					)
					( objectStatus "U2D1.G12" )
				)
				( pin "upi1_tx_dp(11)"
					( attribute "PN" "F13"
						( Origin gPackager )
					)
					( objectStatus "U2D1.F13" )
				)
				( pin "upi1_tx_dp(12)"
					( attribute "PN" "E14"
						( Origin gPackager )
					)
					( objectStatus "U2D1.E14" )
				)
				( pin "upi1_tx_dp(13)"
					( attribute "PN" "H15"
						( Origin gPackager )
					)
					( objectStatus "U2D1.H15" )
				)
				( pin "upi1_tx_dp(14)"
					( attribute "PN" "G16"
						( Origin gPackager )
					)
					( objectStatus "U2D1.G16" )
				)
				( pin "upi1_tx_dp(15)"
					( attribute "PN" "L18"
						( Origin gPackager )
					)
					( objectStatus "U2D1.L18" )
				)
				( pin "upi1_tx_dp(16)"
					( attribute "PN" "J18"
						( Origin gPackager )
					)
					( objectStatus "U2D1.J18" )
				)
				( pin "upi1_tx_dp(17)"
					( attribute "PN" "H19"
						( Origin gPackager )
					)
					( objectStatus "U2D1.H19" )
				)
				( pin "upi1_tx_dp(18)"
					( attribute "PN" "G20"
						( Origin gPackager )
					)
					( objectStatus "U2D1.G20" )
				)
				( pin "upi1_tx_dp(19)"
					( attribute "PN" "K21"
						( Origin gPackager )
					)
					( objectStatus "U2D1.K21" )
				)
			)
			( gate "@baseboard_fab2_lib.baseboard_fab2(sch_1):page69_i1"
				( attribute "CDS_LIB" "chpset_lib"
					( Origin gPackager )
				)
				( attribute "CDS_LOCATION" "U2D1"
					( Origin gPackager )
				)
				( attribute "CDS_SEC" "15"
					( Origin gPackager )
				)
				( attribute "LOCATION" "U2D1"
					( Origin gFrontEnd )
				)
				( attribute "MATERIAL" "IC"
					( Origin gFrontEnd )
				)
				( attribute "PACK_TYPE" "BGA1"
					( Origin gFrontEnd )
				)
				( attribute "PART_NUMBER" "TBD"
					( Origin gFrontEnd )
				)
				( attribute "PHYS_PAGE" "69"
					( Origin gFrontEnd )
				)
				( attribute "ROT" "0"
					( Origin gFrontEnd )
				)
				( attribute "SEC" "15"
					( Origin gFrontEnd )
				)
				( attribute "SEC_TYPE" "BGA1"
					( Origin gFrontEnd )
				)
				( attribute "VER" "15"
					( Origin gFrontEnd )
				)
				( attribute "XY" "(-4275,2700)"
					( Origin gFrontEnd )
				)
				( attribute "CHIPS_PART_NAME" "SKX_EXT_B"
					( Origin gPackager )
				)
				( attribute "CDS_PART_NAME" "SKX_EXT_B_BGA1-IC,TBD"
					( Origin gPackager )
				)
				( objectStatus "U2D1" )
				( pin "upi2_rx_dn(0)"
					( attribute "PN" "DF23"
						( Origin gPackager )
					)
					( objectStatus "U2D1.DF23" )
				)
				( pin "upi2_rx_dn(1)"
					( attribute "PN" "DE22"
						( Origin gPackager )
					)
					( objectStatus "U2D1.DE22" )
				)
				( pin "upi2_rx_dn(2)"
					( attribute "PN" "DC22"
						( Origin gPackager )
					)
					( objectStatus "U2D1.DC22" )
				)
				( pin "upi2_rx_dn(3)"
					( attribute "PN" "DB21"
						( Origin gPackager )
					)
					( objectStatus "U2D1.DB21" )
				)
				( pin "upi2_rx_dn(4)"
					( attribute "PN" "DD19"
						( Origin gPackager )
					)
					( objectStatus "U2D1.DD19" )
				)
				( pin "upi2_rx_dn(5)"
					( attribute "PN" "DA20"
						( Origin gPackager )
					)
					( objectStatus "U2D1.DA20" )
				)
				( pin "upi2_rx_dn(6)"
					( attribute "PN" "CW20"
						( Origin gPackager )
					)
					( objectStatus "U2D1.CW20" )
				)
				( pin "upi2_rx_dn(7)"
					( attribute "PN" "CV19"
						( Origin gPackager )
					)
					( objectStatus "U2D1.CV19" )
				)
				( pin "upi2_rx_dn(8)"
					( attribute "PN" "CT21"
						( Origin gPackager )
					)
					( objectStatus "U2D1.CT21" )
				)
				( pin "upi2_rx_dn(9)"
					( attribute "PN" "CR18"
						( Origin gPackager )
					)
					( objectStatus "U2D1.CR18" )
				)
				( pin "upi2_rx_dn(10)"
					( attribute "PN" "CN20"
						( Origin gPackager )
					)
					( objectStatus "U2D1.CN20" )
				)
				( pin "upi2_rx_dn(11)"
					( attribute "PN" "CP21"
						( Origin gPackager )
					)
					( objectStatus "U2D1.CP21" )
				)
				( pin "upi2_rx_dn(12)"
					( attribute "PN" "CL16"
						( Origin gPackager )
					)
					( objectStatus "U2D1.CL16" )
				)
				( pin "upi2_rx_dn(13)"
					( attribute "PN" "CJ18"
						( Origin gPackager )
					)
					( objectStatus "U2D1.CJ18" )
				)
				( pin "upi2_rx_dn(14)"
					( attribute "PN" "CH17"
						( Origin gPackager )
					)
					( objectStatus "U2D1.CH17" )
				)
				( pin "upi2_rx_dn(15)"
					( attribute "PN" "CE16"
						( Origin gPackager )
					)
					( objectStatus "U2D1.CE16" )
				)
				( pin "upi2_rx_dn(16)"
					( attribute "PN" "CD15"
						( Origin gPackager )
					)
					( objectStatus "U2D1.CD15" )
				)
				( pin "upi2_rx_dn(17)"
					( attribute "PN" "CF17"
						( Origin gPackager )
					)
					( objectStatus "U2D1.CF17" )
				)
				( pin "upi2_rx_dn(18)"
					( attribute "PN" "CB15"
						( Origin gPackager )
					)
					( objectStatus "U2D1.CB15" )
				)
				( pin "upi2_rx_dn(19)"
					( attribute "PN" "BY17"
						( Origin gPackager )
					)
					( objectStatus "U2D1.BY17" )
				)
				( pin "upi2_rx_dp(0)"
					( attribute "PN" "DG22"
						( Origin gPackager )
					)
					( objectStatus "U2D1.DG22" )
				)
				( pin "upi2_rx_dp(1)"
					( attribute "PN" "DD21"
						( Origin gPackager )
					)
					( objectStatus "U2D1.DD21" )
				)
				( pin "upi2_rx_dp(2)"
					( attribute "PN" "DA22"
						( Origin gPackager )
					)
					( objectStatus "U2D1.DA22" )
				)
				( pin "upi2_rx_dp(3)"
					( attribute "PN" "DC20"
						( Origin gPackager )
					)
					( objectStatus "U2D1.DC20" )
				)
				( pin "upi2_rx_dp(4)"
					( attribute "PN" "DB19"
						( Origin gPackager )
					)
					( objectStatus "U2D1.DB19" )
				)
				( pin "upi2_rx_dp(5)"
					( attribute "PN" "CY19"
						( Origin gPackager )
					)
					( objectStatus "U2D1.CY19" )
				)
				( pin "upi2_rx_dp(6)"
					( attribute "PN" "CU20"
						( Origin gPackager )
					)
					( objectStatus "U2D1.CU20" )
				)
				( pin "upi2_rx_dp(7)"
					( attribute "PN" "CW18"
						( Origin gPackager )
					)
					( objectStatus "U2D1.CW18" )
				)
				( pin "upi2_rx_dp(8)"
					( attribute "PN" "CR20"
						( Origin gPackager )
					)
					( objectStatus "U2D1.CR20" )
				)
				( pin "upi2_rx_dp(9)"
					( attribute "PN" "CN18"
						( Origin gPackager )
					)
					( objectStatus "U2D1.CN18" )
				)
				( pin "upi2_rx_dp(10)"
					( attribute "PN" "CP19"
						( Origin gPackager )
					)
					( objectStatus "U2D1.CP19" )
				)
				( pin "upi2_rx_dp(11)"
					( attribute "PN" "CM21"
						( Origin gPackager )
					)
					( objectStatus "U2D1.CM21" )
				)
				( pin "upi2_rx_dp(12)"
					( attribute "PN" "CJ16"
						( Origin gPackager )
					)
					( objectStatus "U2D1.CJ16" )
				)
				( pin "upi2_rx_dp(13)"
					( attribute "PN" "CK17"
						( Origin gPackager )
					)
					( objectStatus "U2D1.CK17" )
				)
				( pin "upi2_rx_dp(14)"
					( attribute "PN" "CG16"
						( Origin gPackager )
					)
					( objectStatus "U2D1.CG16" )
				)
				( pin "upi2_rx_dp(15)"
					( attribute "PN" "CF15"
						( Origin gPackager )
					)
					( objectStatus "U2D1.CF15" )
				)
				( pin "upi2_rx_dp(16)"
					( attribute "PN" "CC14"
						( Origin gPackager )
					)
					( objectStatus "U2D1.CC14" )
				)
				( pin "upi2_rx_dp(17)"
					( attribute "PN" "CD17"
						( Origin gPackager )
					)
					( objectStatus "U2D1.CD17" )
				)
				( pin "upi2_rx_dp(18)"
					( attribute "PN" "BY15"
						( Origin gPackager )
					)
					( objectStatus "U2D1.BY15" )
				)
				( pin "upi2_rx_dp(19)"
					( attribute "PN" "CA16"
						( Origin gPackager )
					)
					( objectStatus "U2D1.CA16" )
				)
				( pin "upi2_tx_dn(0)"
					( attribute "PN" "DT21"
						( Origin gPackager )
					)
					( objectStatus "U2D1.DT21" )
				)
				( pin "upi2_tx_dn(1)"
					( attribute "PN" "DM21"
						( Origin gPackager )
					)
					( objectStatus "U2D1.DM21" )
				)
				( pin "upi2_tx_dn(2)"
					( attribute "PN" "DL20"
						( Origin gPackager )
					)
					( objectStatus "U2D1.DL20" )
				)
				( pin "upi2_tx_dn(3)"
					( attribute "PN" "DG20"
						( Origin gPackager )
					)
					( objectStatus "U2D1.DG20" )
				)
				( pin "upi2_tx_dn(4)"
					( attribute "PN" "DH19"
						( Origin gPackager )
					)
					( objectStatus "U2D1.DH19" )
				)
				( pin "upi2_tx_dn(5)"
					( attribute "PN" "DK17"
						( Origin gPackager )
					)
					( objectStatus "U2D1.DK17" )
				)
				( pin "upi2_tx_dn(6)"
					( attribute "PN" "DG18"
						( Origin gPackager )
					)
					( objectStatus "U2D1.DG18" )
				)
				( pin "upi2_tx_dn(7)"
					( attribute "PN" "DD17"
						( Origin gPackager )
					)
					( objectStatus "U2D1.DD17" )
				)
				( pin "upi2_tx_dn(8)"
					( attribute "PN" "DF15"
						( Origin gPackager )
					)
					( objectStatus "U2D1.DF15" )
				)
				( pin "upi2_tx_dn(9)"
					( attribute "PN" "DC16"
						( Origin gPackager )
					)
					( objectStatus "U2D1.DC16" )
				)
				( pin "upi2_tx_dn(10)"
					( attribute "PN" "DA16"
						( Origin gPackager )
					)
					( objectStatus "U2D1.DA16" )
				)
				( pin "upi2_tx_dn(11)"
					( attribute "PN" "CW14"
						( Origin gPackager )
					)
					( objectStatus "U2D1.CW14" )
				)
				( pin "upi2_tx_dn(12)"
					( attribute "PN" "CU14"
						( Origin gPackager )
					)
					( objectStatus "U2D1.CU14" )
				)
				( pin "upi2_tx_dn(13)"
					( attribute "PN" "CM13"
						( Origin gPackager )
					)
					( objectStatus "U2D1.CM13" )
				)
				( pin "upi2_tx_dn(14)"
					( attribute "PN" "CJ14"
						( Origin gPackager )
					)
					( objectStatus "U2D1.CJ14" )
				)
				( pin "upi2_tx_dn(15)"
					( attribute "PN" "CF13"
						( Origin gPackager )
					)
					( objectStatus "U2D1.CF13" )
				)
				( pin "upi2_tx_dn(16)"
					( attribute "PN" "CH11"
						( Origin gPackager )
					)
					( objectStatus "U2D1.CH11" )
				)
				( pin "upi2_tx_dn(17)"
					( attribute "PN" "CE12"
						( Origin gPackager )
					)
					( objectStatus "U2D1.CE12" )
				)
				( pin "upi2_tx_dn(18)"
					( attribute "PN" "CC10"
						( Origin gPackager )
					)
					( objectStatus "U2D1.CC10" )
				)
				( pin "upi2_tx_dn(19)"
					( attribute "PN" "CC12"
						( Origin gPackager )
					)
					( objectStatus "U2D1.CC12" )
				)
				( pin "upi2_tx_dp(0)"
					( attribute "PN" "DP21"
						( Origin gPackager )
					)
					( objectStatus "U2D1.DP21" )
				)
				( pin "upi2_tx_dp(1)"
					( attribute "PN" "DN20"
						( Origin gPackager )
					)
					( objectStatus "U2D1.DN20" )
				)
				( pin "upi2_tx_dp(2)"
					( attribute "PN" "DK19"
						( Origin gPackager )
					)
					( objectStatus "U2D1.DK19" )
				)
				( pin "upi2_tx_dp(3)"
					( attribute "PN" "DJ20"
						( Origin gPackager )
					)
					( objectStatus "U2D1.DJ20" )
				)
				( pin "upi2_tx_dp(4)"
					( attribute "PN" "DJ18"
						( Origin gPackager )
					)
					( objectStatus "U2D1.DJ18" )
				)
				( pin "upi2_tx_dp(5)"
					( attribute "PN" "DH17"
						( Origin gPackager )
					)
					( objectStatus "U2D1.DH17" )
				)
				( pin "upi2_tx_dp(6)"
					( attribute "PN" "DF17"
						( Origin gPackager )
					)
					( objectStatus "U2D1.DF17" )
				)
				( pin "upi2_tx_dp(7)"
					( attribute "PN" "DE16"
						( Origin gPackager )
					)
					( objectStatus "U2D1.DE16" )
				)
				( pin "upi2_tx_dp(8)"
					( attribute "PN" "DD15"
						( Origin gPackager )
					)
					( objectStatus "U2D1.DD15" )
				)
				( pin "upi2_tx_dp(9)"
					( attribute "PN" "DB15"
						( Origin gPackager )
					)
					( objectStatus "U2D1.DB15" )
				)
				( pin "upi2_tx_dp(10)"
					( attribute "PN" "CW16"
						( Origin gPackager )
					)
					( objectStatus "U2D1.CW16" )
				)
				( pin "upi2_tx_dp(11)"
					( attribute "PN" "CV13"
						( Origin gPackager )
					)
					( objectStatus "U2D1.CV13" )
				)
				( pin "upi2_tx_dp(12)"
					( attribute "PN" "CR14"
						( Origin gPackager )
					)
					( objectStatus "U2D1.CR14" )
				)
				( pin "upi2_tx_dp(13)"
					( attribute "PN" "CK13"
						( Origin gPackager )
					)
					( objectStatus "U2D1.CK13" )
				)
				( pin "upi2_tx_dp(14)"
					( attribute "PN" "CH13"
						( Origin gPackager )
					)
					( objectStatus "U2D1.CH13" )
				)
				( pin "upi2_tx_dp(15)"
					( attribute "PN" "CG12"
						( Origin gPackager )
					)
					( objectStatus "U2D1.CG12" )
				)
				( pin "upi2_tx_dp(16)"
					( attribute "PN" "CF11"
						( Origin gPackager )
					)
					( objectStatus "U2D1.CF11" )
				)
				( pin "upi2_tx_dp(17)"
					( attribute "PN" "CD11"
						( Origin gPackager )
					)
					( objectStatus "U2D1.CD11" )
				)
				( pin "upi2_tx_dp(18)"
					( attribute "PN" "CB11"
						( Origin gPackager )
					)
					( objectStatus "U2D1.CB11" )
				)
				( pin "upi2_tx_dp(19)"
					( attribute "PN" "CA12"
						( Origin gPackager )
					)
					( objectStatus "U2D1.CA12" )
				)
			)
			( gate "@baseboard_fab2_lib.baseboard_fab2(sch_1):page70_i9"
				( attribute "CDS_LIB" "chpset_lib"
					( Origin gPackager )
				)
				( attribute "CDS_LOCATION" "U2D1"
					( Origin gPackager )
				)
				( attribute "CDS_SEC" "16"
					( Origin gPackager )
				)
				( attribute "LOCATION" "U2D1"
					( Origin gFrontEnd )
				)
				( attribute "MATERIAL" "IC"
					( Origin gFrontEnd )
				)
				( attribute "PACK_TYPE" "BGA1"
					( Origin gFrontEnd )
				)
				( attribute "PART_NUMBER" "TBD"
					( Origin gFrontEnd )
				)
				( attribute "PHYS_PAGE" "70"
					( Origin gFrontEnd )
				)
				( attribute "ROT" "0"
					( Origin gFrontEnd )
				)
				( attribute "SEC" "16"
					( Origin gFrontEnd )
				)
				( attribute "SEC_TYPE" "BGA1"
					( Origin gFrontEnd )
				)
				( attribute "VER" "16"
					( Origin gFrontEnd )
				)
				( attribute "XY" "(-5450,2550)"
					( Origin gFrontEnd )
				)
				( attribute "CHIPS_PART_NAME" "SKX_EXT_B"
					( Origin gPackager )
				)
				( attribute "CDS_PART_NAME" "SKX_EXT_B_BGA1-IC,TBD"
					( Origin gPackager )
				)
				( objectStatus "U2D1" )
				( pin "rsvd(92)"
					( attribute "PN" "CH23"
						( Origin gPackager )
					)
					( objectStatus "U2D1.CH23" )
				)
				( pin "rsvd(93)"
					( attribute "PN" "CH21"
						( Origin gPackager )
					)
					( objectStatus "U2D1.CH21" )
				)
				( pin "rsvd(94)"
					( attribute "PN" "CG82"
						( Origin gPackager )
					)
					( objectStatus "U2D1.CG82" )
				)
				( pin "rsvd(95)"
					( attribute "PN" "CG78"
						( Origin gPackager )
					)
					( objectStatus "U2D1.CG78" )
				)
				( pin "rsvd(96)"
					( attribute "PN" "CG26"
						( Origin gPackager )
					)
					( objectStatus "U2D1.CG26" )
				)
				( pin "rsvd(97)"
					( attribute "PN" "CG24"
						( Origin gPackager )
					)
					( objectStatus "U2D1.CG24" )
				)
				( pin "rsvd(98)"
					( attribute "PN" "CG20"
						( Origin gPackager )
					)
					( objectStatus "U2D1.CG20" )
				)
				( pin "rsvd(99)"
					( attribute "PN" "CG10"
						( Origin gPackager )
					)
					( objectStatus "U2D1.CG10" )
				)
				( pin "rsvd(100)"
					( attribute "PN" "CF81"
						( Origin gPackager )
					)
					( objectStatus "U2D1.CF81" )
				)
				( pin "rsvd(101)"
					( attribute "PN" "CF79"
						( Origin gPackager )
					)
					( objectStatus "U2D1.CF79" )
				)
				( pin "rsvd(102)"
					( attribute "PN" "CF23"
						( Origin gPackager )
					)
					( objectStatus "U2D1.CF23" )
				)
				( pin "rsvd(103)"
					( attribute "PN" "CF21"
						( Origin gPackager )
					)
					( objectStatus "U2D1.CF21" )
				)
				( pin "rsvd(104)"
					( attribute "PN" "CF19"
						( Origin gPackager )
					)
					( objectStatus "U2D1.CF19" )
				)
				( pin "rsvd(105)"
					( attribute "PN" "CE80"
						( Origin gPackager )
					)
					( objectStatus "U2D1.CE80" )
				)
				( pin "rsvd(106)"
					( attribute "PN" "CE78"
						( Origin gPackager )
					)
					( objectStatus "U2D1.CE78" )
				)
				( pin "rsvd(107)"
					( attribute "PN" "CE22"
						( Origin gPackager )
					)
					( objectStatus "U2D1.CE22" )
				)
				( pin "rsvd(108)"
					( attribute "PN" "CD25"
						( Origin gPackager )
					)
					( objectStatus "U2D1.CD25" )
				)
				( pin "rsvd(109)"
					( attribute "PN" "CD21"
						( Origin gPackager )
					)
					( objectStatus "U2D1.CD21" )
				)
				( pin "rsvd(110)"
					( attribute "PN" "CD19"
						( Origin gPackager )
					)
					( objectStatus "U2D1.CD19" )
				)
				( pin "rsvd(111)"
					( attribute "PN" "CC6"
						( Origin gPackager )
					)
					( objectStatus "U2D1.CC6" )
				)
				( pin "rsvd(112)"
					( attribute "PN" "CC20"
						( Origin gPackager )
					)
					( objectStatus "U2D1.CC20" )
				)
				( pin "rsvd(113)"
					( attribute "PN" "CB5"
						( Origin gPackager )
					)
					( objectStatus "U2D1.CB5" )
				)
				( pin "rsvd(114)"
					( attribute "PN" "CB25"
						( Origin gPackager )
					)
					( objectStatus "U2D1.CB25" )
				)
				( pin "rsvd(115)"
					( attribute "PN" "CB21"
						( Origin gPackager )
					)
					( objectStatus "U2D1.CB21" )
				)
				( pin "rsvd(116)"
					( attribute "PN" "CB19"
						( Origin gPackager )
					)
					( objectStatus "U2D1.CB19" )
				)
				( pin "rsvd(117)"
					( attribute "PN" "CA24"
						( Origin gPackager )
					)
					( objectStatus "U2D1.CA24" )
				)
				( pin "rsvd(118)"
					( attribute "PN" "CA22"
						( Origin gPackager )
					)
					( objectStatus "U2D1.CA22" )
				)
				( pin "rsvd(119)"
					( attribute "PN" "BY25"
						( Origin gPackager )
					)
					( objectStatus "U2D1.BY25" )
				)
				( pin "rsvd(120)"
					( attribute "PN" "BY19"
						( Origin gPackager )
					)
					( objectStatus "U2D1.BY19" )
				)
				( pin "rsvd(121)"
					( attribute "PN" "BW22"
						( Origin gPackager )
					)
					( objectStatus "U2D1.BW22" )
				)
				( pin "rsvd(122)"
					( attribute "PN" "BW20"
						( Origin gPackager )
					)
					( objectStatus "U2D1.BW20" )
				)
				( pin "rsvd(123)"
					( attribute "PN" "BW10"
						( Origin gPackager )
					)
					( objectStatus "U2D1.BW10" )
				)
				( pin "rsvd(124)"
					( attribute "PN" "BV23"
						( Origin gPackager )
					)
					( objectStatus "U2D1.BV23" )
				)
				( pin "rsvd(125)"
					( attribute "PN" "BV21"
						( Origin gPackager )
					)
					( objectStatus "U2D1.BV21" )
				)
				( pin "rsvd(126)"
					( attribute "PN" "BV19"
						( Origin gPackager )
					)
					( objectStatus "U2D1.BV19" )
				)
				( pin "rsvd(127)"
					( attribute "PN" "BU22"
						( Origin gPackager )
					)
					( objectStatus "U2D1.BU22" )
				)
				( pin "rsvd(128)"
					( attribute "PN" "BU20"
						( Origin gPackager )
					)
					( objectStatus "U2D1.BU20" )
				)
				( pin "rsvd(129)"
					( attribute "PN" "BU18"
						( Origin gPackager )
					)
					( objectStatus "U2D1.BU18" )
				)
				( pin "rsvd(130)"
					( attribute "PN" "BR24"
						( Origin gPackager )
					)
					( objectStatus "U2D1.BR24" )
				)
				( pin "rsvd(131)"
					( attribute "PN" "BR22"
						( Origin gPackager )
					)
					( objectStatus "U2D1.BR22" )
				)
				( pin "rsvd(132)"
					( attribute "PN" "BP21"
						( Origin gPackager )
					)
					( objectStatus "U2D1.BP21" )
				)
				( pin "rsvd(133)"
					( attribute "PN" "BP17"
						( Origin gPackager )
					)
					( objectStatus "U2D1.BP17" )
				)
				( pin "rsvd(134)"
					( attribute "PN" "BN18"
						( Origin gPackager )
					)
					( objectStatus "U2D1.BN18" )
				)
				( pin "rsvd(135)"
					( attribute "PN" "BM19"
						( Origin gPackager )
					)
					( objectStatus "U2D1.BM19" )
				)
				( pin "rsvd(136)"
					( attribute "PN" "BM17"
						( Origin gPackager )
					)
					( objectStatus "U2D1.BM17" )
				)
				( pin "rsvd(137)"
					( attribute "PN" "BL20"
						( Origin gPackager )
					)
					( objectStatus "U2D1.BL20" )
				)
				( pin "rsvd(138)"
					( attribute "PN" "BL18"
						( Origin gPackager )
					)
					( objectStatus "U2D1.BL18" )
				)
				( pin "rsvd(139)"
					( attribute "PN" "BK17"
						( Origin gPackager )
					)
					( objectStatus "U2D1.BK17" )
				)
				( pin "rsvd(140)"
					( attribute "PN" "BJ20"
						( Origin gPackager )
					)
					( objectStatus "U2D1.BJ20" )
				)
				( pin "rsvd(141)"
					( attribute "PN" "BJ18"
						( Origin gPackager )
					)
					( objectStatus "U2D1.BJ18" )
				)
				( pin "rsvd(142)"
					( attribute "PN" "BJ16"
						( Origin gPackager )
					)
					( objectStatus "U2D1.BJ16" )
				)
				( pin "rsvd(143)"
					( attribute "PN" "BH19"
						( Origin gPackager )
					)
					( objectStatus "U2D1.BH19" )
				)
				( pin "rsvd(144)"
					( attribute "PN" "BG20"
						( Origin gPackager )
					)
					( objectStatus "U2D1.BG20" )
				)
				( pin "rsvd(145)"
					( attribute "PN" "BG18"
						( Origin gPackager )
					)
					( objectStatus "U2D1.BG18" )
				)
				( pin "rsvd(146)"
					( attribute "PN" "BF21"
						( Origin gPackager )
					)
					( objectStatus "U2D1.BF21" )
				)
				( pin "rsvd(147)"
					( attribute "PN" "BE22"
						( Origin gPackager )
					)
					( objectStatus "U2D1.BE22" )
				)
				( pin "rsvd(148)"
					( attribute "PN" "BE20"
						( Origin gPackager )
					)
					( objectStatus "U2D1.BE20" )
				)
				( pin "rsvd(149)"
					( attribute "PN" "BE18"
						( Origin gPackager )
					)
					( objectStatus "U2D1.BE18" )
				)
				( pin "rsvd(150)"
					( attribute "PN" "BD69"
						( Origin gPackager )
					)
					( objectStatus "U2D1.BD69" )
				)
				( pin "rsvd(151)"
					( attribute "PN" "BD67"
						( Origin gPackager )
					)
					( objectStatus "U2D1.BD67" )
				)
				( pin "rsvd(152)"
					( attribute "PN" "BD65"
						( Origin gPackager )
					)
					( objectStatus "U2D1.BD65" )
				)
				( pin "rsvd(153)"
					( attribute "PN" "BD25"
						( Origin gPackager )
					)
					( objectStatus "U2D1.BD25" )
				)
				( pin "rsvd(154)"
					( attribute "PN" "BD19"
						( Origin gPackager )
					)
					( objectStatus "U2D1.BD19" )
				)
				( pin "rsvd(155)"
					( attribute "PN" "BD17"
						( Origin gPackager )
					)
					( objectStatus "U2D1.BD17" )
				)
				( pin "rsvd(156)"
					( attribute "PN" "BC68"
						( Origin gPackager )
					)
					( objectStatus "U2D1.BC68" )
				)
				( pin "rsvd(157)"
					( attribute "PN" "BC66"
						( Origin gPackager )
					)
					( objectStatus "U2D1.BC66" )
				)
				( pin "rsvd(158)"
					( attribute "PN" "BC64"
						( Origin gPackager )
					)
					( objectStatus "U2D1.BC64" )
				)
				( pin "rsvd(159)"
					( attribute "PN" "BC22"
						( Origin gPackager )
					)
					( objectStatus "U2D1.BC22" )
				)
				( pin "rsvd(160)"
					( attribute "PN" "BC20"
						( Origin gPackager )
					)
					( objectStatus "U2D1.BC20" )
				)
				( pin "rsvd(161)"
					( attribute "PN" "BC18"
						( Origin gPackager )
					)
					( objectStatus "U2D1.BC18" )
				)
				( pin "rsvd(162)"
					( attribute "PN" "BC14"
						( Origin gPackager )
					)
					( objectStatus "U2D1.BC14" )
				)
				( pin "rsvd(163)"
					( attribute "PN" "BB67"
						( Origin gPackager )
					)
					( objectStatus "U2D1.BB67" )
				)
				( pin "rsvd(164)"
					( attribute "PN" "BB65"
						( Origin gPackager )
					)
					( objectStatus "U2D1.BB65" )
				)
				( pin "rsvd(165)"
					( attribute "PN" "BB25"
						( Origin gPackager )
					)
					( objectStatus "U2D1.BB25" )
				)
				( pin "rsvd(166)"
					( attribute "PN" "BB21"
						( Origin gPackager )
					)
					( objectStatus "U2D1.BB21" )
				)
				( pin "rsvd(167)"
					( attribute "PN" "BB17"
						( Origin gPackager )
					)
					( objectStatus "U2D1.BB17" )
				)
				( pin "rsvd(168)"
					( attribute "PN" "BB15"
						( Origin gPackager )
					)
					( objectStatus "U2D1.BB15" )
				)
				( pin "rsvd(169)"
					( attribute "PN" "BB13"
						( Origin gPackager )
					)
					( objectStatus "U2D1.BB13" )
				)
				( pin "rsvd(170)"
					( attribute "PN" "BA82"
						( Origin gPackager )
					)
					( objectStatus "U2D1.BA82" )
				)
				( pin "rsvd(171)"
					( attribute "PN" "BA78"
						( Origin gPackager )
					)
					( objectStatus "U2D1.BA78" )
				)
				( pin "rsvd(172)"
					( attribute "CDS_NOT_ON_SYM" "TRUE"
						( Origin gFrontEnd )
					)
				)
				( pin "rsvd(173)"
					( attribute "CDS_NOT_ON_SYM" "TRUE"
						( Origin gFrontEnd )
					)
				)
				( pin "rsvd(174)"
					( attribute "CDS_NOT_ON_SYM" "TRUE"
						( Origin gFrontEnd )
					)
				)
				( pin "rsvd(175)"
					( attribute "CDS_NOT_ON_SYM" "TRUE"
						( Origin gFrontEnd )
					)
				)
				( pin "rsvd(176)"
					( attribute "CDS_NOT_ON_SYM" "TRUE"
						( Origin gFrontEnd )
					)
				)
				( pin "rsvd(177)"
					( attribute "CDS_NOT_ON_SYM" "TRUE"
						( Origin gFrontEnd )
					)
				)
				( pin "rsvd(178)"
					( attribute "CDS_NOT_ON_SYM" "TRUE"
						( Origin gFrontEnd )
					)
				)
				( pin "rsvd(179)"
					( attribute "CDS_NOT_ON_SYM" "TRUE"
						( Origin gFrontEnd )
					)
				)
				( pin "rsvd(180)"
					( attribute "CDS_NOT_ON_SYM" "TRUE"
						( Origin gFrontEnd )
					)
				)
				( pin "rsvd(181)"
					( attribute "CDS_NOT_ON_SYM" "TRUE"
						( Origin gFrontEnd )
					)
				)
				( pin "rsvd(182)"
					( attribute "CDS_NOT_ON_SYM" "TRUE"
						( Origin gFrontEnd )
					)
				)
				( pin "rsvd(183)"
					( attribute "CDS_NOT_ON_SYM" "TRUE"
						( Origin gFrontEnd )
					)
				)
				( pin "rsvd(184)"
					( attribute "CDS_NOT_ON_SYM" "TRUE"
						( Origin gFrontEnd )
					)
				)
				( pin "rsvd(185)"
					( attribute "CDS_NOT_ON_SYM" "TRUE"
						( Origin gFrontEnd )
					)
				)
				( pin "rsvd(186)"
					( attribute "CDS_NOT_ON_SYM" "TRUE"
						( Origin gFrontEnd )
					)
				)
				( pin "rsvd(187)"
					( attribute "CDS_NOT_ON_SYM" "TRUE"
						( Origin gFrontEnd )
					)
				)
				( pin "rsvd(188)"
					( attribute "CDS_NOT_ON_SYM" "TRUE"
						( Origin gFrontEnd )
					)
				)
				( pin "rsvd(189)"
					( attribute "CDS_NOT_ON_SYM" "TRUE"
						( Origin gFrontEnd )
					)
				)
				( pin "rsvd(190)"
					( attribute "CDS_NOT_ON_SYM" "TRUE"
						( Origin gFrontEnd )
					)
				)
				( pin "rsvd(191)"
					( attribute "CDS_NOT_ON_SYM" "TRUE"
						( Origin gFrontEnd )
					)
				)
				( pin "rsvd(192)"
					( attribute "CDS_NOT_ON_SYM" "TRUE"
						( Origin gFrontEnd )
					)
				)
				( pin "rsvd(193)"
					( attribute "CDS_NOT_ON_SYM" "TRUE"
						( Origin gFrontEnd )
					)
				)
				( pin "rsvd(194)"
					( attribute "CDS_NOT_ON_SYM" "TRUE"
						( Origin gFrontEnd )
					)
				)
				( pin "rsvd(195)"
					( attribute "CDS_NOT_ON_SYM" "TRUE"
						( Origin gFrontEnd )
					)
				)
				( pin "rsvd(196)"
					( attribute "CDS_NOT_ON_SYM" "TRUE"
						( Origin gFrontEnd )
					)
				)
				( pin "rsvd(197)"
					( attribute "CDS_NOT_ON_SYM" "TRUE"
						( Origin gFrontEnd )
					)
				)
				( pin "rsvd(198)"
					( attribute "CDS_NOT_ON_SYM" "TRUE"
						( Origin gFrontEnd )
					)
				)
				( pin "rsvd(199)"
					( attribute "CDS_NOT_ON_SYM" "TRUE"
						( Origin gFrontEnd )
					)
				)
				( pin "rsvd(200)"
					( attribute "CDS_NOT_ON_SYM" "TRUE"
						( Origin gFrontEnd )
					)
				)
				( pin "rsvd(201)"
					( attribute "CDS_NOT_ON_SYM" "TRUE"
						( Origin gFrontEnd )
					)
				)
				( pin "rsvd(202)"
					( attribute "CDS_NOT_ON_SYM" "TRUE"
						( Origin gFrontEnd )
					)
				)
				( pin "rsvd(203)"
					( attribute "CDS_NOT_ON_SYM" "TRUE"
						( Origin gFrontEnd )
					)
				)
				( pin "rsvd(204)"
					( attribute "CDS_NOT_ON_SYM" "TRUE"
						( Origin gFrontEnd )
					)
				)
				( pin "rsvd(205)"
					( attribute "CDS_NOT_ON_SYM" "TRUE"
						( Origin gFrontEnd )
					)
				)
				( pin "rsvd(206)"
					( attribute "CDS_NOT_ON_SYM" "TRUE"
						( Origin gFrontEnd )
					)
				)
				( pin "rsvd(207)"
					( attribute "CDS_NOT_ON_SYM" "TRUE"
						( Origin gFrontEnd )
					)
				)
				( pin "rsvd(208)"
					( attribute "CDS_NOT_ON_SYM" "TRUE"
						( Origin gFrontEnd )
					)
				)
				( pin "rsvd(209)"
					( attribute "CDS_NOT_ON_SYM" "TRUE"
						( Origin gFrontEnd )
					)
				)
				( pin "rsvd(210)"
					( attribute "CDS_NOT_ON_SYM" "TRUE"
						( Origin gFrontEnd )
					)
				)
				( pin "rsvd(211)"
					( attribute "CDS_NOT_ON_SYM" "TRUE"
						( Origin gFrontEnd )
					)
				)
				( pin "rsvd(212)"
					( attribute "CDS_NOT_ON_SYM" "TRUE"
						( Origin gFrontEnd )
					)
				)
				( pin "rsvd(213)"
					( attribute "CDS_NOT_ON_SYM" "TRUE"
						( Origin gFrontEnd )
					)
				)
				( pin "rsvd(214)"
					( attribute "CDS_NOT_ON_SYM" "TRUE"
						( Origin gFrontEnd )
					)
				)
				( pin "rsvd(215)"
					( attribute "CDS_NOT_ON_SYM" "TRUE"
						( Origin gFrontEnd )
					)
				)
				( pin "rsvd(216)"
					( attribute "CDS_NOT_ON_SYM" "TRUE"
						( Origin gFrontEnd )
					)
				)
				( pin "rsvd(217)"
					( attribute "CDS_NOT_ON_SYM" "TRUE"
						( Origin gFrontEnd )
					)
				)
				( pin "rsvd(218)"
					( attribute "CDS_NOT_ON_SYM" "TRUE"
						( Origin gFrontEnd )
					)
				)
				( pin "rsvd(219)"
					( attribute "CDS_NOT_ON_SYM" "TRUE"
						( Origin gFrontEnd )
					)
				)
				( pin "rsvd(220)"
					( attribute "CDS_NOT_ON_SYM" "TRUE"
						( Origin gFrontEnd )
					)
				)
				( pin "rsvd(221)"
					( attribute "CDS_NOT_ON_SYM" "TRUE"
						( Origin gFrontEnd )
					)
				)
				( pin "rsvd(222)"
					( attribute "CDS_NOT_ON_SYM" "TRUE"
						( Origin gFrontEnd )
					)
				)
				( pin "rsvd(223)"
					( attribute "CDS_NOT_ON_SYM" "TRUE"
						( Origin gFrontEnd )
					)
				)
				( pin "rsvd(224)"
					( attribute "CDS_NOT_ON_SYM" "TRUE"
						( Origin gFrontEnd )
					)
				)
				( pin "rsvd(225)"
					( attribute "CDS_NOT_ON_SYM" "TRUE"
						( Origin gFrontEnd )
					)
				)
				( pin "rsvd(226)"
					( attribute "CDS_NOT_ON_SYM" "TRUE"
						( Origin gFrontEnd )
					)
				)
				( pin "rsvd(227)"
					( attribute "CDS_NOT_ON_SYM" "TRUE"
						( Origin gFrontEnd )
					)
				)
				( pin "rsvd(228)"
					( attribute "CDS_NOT_ON_SYM" "TRUE"
						( Origin gFrontEnd )
					)
				)
				( pin "rsvd(229)"
					( attribute "CDS_NOT_ON_SYM" "TRUE"
						( Origin gFrontEnd )
					)
				)
				( pin "rsvd(230)"
					( attribute "CDS_NOT_ON_SYM" "TRUE"
						( Origin gFrontEnd )
					)
				)
				( pin "rsvd(231)"
					( attribute "CDS_NOT_ON_SYM" "TRUE"
						( Origin gFrontEnd )
					)
				)
				( pin "rsvd(232)"
					( attribute "CDS_NOT_ON_SYM" "TRUE"
						( Origin gFrontEnd )
					)
				)
				( pin "rsvd(233)"
					( attribute "CDS_NOT_ON_SYM" "TRUE"
						( Origin gFrontEnd )
					)
				)
				( pin "rsvd(234)"
					( attribute "CDS_NOT_ON_SYM" "TRUE"
						( Origin gFrontEnd )
					)
				)
				( pin "rsvd(235)"
					( attribute "CDS_NOT_ON_SYM" "TRUE"
						( Origin gFrontEnd )
					)
				)
				( pin "rsvd(236)"
					( attribute "CDS_NOT_ON_SYM" "TRUE"
						( Origin gFrontEnd )
					)
				)
				( pin "rsvd(237)"
					( attribute "CDS_NOT_ON_SYM" "TRUE"
						( Origin gFrontEnd )
					)
				)
				( pin "rsvd(238)"
					( attribute "CDS_NOT_ON_SYM" "TRUE"
						( Origin gFrontEnd )
					)
				)
				( pin "rsvd(239)"
					( attribute "CDS_NOT_ON_SYM" "TRUE"
						( Origin gFrontEnd )
					)
				)
				( pin "rsvd(240)"
					( attribute "CDS_NOT_ON_SYM" "TRUE"
						( Origin gFrontEnd )
					)
				)
				( pin "rsvd(241)"
					( attribute "CDS_NOT_ON_SYM" "TRUE"
						( Origin gFrontEnd )
					)
				)
				( pin "rsvd(242)"
					( attribute "CDS_NOT_ON_SYM" "TRUE"
						( Origin gFrontEnd )
					)
				)
				( pin "rsvd(243)"
					( attribute "CDS_NOT_ON_SYM" "TRUE"
						( Origin gFrontEnd )
					)
				)
				( pin "rsvd(244)"
					( attribute "CDS_NOT_ON_SYM" "TRUE"
						( Origin gFrontEnd )
					)
				)
				( pin "rsvd(245)"
					( attribute "CDS_NOT_ON_SYM" "TRUE"
						( Origin gFrontEnd )
					)
				)
				( pin "rsvd(246)"
					( attribute "CDS_NOT_ON_SYM" "TRUE"
						( Origin gFrontEnd )
					)
				)
				( pin "rsvd(247)"
					( attribute "CDS_NOT_ON_SYM" "TRUE"
						( Origin gFrontEnd )
					)
				)
				( pin "rsvd(248)"
					( attribute "CDS_NOT_ON_SYM" "TRUE"
						( Origin gFrontEnd )
					)
				)
				( pin "rsvd(249)"
					( attribute "CDS_NOT_ON_SYM" "TRUE"
						( Origin gFrontEnd )
					)
				)
				( pin "rsvd(250)"
					( attribute "CDS_NOT_ON_SYM" "TRUE"
						( Origin gFrontEnd )
					)
				)
				( pin "rsvd(251)"
					( attribute "CDS_NOT_ON_SYM" "TRUE"
						( Origin gFrontEnd )
					)
				)
				( pin "rsvd(252)"
					( attribute "CDS_NOT_ON_SYM" "TRUE"
						( Origin gFrontEnd )
					)
				)
				( pin "rsvd(253)"
					( attribute "CDS_NOT_ON_SYM" "TRUE"
						( Origin gFrontEnd )
					)
				)
				( pin "rsvd(254)"
					( attribute "CDS_NOT_ON_SYM" "TRUE"
						( Origin gFrontEnd )
					)
				)
				( pin "rsvd(255)"
					( attribute "PN" "AY83"
						( Origin gPackager )
					)
					( objectStatus "U2D1.AY83" )
				)
			)
			( gate "@baseboard_fab2_lib.baseboard_fab2(sch_1):page70_i10"
				( attribute "CDS_LIB" "chpset_lib"
					( Origin gPackager )
				)
				( attribute "CDS_LOCATION" "U2D1"
					( Origin gPackager )
				)
				( attribute "CDS_SEC" "17"
					( Origin gPackager )
				)
				( attribute "LOCATION" "U2D1"
					( Origin gFrontEnd )
				)
				( attribute "MATERIAL" "IC"
					( Origin gFrontEnd )
				)
				( attribute "PACK_TYPE" "BGA1"
					( Origin gFrontEnd )
				)
				( attribute "PART_NUMBER" "TBD"
					( Origin gFrontEnd )
				)
				( attribute "PHYS_PAGE" "70"
					( Origin gFrontEnd )
				)
				( attribute "ROT" "0"
					( Origin gFrontEnd )
				)
				( attribute "SEC" "17"
					( Origin gFrontEnd )
				)
				( attribute "SEC_TYPE" "BGA1"
					( Origin gFrontEnd )
				)
				( attribute "VER" "17"
					( Origin gFrontEnd )
				)
				( attribute "XY" "(-2925,2575)"
					( Origin gFrontEnd )
				)
				( attribute "CHIPS_PART_NAME" "SKX_EXT_B"
					( Origin gPackager )
				)
				( attribute "CDS_PART_NAME" "SKX_EXT_B_BGA1-IC,TBD"
					( Origin gPackager )
				)
				( objectStatus "U2D1" )
				( pin "rsvd(81)"
					( attribute "PN" "CL24"
						( Origin gPackager )
					)
					( objectStatus "U2D1.CL24" )
				)
				( pin "rsvd(82)"
					( attribute "PN" "CK77"
						( Origin gPackager )
					)
					( objectStatus "U2D1.CK77" )
				)
				( pin "rsvd(83)"
					( attribute "PN" "CK25"
						( Origin gPackager )
					)
					( objectStatus "U2D1.CK25" )
				)
				( pin "rsvd(84)"
					( attribute "PN" "CK23"
						( Origin gPackager )
					)
					( objectStatus "U2D1.CK23" )
				)
				( pin "rsvd(85)"
					( attribute "PN" "CK19"
						( Origin gPackager )
					)
					( objectStatus "U2D1.CK19" )
				)
				( pin "rsvd(86)"
					( attribute "PN" "CJ26"
						( Origin gPackager )
					)
					( objectStatus "U2D1.CJ26" )
				)
				( pin "rsvd(87)"
					( attribute "PN" "CJ24"
						( Origin gPackager )
					)
					( objectStatus "U2D1.CJ24" )
				)
				( pin "rsvd(88)"
					( attribute "PN" "CJ22"
						( Origin gPackager )
					)
					( objectStatus "U2D1.CJ22" )
				)
				( pin "rsvd(89)"
					( attribute "PN" "CJ20"
						( Origin gPackager )
					)
					( objectStatus "U2D1.CJ20" )
				)
				( pin "rsvd(90)"
					( attribute "PN" "CH77"
						( Origin gPackager )
					)
					( objectStatus "U2D1.CH77" )
				)
				( pin "rsvd(91)"
					( attribute "PN" "CH25"
						( Origin gPackager )
					)
					( objectStatus "U2D1.CH25" )
				)
				( pin "test_6"
					( attribute "PN" "AR16"
						( Origin gPackager )
					)
					( objectStatus "U2D1.AR16" )
				)
				( pin "test_7"
					( attribute "PN" "AU18"
						( Origin gPackager )
					)
					( objectStatus "U2D1.AU18" )
				)
				( pin "test_8"
					( attribute "PN" "AW16"
						( Origin gPackager )
					)
					( objectStatus "U2D1.AW16" )
				)
				( pin "test_9"
					( attribute "PN" "AW20"
						( Origin gPackager )
					)
					( objectStatus "U2D1.AW20" )
				)
				( pin "test_10"
					( attribute "PN" "AW22"
						( Origin gPackager )
					)
					( objectStatus "U2D1.AW22" )
				)
			)
			( gate "@baseboard_fab2_lib.baseboard_fab2(sch_1):page71_i43"
				( attribute "BOM_COST" "PROC_SOCKET"
					( Origin gFrontEnd )
				)
				( attribute "CDS_LIB" "mstr_discrete"
					( Origin gPackager )
				)
				( attribute "CDS_LOCATION" "R3D27"
					( Origin gPackager )
				)
				( attribute "CDS_SEC" "1"
					( Origin gPackager )
				)
				( attribute "LOCATION" "R3D27"
					( Origin gFrontEnd )
				)
				( attribute "MATERIAL" "CHIP"
					( Origin gFrontEnd )
				)
				( attribute "PACK_TYPE" "0402"
					( Origin gFrontEnd )
				)
				( attribute "PART_NUMBER" "G85996-031"
					( Origin gFrontEnd )
				)
				( attribute "PHYS_PAGE" "71"
					( Origin gFrontEnd )
				)
				( attribute "ROOM" "CPU1"
					( Origin gFrontEnd )
				)
				( attribute "ROT" "0"
					( Origin gFrontEnd )
				)
				( attribute "SEC" "1"
					( Origin gFrontEnd )
				)
				( attribute "SEC_TYPE" "0402"
					( Origin gFrontEnd )
				)
				( attribute "TOLERANCE" "0.1%"
					( Origin gFrontEnd )
				)
				( attribute "VALUE" "249"
					( Origin gFrontEnd )
				)
				( attribute "VER" "2"
					( Origin gFrontEnd )
				)
				( attribute "WATTAGE" "1/16W"
					( Origin gFrontEnd )
				)
				( attribute "XY" "(-500,750)"
					( Origin gFrontEnd )
				)
				( attribute "CHIPS_PART_NAME" "RES"
					( Origin gPackager )
				)
				( attribute "CDS_PART_NAME" "RES_0402-249,0.1%,1/16W,CHIP,GA"
					( Origin gPackager )
				)
				( objectStatus "R3D27" )
				( pin "a"
					( attribute "PN" "1"
						( Origin gPackager )
					)
					( objectStatus "R3D27.1" )
				)
				( pin "b"
					( attribute "PN" "2"
						( Origin gPackager )
					)
					( objectStatus "R3D27.2" )
				)
			)
			( gate "@baseboard_fab2_lib.baseboard_fab2(sch_1):page71_i49"
				( attribute "BOM_COST" "PROC_SOCKET"
					( Origin gFrontEnd )
				)
				( attribute "CDS_LIB" "mstr_discrete"
					( Origin gPackager )
				)
				( attribute "CDS_LOCATION" "RT8P1"
					( Origin gPackager )
				)
				( attribute "CDS_SEC" "1"
					( Origin gPackager )
				)
				( attribute "LOCATION" "RT8P1"
					( Origin gFrontEnd )
				)
				( attribute "MATERIAL" "CHIP"
					( Origin gFrontEnd )
				)
				( attribute "PACK_TYPE" "0603"
					( Origin gFrontEnd )
				)
				( attribute "PART_NUMBER" "G22026-050"
					( Origin gFrontEnd )
				)
				( attribute "PHYS_PAGE" "71"
					( Origin gFrontEnd )
				)
				( attribute "ROOM" "CPU1"
					( Origin gFrontEnd )
				)
				( attribute "ROT" "0"
					( Origin gFrontEnd )
				)
				( attribute "SEC" "1"
					( Origin gFrontEnd )
				)
				( attribute "SEC_TYPE" "0603"
					( Origin gFrontEnd )
				)
				( attribute "TOLERANCE" "1%"
					( Origin gFrontEnd )
				)
				( attribute "VALUE" "100.0K"
					( Origin gFrontEnd )
				)
				( attribute "VER" "2"
					( Origin gFrontEnd )
				)
				( attribute "WATTAGE" "1/10W"
					( Origin gFrontEnd )
				)
				( attribute "XY" "(-1100,1400)"
					( Origin gFrontEnd )
				)
				( attribute "CHIPS_PART_NAME" "RES"
					( Origin gPackager )
				)
				( attribute "CDS_PART_NAME" "RES_0603-100.0K,1%,1/10W,CHIP,A"
					( Origin gPackager )
				)
				( objectStatus "RT8P1" )
				( pin "a"
					( attribute "PN" "1"
						( Origin gPackager )
					)
					( objectStatus "RT8P1.1" )
				)
				( pin "b"
					( attribute "PN" "2"
						( Origin gPackager )
					)
					( objectStatus "RT8P1.2" )
				)
			)
			( gate "@baseboard_fab2_lib.baseboard_fab2(sch_1):page71_i50"
				( attribute "CDS_LIB" "chpset_lib"
					( Origin gPackager )
				)
				( attribute "CDS_LOCATION" "U2D1"
					( Origin gPackager )
				)
				( attribute "CDS_SEC" "18"
					( Origin gPackager )
				)
				( attribute "LOCATION" "U2D1"
					( Origin gFrontEnd )
				)
				( attribute "MATERIAL" "IC"
					( Origin gFrontEnd )
				)
				( attribute "PACK_TYPE" "BGA1"
					( Origin gFrontEnd )
				)
				( attribute "PART_NUMBER" "TBD"
					( Origin gFrontEnd )
				)
				( attribute "PHYS_PAGE" "71"
					( Origin gFrontEnd )
				)
				( attribute "ROT" "0"
					( Origin gFrontEnd )
				)
				( attribute "SEC" "18"
					( Origin gFrontEnd )
				)
				( attribute "SEC_TYPE" "BGA1"
					( Origin gFrontEnd )
				)
				( attribute "VER" "18"
					( Origin gFrontEnd )
				)
				( attribute "XY" "(-6375,2525)"
					( Origin gFrontEnd )
				)
				( attribute "CHIPS_PART_NAME" "SKX_EXT_B"
					( Origin gPackager )
				)
				( attribute "CDS_PART_NAME" "SKX_EXT_B_BGA1-IC,TBD"
					( Origin gPackager )
				)
				( objectStatus "U2D1" )
				( pin "vccin(130)"
					( attribute "PN" "BN78"
						( Origin gPackager )
					)
					( objectStatus "U2D1.BN78" )
				)
				( pin "vccin(131)"
					( attribute "PN" "BN76"
						( Origin gPackager )
					)
					( objectStatus "U2D1.BN76" )
				)
				( pin "vccin(132)"
					( attribute "PN" "BN74"
						( Origin gPackager )
					)
					( objectStatus "U2D1.BN74" )
				)
				( pin "vccin(133)"
					( attribute "PN" "BN72"
						( Origin gPackager )
					)
					( objectStatus "U2D1.BN72" )
				)
				( pin "vccin(134)"
					( attribute "PN" "BN70"
						( Origin gPackager )
					)
					( objectStatus "U2D1.BN70" )
				)
				( pin "vccin(135)"
					( attribute "PN" "BN68"
						( Origin gPackager )
					)
					( objectStatus "U2D1.BN68" )
				)
				( pin "vccin(136)"
					( attribute "PN" "BN66"
						( Origin gPackager )
					)
					( objectStatus "U2D1.BN66" )
				)
				( pin "vccin(137)"
					( attribute "PN" "BN64"
						( Origin gPackager )
					)
					( objectStatus "U2D1.BN64" )
				)
				( pin "vccin(138)"
					( attribute "PN" "BN62"
						( Origin gPackager )
					)
					( objectStatus "U2D1.BN62" )
				)
				( pin "vccin(139)"
					( attribute "PN" "BN60"
						( Origin gPackager )
					)
					( objectStatus "U2D1.BN60" )
				)
				( pin "vccin(140)"
					( attribute "PN" "BM83"
						( Origin gPackager )
					)
					( objectStatus "U2D1.BM83" )
				)
				( pin "vccin(141)"
					( attribute "PN" "BM81"
						( Origin gPackager )
					)
					( objectStatus "U2D1.BM81" )
				)
				( pin "vccin(142)"
					( attribute "PN" "BM79"
						( Origin gPackager )
					)
					( objectStatus "U2D1.BM79" )
				)
				( pin "vccin(143)"
					( attribute "PN" "BM77"
						( Origin gPackager )
					)
					( objectStatus "U2D1.BM77" )
				)
				( pin "vccin(144)"
					( attribute "PN" "BM75"
						( Origin gPackager )
					)
					( objectStatus "U2D1.BM75" )
				)
				( pin "vccin(145)"
					( attribute "PN" "BM73"
						( Origin gPackager )
					)
					( objectStatus "U2D1.BM73" )
				)
				( pin "vccin(146)"
					( attribute "PN" "BM71"
						( Origin gPackager )
					)
					( objectStatus "U2D1.BM71" )
				)
				( pin "vccin(147)"
					( attribute "PN" "BM69"
						( Origin gPackager )
					)
					( objectStatus "U2D1.BM69" )
				)
				( pin "vccin(148)"
					( attribute "PN" "BM67"
						( Origin gPackager )
					)
					( objectStatus "U2D1.BM67" )
				)
				( pin "vccin(149)"
					( attribute "PN" "BM65"
						( Origin gPackager )
					)
					( objectStatus "U2D1.BM65" )
				)
				( pin "vccin(150)"
					( attribute "PN" "BM63"
						( Origin gPackager )
					)
					( objectStatus "U2D1.BM63" )
				)
				( pin "vccin(151)"
					( attribute "PN" "BM61"
						( Origin gPackager )
					)
					( objectStatus "U2D1.BM61" )
				)
				( pin "vccin(152)"
					( attribute "PN" "BL84"
						( Origin gPackager )
					)
					( objectStatus "U2D1.BL84" )
				)
				( pin "vccin(153)"
					( attribute "PN" "BL62"
						( Origin gPackager )
					)
					( objectStatus "U2D1.BL62" )
				)
				( pin "vccin(154)"
					( attribute "PN" "BL60"
						( Origin gPackager )
					)
					( objectStatus "U2D1.BL60" )
				)
				( pin "vccin(155)"
					( attribute "PN" "BK83"
						( Origin gPackager )
					)
					( objectStatus "U2D1.BK83" )
				)
				( pin "vccin(156)"
					( attribute "PN" "BK81"
						( Origin gPackager )
					)
					( objectStatus "U2D1.BK81" )
				)
				( pin "vccin(157)"
					( attribute "PN" "BK79"
						( Origin gPackager )
					)
					( objectStatus "U2D1.BK79" )
				)
				( pin "vccin(158)"
					( attribute "PN" "BK77"
						( Origin gPackager )
					)
					( objectStatus "U2D1.BK77" )
				)
				( pin "vccin(159)"
					( attribute "PN" "BK75"
						( Origin gPackager )
					)
					( objectStatus "U2D1.BK75" )
				)
				( pin "vccin(160)"
					( attribute "PN" "BK73"
						( Origin gPackager )
					)
					( objectStatus "U2D1.BK73" )
				)
				( pin "vccin(161)"
					( attribute "PN" "BK71"
						( Origin gPackager )
					)
					( objectStatus "U2D1.BK71" )
				)
				( pin "vccin(162)"
					( attribute "PN" "BK69"
						( Origin gPackager )
					)
					( objectStatus "U2D1.BK69" )
				)
				( pin "vccin(163)"
					( attribute "PN" "BK67"
						( Origin gPackager )
					)
					( objectStatus "U2D1.BK67" )
				)
				( pin "vccin(164)"
					( attribute "PN" "BK65"
						( Origin gPackager )
					)
					( objectStatus "U2D1.BK65" )
				)
				( pin "vccin(165)"
					( attribute "PN" "BK63"
						( Origin gPackager )
					)
					( objectStatus "U2D1.BK63" )
				)
				( pin "vccin(166)"
					( attribute "PN" "BK61"
						( Origin gPackager )
					)
					( objectStatus "U2D1.BK61" )
				)
				( pin "vccin(167)"
					( attribute "PN" "BJ84"
						( Origin gPackager )
					)
					( objectStatus "U2D1.BJ84" )
				)
				( pin "vccin(168)"
					( attribute "PN" "BJ82"
						( Origin gPackager )
					)
					( objectStatus "U2D1.BJ82" )
				)
				( pin "vccin(169)"
					( attribute "PN" "BJ80"
						( Origin gPackager )
					)
					( objectStatus "U2D1.BJ80" )
				)
				( pin "vccin(170)"
					( attribute "PN" "BJ78"
						( Origin gPackager )
					)
					( objectStatus "U2D1.BJ78" )
				)
				( pin "vccin(171)"
					( attribute "PN" "BJ76"
						( Origin gPackager )
					)
					( objectStatus "U2D1.BJ76" )
				)
				( pin "vccin(172)"
					( attribute "PN" "BJ74"
						( Origin gPackager )
					)
					( objectStatus "U2D1.BJ74" )
				)
				( pin "vccin(173)"
					( attribute "PN" "BJ72"
						( Origin gPackager )
					)
					( objectStatus "U2D1.BJ72" )
				)
				( pin "vccin(174)"
					( attribute "PN" "BJ70"
						( Origin gPackager )
					)
					( objectStatus "U2D1.BJ70" )
				)
				( pin "vccin(175)"
					( attribute "PN" "BJ68"
						( Origin gPackager )
					)
					( objectStatus "U2D1.BJ68" )
				)
				( pin "vccin(176)"
					( attribute "PN" "BJ66"
						( Origin gPackager )
					)
					( objectStatus "U2D1.BJ66" )
				)
				( pin "vccin(177)"
					( attribute "PN" "BJ64"
						( Origin gPackager )
					)
					( objectStatus "U2D1.BJ64" )
				)
				( pin "vccin(178)"
					( attribute "PN" "BJ62"
						( Origin gPackager )
					)
					( objectStatus "U2D1.BJ62" )
				)
				( pin "vccin(179)"
					( attribute "PN" "BJ60"
						( Origin gPackager )
					)
					( objectStatus "U2D1.BJ60" )
				)
				( pin "vccin(180)"
					( attribute "PN" "BH83"
						( Origin gPackager )
					)
					( objectStatus "U2D1.BH83" )
				)
				( pin "vccin(181)"
					( attribute "PN" "BH81"
						( Origin gPackager )
					)
					( objectStatus "U2D1.BH81" )
				)
				( pin "vccin(182)"
					( attribute "PN" "BH79"
						( Origin gPackager )
					)
					( objectStatus "U2D1.BH79" )
				)
				( pin "vccin(183)"
					( attribute "PN" "BH77"
						( Origin gPackager )
					)
					( objectStatus "U2D1.BH77" )
				)
				( pin "vccin(184)"
					( attribute "PN" "BH75"
						( Origin gPackager )
					)
					( objectStatus "U2D1.BH75" )
				)
				( pin "vccin(185)"
					( attribute "PN" "BH73"
						( Origin gPackager )
					)
					( objectStatus "U2D1.BH73" )
				)
				( pin "vccin(186)"
					( attribute "PN" "BH71"
						( Origin gPackager )
					)
					( objectStatus "U2D1.BH71" )
				)
				( pin "vccin(187)"
					( attribute "PN" "BH69"
						( Origin gPackager )
					)
					( objectStatus "U2D1.BH69" )
				)
				( pin "vccin(188)"
					( attribute "PN" "BH67"
						( Origin gPackager )
					)
					( objectStatus "U2D1.BH67" )
				)
				( pin "vccin(189)"
					( attribute "PN" "BH65"
						( Origin gPackager )
					)
					( objectStatus "U2D1.BH65" )
				)
				( pin "vccin(190)"
					( attribute "PN" "BH63"
						( Origin gPackager )
					)
					( objectStatus "U2D1.BH63" )
				)
				( pin "vccin(191)"
					( attribute "PN" "BH61"
						( Origin gPackager )
					)
					( objectStatus "U2D1.BH61" )
				)
				( pin "vccin(192)"
					( attribute "PN" "BG84"
						( Origin gPackager )
					)
					( objectStatus "U2D1.BG84" )
				)
				( pin "vccin(193)"
					( attribute "PN" "BG70"
						( Origin gPackager )
					)
					( objectStatus "U2D1.BG70" )
				)
				( pin "vccin(194)"
					( attribute "PN" "BG68"
						( Origin gPackager )
					)
					( objectStatus "U2D1.BG68" )
				)
				( pin "vccin(195)"
					( attribute "PN" "BG66"
						( Origin gPackager )
					)
					( objectStatus "U2D1.BG66" )
				)
				( pin "vccin(196)"
					( attribute "PN" "BG64"
						( Origin gPackager )
					)
					( objectStatus "U2D1.BG64" )
				)
				( pin "vccin(197)"
					( attribute "PN" "BG62"
						( Origin gPackager )
					)
					( objectStatus "U2D1.BG62" )
				)
				( pin "vccin(198)"
					( attribute "PN" "BG60"
						( Origin gPackager )
					)
					( objectStatus "U2D1.BG60" )
				)
				( pin "vccin(199)"
					( attribute "PN" "BF85"
						( Origin gPackager )
					)
					( objectStatus "U2D1.BF85" )
				)
				( pin "vccin(200)"
					( attribute "PN" "BF83"
						( Origin gPackager )
					)
					( objectStatus "U2D1.BF83" )
				)
				( pin "vccin(201)"
					( attribute "PN" "BF81"
						( Origin gPackager )
					)
					( objectStatus "U2D1.BF81" )
				)
				( pin "vccin(202)"
					( attribute "PN" "BF79"
						( Origin gPackager )
					)
					( objectStatus "U2D1.BF79" )
				)
				( pin "vccin(203)"
					( attribute "PN" "BF77"
						( Origin gPackager )
					)
					( objectStatus "U2D1.BF77" )
				)
				( pin "vccin(204)"
					( attribute "PN" "BF75"
						( Origin gPackager )
					)
					( objectStatus "U2D1.BF75" )
				)
				( pin "vccin(205)"
					( attribute "PN" "BF73"
						( Origin gPackager )
					)
					( objectStatus "U2D1.BF73" )
				)
				( pin "vccin(206)"
					( attribute "PN" "BF61"
						( Origin gPackager )
					)
					( objectStatus "U2D1.BF61" )
				)
				( pin "vccin(207)"
					( attribute "PN" "BE84"
						( Origin gPackager )
					)
					( objectStatus "U2D1.BE84" )
				)
				( pin "vccin(208)"
					( attribute "PN" "BE82"
						( Origin gPackager )
					)
					( objectStatus "U2D1.BE82" )
				)
				( pin "vccin(209)"
					( attribute "PN" "BE80"
						( Origin gPackager )
					)
					( objectStatus "U2D1.BE80" )
				)
				( pin "vccin(210)"
					( attribute "PN" "BE78"
						( Origin gPackager )
					)
					( objectStatus "U2D1.BE78" )
				)
				( pin "vccin(211)"
					( attribute "PN" "BE76"
						( Origin gPackager )
					)
					( objectStatus "U2D1.BE76" )
				)
				( pin "vccin(212)"
					( attribute "PN" "BE74"
						( Origin gPackager )
					)
					( objectStatus "U2D1.BE74" )
				)
				( pin "vccin(213)"
					( attribute "PN" "BE72"
						( Origin gPackager )
					)
					( objectStatus "U2D1.BE72" )
				)
				( pin "vccin(214)"
					( attribute "PN" "BE62"
						( Origin gPackager )
					)
					( objectStatus "U2D1.BE62" )
				)
				( pin "vccin(215)"
					( attribute "PN" "BE60"
						( Origin gPackager )
					)
					( objectStatus "U2D1.BE60" )
				)
				( pin "vccin(216)"
					( attribute "PN" "BD85"
						( Origin gPackager )
					)
					( objectStatus "U2D1.BD85" )
				)
				( pin "vccin(217)"
					( attribute "PN" "BD83"
						( Origin gPackager )
					)
					( objectStatus "U2D1.BD83" )
				)
				( pin "vccin(218)"
					( attribute "PN" "BD81"
						( Origin gPackager )
					)
					( objectStatus "U2D1.BD81" )
				)
				( pin "vccin(219)"
					( attribute "PN" "BD79"
						( Origin gPackager )
					)
					( objectStatus "U2D1.BD79" )
				)
				( pin "vccin(220)"
					( attribute "PN" "BD77"
						( Origin gPackager )
					)
					( objectStatus "U2D1.BD77" )
				)
				( pin "vccin(221)"
					( attribute "PN" "BD75"
						( Origin gPackager )
					)
					( objectStatus "U2D1.BD75" )
				)
				( pin "vccin(222)"
					( attribute "PN" "BD73"
						( Origin gPackager )
					)
					( objectStatus "U2D1.BD73" )
				)
				( pin "vccin(223)"
					( attribute "PN" "BD61"
						( Origin gPackager )
					)
					( objectStatus "U2D1.BD61" )
				)
				( pin "vccin(224)"
					( attribute "PN" "BC84"
						( Origin gPackager )
					)
					( objectStatus "U2D1.BC84" )
				)
				( pin "vccin(225)"
					( attribute "PN" "BC62"
						( Origin gPackager )
					)
					( objectStatus "U2D1.BC62" )
				)
				( pin "vccin(226)"
					( attribute "PN" "BC60"
						( Origin gPackager )
					)
					( objectStatus "U2D1.BC60" )
				)
				( pin "vccin(227)"
					( attribute "PN" "BB85"
						( Origin gPackager )
					)
					( objectStatus "U2D1.BB85" )
				)
				( pin "vccin(228)"
					( attribute "PN" "BB61"
						( Origin gPackager )
					)
					( objectStatus "U2D1.BB61" )
				)
				( pin "vccin(229)"
					( attribute "PN" "BA60"
						( Origin gPackager )
					)
					( objectStatus "U2D1.BA60" )
				)
				( pin "vccin(230)"
					( attribute "PN" "AY61"
						( Origin gPackager )
					)
					( objectStatus "U2D1.AY61" )
				)
				( pin "vccin(231)"
					( attribute "PN" "AW60"
						( Origin gPackager )
					)
					( objectStatus "U2D1.AW60" )
				)
				( pin "vccin(232)"
					( attribute "PN" "AV61"
						( Origin gPackager )
					)
					( objectStatus "U2D1.AV61" )
				)
				( pin "vccin(233)"
					( attribute "PN" "AV59"
						( Origin gPackager )
					)
					( objectStatus "U2D1.AV59" )
				)
				( pin "vccin(234)"
					( attribute "PN" "AU60"
						( Origin gPackager )
					)
					( objectStatus "U2D1.AU60" )
				)
				( pin "vccin(235)"
					( attribute "PN" "AU58"
						( Origin gPackager )
					)
					( objectStatus "U2D1.AU58" )
				)
				( pin "vccin(236)"
					( attribute "PN" "AT59"
						( Origin gPackager )
					)
					( objectStatus "U2D1.AT59" )
				)
				( pin "vccin(237)"
					( attribute "PN" "AT57"
						( Origin gPackager )
					)
					( objectStatus "U2D1.AT57" )
				)
				( pin "vccin(238)"
					( attribute "PN" "AR58"
						( Origin gPackager )
					)
					( objectStatus "U2D1.AR58" )
				)
				( pin "vccin(239)"
					( attribute "PN" "AR56"
						( Origin gPackager )
					)
					( objectStatus "U2D1.AR56" )
				)
				( pin "vccin(240)"
					( attribute "PN" "AP57"
						( Origin gPackager )
					)
					( objectStatus "U2D1.AP57" )
				)
				( pin "vccin(241)"
					( attribute "PN" "AP55"
						( Origin gPackager )
					)
					( objectStatus "U2D1.AP55" )
				)
				( pin "vccin(242)"
					( attribute "PN" "AN56"
						( Origin gPackager )
					)
					( objectStatus "U2D1.AN56" )
				)
				( pin "vccin(243)"
					( attribute "PN" "AN54"
						( Origin gPackager )
					)
					( objectStatus "U2D1.AN54" )
				)
				( pin "vccin(244)"
					( attribute "PN" "AN32"
						( Origin gPackager )
					)
					( objectStatus "U2D1.AN32" )
				)
				( pin "vccin(245)"
					( attribute "PN" "AM55"
						( Origin gPackager )
					)
					( objectStatus "U2D1.AM55" )
				)
				( pin "vccin(246)"
					( attribute "PN" "AM53"
						( Origin gPackager )
					)
					( objectStatus "U2D1.AM53" )
				)
				( pin "vccin(247)"
					( attribute "PN" "AM33"
						( Origin gPackager )
					)
					( objectStatus "U2D1.AM33" )
				)
				( pin "vccin(248)"
					( attribute "PN" "AL54"
						( Origin gPackager )
					)
					( objectStatus "U2D1.AL54" )
				)
				( pin "vccin(249)"
					( attribute "PN" "AL52"
						( Origin gPackager )
					)
					( objectStatus "U2D1.AL52" )
				)
				( pin "vccin(250)"
					( attribute "PN" "AL50"
						( Origin gPackager )
					)
					( objectStatus "U2D1.AL50" )
				)
				( pin "vccin(251)"
					( attribute "PN" "AL48"
						( Origin gPackager )
					)
					( objectStatus "U2D1.AL48" )
				)
				( pin "vccin(252)"
					( attribute "PN" "AL46"
						( Origin gPackager )
					)
					( objectStatus "U2D1.AL46" )
				)
				( pin "vccin(253)"
					( attribute "PN" "AL34"
						( Origin gPackager )
					)
					( objectStatus "U2D1.AL34" )
				)
				( pin "vccin(254)"
					( attribute "PN" "AK53"
						( Origin gPackager )
					)
					( objectStatus "U2D1.AK53" )
				)
				( pin "vccin(255)"
					( attribute "PN" "AK51"
						( Origin gPackager )
					)
					( objectStatus "U2D1.AK51" )
				)
				( pin "vccin(256)"
					( attribute "PN" "AK49"
						( Origin gPackager )
					)
					( objectStatus "U2D1.AK49" )
				)
				( pin "vccin(257)"
					( attribute "PN" "AK47"
						( Origin gPackager )
					)
					( objectStatus "U2D1.AK47" )
				)
				( pin "vccin(258)"
					( attribute "PN" "AK45"
						( Origin gPackager )
					)
					( objectStatus "U2D1.AK45" )
				)
				( pin "vccin(259)"
					( attribute "PN" "AK35"
						( Origin gPackager )
					)
					( objectStatus "U2D1.AK35" )
				)
				( pin "vccin(260)"
					( attribute "PN" "AJ36"
						( Origin gPackager )
					)
					( objectStatus "U2D1.AJ36" )
				)
				( pin "vccin(261)"
					( attribute "PN" "AH41"
						( Origin gPackager )
					)
					( objectStatus "U2D1.AH41" )
				)
				( pin "vccin(262)"
					( attribute "PN" "AH39"
						( Origin gPackager )
					)
					( objectStatus "U2D1.AH39" )
				)
				( pin "vccin(263)"
					( attribute "PN" "AH37"
						( Origin gPackager )
					)
					( objectStatus "U2D1.AH37" )
				)
				( pin "vccin(264)"
					( attribute "PN" "AG42"
						( Origin gPackager )
					)
					( objectStatus "U2D1.AG42" )
				)
				( pin "vccin(265)"
					( attribute "PN" "AG40"
						( Origin gPackager )
					)
					( objectStatus "U2D1.AG40" )
				)
				( pin "vccin(266)"
					( attribute "PN" "AG38"
						( Origin gPackager )
					)
					( objectStatus "U2D1.AG38" )
				)
				( pin "vccin(267)"
					( attribute "PN" "AF43"
						( Origin gPackager )
					)
					( objectStatus "U2D1.AF43" )
				)
			)
			( gate "@baseboard_fab2_lib.baseboard_fab2(sch_1):page71_i51"
				( attribute "CDS_LIB" "chpset_lib"
					( Origin gPackager )
				)
				( attribute "CDS_LOCATION" "U2D1"
					( Origin gPackager )
				)
				( attribute "CDS_SEC" "19"
					( Origin gPackager )
				)
				( attribute "LOCATION" "U2D1"
					( Origin gFrontEnd )
				)
				( attribute "MATERIAL" "IC"
					( Origin gFrontEnd )
				)
				( attribute "PACK_TYPE" "BGA1"
					( Origin gFrontEnd )
				)
				( attribute "PART_NUMBER" "TBD"
					( Origin gFrontEnd )
				)
				( attribute "PHYS_PAGE" "71"
					( Origin gFrontEnd )
				)
				( attribute "ROT" "0"
					( Origin gFrontEnd )
				)
				( attribute "SEC" "19"
					( Origin gFrontEnd )
				)
				( attribute "SEC_TYPE" "BGA1"
					( Origin gFrontEnd )
				)
				( attribute "VER" "19"
					( Origin gFrontEnd )
				)
				( attribute "XY" "(-2675,2525)"
					( Origin gFrontEnd )
				)
				( attribute "CHIPS_PART_NAME" "SKX_EXT_B"
					( Origin gPackager )
				)
				( attribute "CDS_PART_NAME" "SKX_EXT_B_BGA1-IC,TBD"
					( Origin gPackager )
				)
				( objectStatus "U2D1" )
				( pin "vccin(0)"
					( attribute "PN" "CY49"
						( Origin gPackager )
					)
					( objectStatus "U2D1.CY49" )
				)
				( pin "vccin(1)"
					( attribute "PN" "CY47"
						( Origin gPackager )
					)
					( objectStatus "U2D1.CY47" )
				)
				( pin "vccin(2)"
					( attribute "PN" "CW50"
						( Origin gPackager )
					)
					( objectStatus "U2D1.CW50" )
				)
				( pin "vccin(3)"
					( attribute "PN" "CW48"
						( Origin gPackager )
					)
					( objectStatus "U2D1.CW48" )
				)
				( pin "vccin(4)"
					( attribute "PN" "CW46"
						( Origin gPackager )
					)
					( objectStatus "U2D1.CW46" )
				)
				( pin "vccin(5)"
					( attribute "PN" "CV51"
						( Origin gPackager )
					)
					( objectStatus "U2D1.CV51" )
				)
				( pin "vccin(6)"
					( attribute "PN" "CU54"
						( Origin gPackager )
					)
					( objectStatus "U2D1.CU54" )
				)
				( pin "vccin(7)"
					( attribute "PN" "CU52"
						( Origin gPackager )
					)
					( objectStatus "U2D1.CU52" )
				)
				( pin "vccin(8)"
					( attribute "PN" "CU42"
						( Origin gPackager )
					)
					( objectStatus "U2D1.CU42" )
				)
				( pin "vccin(9)"
					( attribute "PN" "CU40"
						( Origin gPackager )
					)
					( objectStatus "U2D1.CU40" )
				)
				( pin "vccin(10)"
					( attribute "PN" "CU38"
						( Origin gPackager )
					)
					( objectStatus "U2D1.CU38" )
				)
				( pin "vccin(11)"
					( attribute "PN" "CT55"
						( Origin gPackager )
					)
					( objectStatus "U2D1.CT55" )
				)
				( pin "vccin(12)"
					( attribute "PN" "CT53"
						( Origin gPackager )
					)
					( objectStatus "U2D1.CT53" )
				)
				( pin "vccin(13)"
					( attribute "PN" "CT41"
						( Origin gPackager )
					)
					( objectStatus "U2D1.CT41" )
				)
				( pin "vccin(14)"
					( attribute "PN" "CT39"
						( Origin gPackager )
					)
					( objectStatus "U2D1.CT39" )
				)
				( pin "vccin(15)"
					( attribute "PN" "CT37"
						( Origin gPackager )
					)
					( objectStatus "U2D1.CT37" )
				)
				( pin "vccin(16)"
					( attribute "PN" "CR56"
						( Origin gPackager )
					)
					( objectStatus "U2D1.CR56" )
				)
				( pin "vccin(17)"
					( attribute "PN" "CR54"
						( Origin gPackager )
					)
					( objectStatus "U2D1.CR54" )
				)
				( pin "vccin(18)"
					( attribute "PN" "CR34"
						( Origin gPackager )
					)
					( objectStatus "U2D1.CR34" )
				)
				( pin "vccin(19)"
					( attribute "PN" "CP57"
						( Origin gPackager )
					)
					( objectStatus "U2D1.CP57" )
				)
				( pin "vccin(20)"
					( attribute "PN" "CP55"
						( Origin gPackager )
					)
					( objectStatus "U2D1.CP55" )
				)
				( pin "vccin(21)"
					( attribute "PN" "CP33"
						( Origin gPackager )
					)
					( objectStatus "U2D1.CP33" )
				)
				( pin "vccin(22)"
					( attribute "PN" "CN58"
						( Origin gPackager )
					)
					( objectStatus "U2D1.CN58" )
				)
				( pin "vccin(23)"
					( attribute "PN" "CN56"
						( Origin gPackager )
					)
					( objectStatus "U2D1.CN56" )
				)
				( pin "vccin(24)"
					( attribute "PN" "CM59"
						( Origin gPackager )
					)
					( objectStatus "U2D1.CM59" )
				)
				( pin "vccin(25)"
					( attribute "PN" "CM57"
						( Origin gPackager )
					)
					( objectStatus "U2D1.CM57" )
				)
				( pin "vccin(26)"
					( attribute "PN" "CL60"
						( Origin gPackager )
					)
					( objectStatus "U2D1.CL60" )
				)
				( pin "vccin(27)"
					( attribute "PN" "CL58"
						( Origin gPackager )
					)
					( objectStatus "U2D1.CL58" )
				)
				( pin "vccin(28)"
					( attribute "PN" "CK61"
						( Origin gPackager )
					)
					( objectStatus "U2D1.CK61" )
				)
				( pin "vccin(29)"
					( attribute "PN" "CK59"
						( Origin gPackager )
					)
					( objectStatus "U2D1.CK59" )
				)
				( pin "vccin(30)"
					( attribute "PN" "CJ60"
						( Origin gPackager )
					)
					( objectStatus "U2D1.CJ60" )
				)
				( pin "vccin(31)"
					( attribute "PN" "CH85"
						( Origin gPackager )
					)
					( objectStatus "U2D1.CH85" )
				)
				( pin "vccin(32)"
					( attribute "PN" "CH61"
						( Origin gPackager )
					)
					( objectStatus "U2D1.CH61" )
				)
				( pin "vccin(33)"
					( attribute "PN" "CG84"
						( Origin gPackager )
					)
					( objectStatus "U2D1.CG84" )
				)
				( pin "vccin(34)"
					( attribute "PN" "CG60"
						( Origin gPackager )
					)
					( objectStatus "U2D1.CG60" )
				)
				( pin "vccin(35)"
					( attribute "PN" "CF85"
						( Origin gPackager )
					)
					( objectStatus "U2D1.CF85" )
				)
				( pin "vccin(36)"
					( attribute "PN" "CF61"
						( Origin gPackager )
					)
					( objectStatus "U2D1.CF61" )
				)
				( pin "vccin(37)"
					( attribute "PN" "CE84"
						( Origin gPackager )
					)
					( objectStatus "U2D1.CE84" )
				)
				( pin "vccin(38)"
					( attribute "PN" "CE60"
						( Origin gPackager )
					)
					( objectStatus "U2D1.CE60" )
				)
				( pin "vccin(39)"
					( attribute "PN" "CD85"
						( Origin gPackager )
					)
					( objectStatus "U2D1.CD85" )
				)
				( pin "vccin(40)"
					( attribute "PN" "CD83"
						( Origin gPackager )
					)
					( objectStatus "U2D1.CD83" )
				)
				( pin "vccin(41)"
					( attribute "PN" "CD61"
						( Origin gPackager )
					)
					( objectStatus "U2D1.CD61" )
				)
				( pin "vccin(42)"
					( attribute "PN" "CC84"
						( Origin gPackager )
					)
					( objectStatus "U2D1.CC84" )
				)
				( pin "vccin(43)"
					( attribute "PN" "CC62"
						( Origin gPackager )
					)
					( objectStatus "U2D1.CC62" )
				)
				( pin "vccin(44)"
					( attribute "PN" "CC60"
						( Origin gPackager )
					)
					( objectStatus "U2D1.CC60" )
				)
				( pin "vccin(45)"
					( attribute "PN" "CB83"
						( Origin gPackager )
					)
					( objectStatus "U2D1.CB83" )
				)
				( pin "vccin(46)"
					( attribute "PN" "CB81"
						( Origin gPackager )
					)
					( objectStatus "U2D1.CB81" )
				)
				( pin "vccin(47)"
					( attribute "PN" "CB79"
						( Origin gPackager )
					)
					( objectStatus "U2D1.CB79" )
				)
				( pin "vccin(48)"
					( attribute "PN" "CB77"
						( Origin gPackager )
					)
					( objectStatus "U2D1.CB77" )
				)
				( pin "vccin(49)"
					( attribute "PN" "CB75"
						( Origin gPackager )
					)
					( objectStatus "U2D1.CB75" )
				)
				( pin "vccin(50)"
					( attribute "PN" "CB73"
						( Origin gPackager )
					)
					( objectStatus "U2D1.CB73" )
				)
				( pin "vccin(51)"
					( attribute "PN" "CB61"
						( Origin gPackager )
					)
					( objectStatus "U2D1.CB61" )
				)
				( pin "vccin(52)"
					( attribute "PN" "CA84"
						( Origin gPackager )
					)
					( objectStatus "U2D1.CA84" )
				)
				( pin "vccin(53)"
					( attribute "PN" "CA82"
						( Origin gPackager )
					)
					( objectStatus "U2D1.CA82" )
				)
				( pin "vccin(54)"
					( attribute "PN" "CA80"
						( Origin gPackager )
					)
					( objectStatus "U2D1.CA80" )
				)
				( pin "vccin(55)"
					( attribute "PN" "CA78"
						( Origin gPackager )
					)
					( objectStatus "U2D1.CA78" )
				)
				( pin "vccin(56)"
					( attribute "PN" "CA76"
						( Origin gPackager )
					)
					( objectStatus "U2D1.CA76" )
				)
				( pin "vccin(57)"
					( attribute "PN" "CA74"
						( Origin gPackager )
					)
					( objectStatus "U2D1.CA74" )
				)
				( pin "vccin(58)"
					( attribute "PN" "CA72"
						( Origin gPackager )
					)
					( objectStatus "U2D1.CA72" )
				)
				( pin "vccin(59)"
					( attribute "PN" "CA62"
						( Origin gPackager )
					)
					( objectStatus "U2D1.CA62" )
				)
				( pin "vccin(60)"
					( attribute "PN" "CA60"
						( Origin gPackager )
					)
					( objectStatus "U2D1.CA60" )
				)
				( pin "vccin(61)"
					( attribute "PN" "BY83"
						( Origin gPackager )
					)
					( objectStatus "U2D1.BY83" )
				)
				( pin "vccin(62)"
					( attribute "PN" "BY81"
						( Origin gPackager )
					)
					( objectStatus "U2D1.BY81" )
				)
				( pin "vccin(63)"
					( attribute "PN" "BY79"
						( Origin gPackager )
					)
					( objectStatus "U2D1.BY79" )
				)
				( pin "vccin(64)"
					( attribute "PN" "BY77"
						( Origin gPackager )
					)
					( objectStatus "U2D1.BY77" )
				)
				( pin "vccin(65)"
					( attribute "PN" "BY75"
						( Origin gPackager )
					)
					( objectStatus "U2D1.BY75" )
				)
				( pin "vccin(66)"
					( attribute "PN" "BY73"
						( Origin gPackager )
					)
					( objectStatus "U2D1.BY73" )
				)
				( pin "vccin(67)"
					( attribute "PN" "BY61"
						( Origin gPackager )
					)
					( objectStatus "U2D1.BY61" )
				)
				( pin "vccin(68)"
					( attribute "PN" "BW84"
						( Origin gPackager )
					)
					( objectStatus "U2D1.BW84" )
				)
				( pin "vccin(69)"
					( attribute "PN" "BW70"
						( Origin gPackager )
					)
					( objectStatus "U2D1.BW70" )
				)
				( pin "vccin(70)"
					( attribute "PN" "BW68"
						( Origin gPackager )
					)
					( objectStatus "U2D1.BW68" )
				)
				( pin "vccin(71)"
					( attribute "PN" "BW66"
						( Origin gPackager )
					)
					( objectStatus "U2D1.BW66" )
				)
				( pin "vccin(72)"
					( attribute "PN" "BW64"
						( Origin gPackager )
					)
					( objectStatus "U2D1.BW64" )
				)
				( pin "vccin(73)"
					( attribute "PN" "BW62"
						( Origin gPackager )
					)
					( objectStatus "U2D1.BW62" )
				)
				( pin "vccin(74)"
					( attribute "PN" "BW60"
						( Origin gPackager )
					)
					( objectStatus "U2D1.BW60" )
				)
				( pin "vccin(75)"
					( attribute "PN" "BV83"
						( Origin gPackager )
					)
					( objectStatus "U2D1.BV83" )
				)
				( pin "vccin(76)"
					( attribute "PN" "BV81"
						( Origin gPackager )
					)
					( objectStatus "U2D1.BV81" )
				)
				( pin "vccin(77)"
					( attribute "PN" "BV79"
						( Origin gPackager )
					)
					( objectStatus "U2D1.BV79" )
				)
				( pin "vccin(78)"
					( attribute "PN" "BV77"
						( Origin gPackager )
					)
					( objectStatus "U2D1.BV77" )
				)
				( pin "vccin(79)"
					( attribute "PN" "BV75"
						( Origin gPackager )
					)
					( objectStatus "U2D1.BV75" )
				)
				( pin "vccin(80)"
					( attribute "PN" "BV73"
						( Origin gPackager )
					)
					( objectStatus "U2D1.BV73" )
				)
				( pin "vccin(81)"
					( attribute "PN" "BV71"
						( Origin gPackager )
					)
					( objectStatus "U2D1.BV71" )
				)
				( pin "vccin(82)"
					( attribute "PN" "BV69"
						( Origin gPackager )
					)
					( objectStatus "U2D1.BV69" )
				)
				( pin "vccin(83)"
					( attribute "PN" "BV67"
						( Origin gPackager )
					)
					( objectStatus "U2D1.BV67" )
				)
				( pin "vccin(84)"
					( attribute "PN" "BV65"
						( Origin gPackager )
					)
					( objectStatus "U2D1.BV65" )
				)
				( pin "vccin(85)"
					( attribute "PN" "BV63"
						( Origin gPackager )
					)
					( objectStatus "U2D1.BV63" )
				)
				( pin "vccin(86)"
					( attribute "PN" "BV61"
						( Origin gPackager )
					)
					( objectStatus "U2D1.BV61" )
				)
				( pin "vccin(87)"
					( attribute "PN" "BU84"
						( Origin gPackager )
					)
					( objectStatus "U2D1.BU84" )
				)
				( pin "vccin(88)"
					( attribute "PN" "BU82"
						( Origin gPackager )
					)
					( objectStatus "U2D1.BU82" )
				)
				( pin "vccin(89)"
					( attribute "PN" "BU80"
						( Origin gPackager )
					)
					( objectStatus "U2D1.BU80" )
				)
				( pin "vccin(90)"
					( attribute "PN" "BU78"
						( Origin gPackager )
					)
					( objectStatus "U2D1.BU78" )
				)
				( pin "vccin(91)"
					( attribute "PN" "BU76"
						( Origin gPackager )
					)
					( objectStatus "U2D1.BU76" )
				)
				( pin "vccin(92)"
					( attribute "PN" "BU74"
						( Origin gPackager )
					)
					( objectStatus "U2D1.BU74" )
				)
				( pin "vccin(93)"
					( attribute "PN" "BU72"
						( Origin gPackager )
					)
					( objectStatus "U2D1.BU72" )
				)
				( pin "vccin(94)"
					( attribute "PN" "BU70"
						( Origin gPackager )
					)
					( objectStatus "U2D1.BU70" )
				)
				( pin "vccin(95)"
					( attribute "PN" "BU68"
						( Origin gPackager )
					)
					( objectStatus "U2D1.BU68" )
				)
				( pin "vccin(96)"
					( attribute "PN" "BU66"
						( Origin gPackager )
					)
					( objectStatus "U2D1.BU66" )
				)
				( pin "vccin(97)"
					( attribute "PN" "BU64"
						( Origin gPackager )
					)
					( objectStatus "U2D1.BU64" )
				)
				( pin "vccin(98)"
					( attribute "PN" "BU62"
						( Origin gPackager )
					)
					( objectStatus "U2D1.BU62" )
				)
				( pin "vccin(99)"
					( attribute "PN" "BU60"
						( Origin gPackager )
					)
					( objectStatus "U2D1.BU60" )
				)
				( pin "vccin(100)"
					( attribute "PN" "BT83"
						( Origin gPackager )
					)
					( objectStatus "U2D1.BT83" )
				)
				( pin "vccin(101)"
					( attribute "PN" "BT81"
						( Origin gPackager )
					)
					( objectStatus "U2D1.BT81" )
				)
				( pin "vccin(102)"
					( attribute "PN" "BT79"
						( Origin gPackager )
					)
					( objectStatus "U2D1.BT79" )
				)
				( pin "vccin(103)"
					( attribute "PN" "BT77"
						( Origin gPackager )
					)
					( objectStatus "U2D1.BT77" )
				)
				( pin "vccin(104)"
					( attribute "PN" "BT75"
						( Origin gPackager )
					)
					( objectStatus "U2D1.BT75" )
				)
				( pin "vccin(105)"
					( attribute "PN" "BT73"
						( Origin gPackager )
					)
					( objectStatus "U2D1.BT73" )
				)
				( pin "vccin(106)"
					( attribute "PN" "BT71"
						( Origin gPackager )
					)
					( objectStatus "U2D1.BT71" )
				)
				( pin "vccin(107)"
					( attribute "PN" "BT69"
						( Origin gPackager )
					)
					( objectStatus "U2D1.BT69" )
				)
				( pin "vccin(108)"
					( attribute "PN" "BT67"
						( Origin gPackager )
					)
					( objectStatus "U2D1.BT67" )
				)
				( pin "vccin(109)"
					( attribute "PN" "BT65"
						( Origin gPackager )
					)
					( objectStatus "U2D1.BT65" )
				)
				( pin "vccin(110)"
					( attribute "PN" "BT63"
						( Origin gPackager )
					)
					( objectStatus "U2D1.BT63" )
				)
				( pin "vccin(111)"
					( attribute "PN" "BT61"
						( Origin gPackager )
					)
					( objectStatus "U2D1.BT61" )
				)
				( pin "vccin(112)"
					( attribute "PN" "BR84"
						( Origin gPackager )
					)
					( objectStatus "U2D1.BR84" )
				)
				( pin "vccin(113)"
					( attribute "PN" "BR62"
						( Origin gPackager )
					)
					( objectStatus "U2D1.BR62" )
				)
				( pin "vccin(114)"
					( attribute "PN" "BR60"
						( Origin gPackager )
					)
					( objectStatus "U2D1.BR60" )
				)
				( pin "vccin(115)"
					( attribute "PN" "BP83"
						( Origin gPackager )
					)
					( objectStatus "U2D1.BP83" )
				)
				( pin "vccin(116)"
					( attribute "PN" "BP81"
						( Origin gPackager )
					)
					( objectStatus "U2D1.BP81" )
				)
				( pin "vccin(117)"
					( attribute "PN" "BP79"
						( Origin gPackager )
					)
					( objectStatus "U2D1.BP79" )
				)
				( pin "vccin(118)"
					( attribute "PN" "BP77"
						( Origin gPackager )
					)
					( objectStatus "U2D1.BP77" )
				)
				( pin "vccin(119)"
					( attribute "PN" "BP75"
						( Origin gPackager )
					)
					( objectStatus "U2D1.BP75" )
				)
				( pin "vccin(120)"
					( attribute "PN" "BP73"
						( Origin gPackager )
					)
					( objectStatus "U2D1.BP73" )
				)
				( pin "vccin(121)"
					( attribute "PN" "BP71"
						( Origin gPackager )
					)
					( objectStatus "U2D1.BP71" )
				)
				( pin "vccin(122)"
					( attribute "PN" "BP69"
						( Origin gPackager )
					)
					( objectStatus "U2D1.BP69" )
				)
				( pin "vccin(123)"
					( attribute "PN" "BP67"
						( Origin gPackager )
					)
					( objectStatus "U2D1.BP67" )
				)
				( pin "vccin(124)"
					( attribute "PN" "BP65"
						( Origin gPackager )
					)
					( objectStatus "U2D1.BP65" )
				)
				( pin "vccin(125)"
					( attribute "PN" "BP63"
						( Origin gPackager )
					)
					( objectStatus "U2D1.BP63" )
				)
				( pin "vccin(126)"
					( attribute "PN" "BP61"
						( Origin gPackager )
					)
					( objectStatus "U2D1.BP61" )
				)
				( pin "vccin(127)"
					( attribute "PN" "BN84"
						( Origin gPackager )
					)
					( objectStatus "U2D1.BN84" )
				)
				( pin "vccin(128)"
					( attribute "PN" "BN82"
						( Origin gPackager )
					)
					( objectStatus "U2D1.BN82" )
				)
				( pin "vccin(129)"
					( attribute "PN" "BN80"
						( Origin gPackager )
					)
					( objectStatus "U2D1.BN80" )
				)
				( pin "vccin_sense"
					( attribute "PN" "BA86"
						( Origin gPackager )
					)
					( objectStatus "U2D1.BA86" )
				)
				( pin "vccinpmax(0)"
					( attribute "PN" "AW86"
						( Origin gPackager )
					)
					( objectStatus "U2D1.AW86" )
				)
				( pin "vccinpmax(1)"
					( attribute "PN" "AV85"
						( Origin gPackager )
					)
					( objectStatus "U2D1.AV85" )
				)
				( pin "vsensepmax"
					( attribute "PN" "AD41"
						( Origin gPackager )
					)
					( objectStatus "U2D1.AD41" )
				)
				( pin "vss_vccin_sense"
					( attribute "PN" "AY85"
						( Origin gPackager )
					)
					( objectStatus "U2D1.AY85" )
				)
			)
			( gate "@baseboard_fab2_lib.baseboard_fab2(sch_1):page71_i53"
				( attribute "CDS_LIB" "mstr_discrete"
					( Origin gPackager )
				)
				( attribute "CDS_LOCATION" "R3D32"
					( Origin gPackager )
				)
				( attribute "CDS_SEC" "1"
					( Origin gPackager )
				)
				( attribute "LOCATION" "R3D32"
					( Origin gFrontEnd )
				)
				( attribute "MATERIAL" "EMPTY"
					( Origin gFrontEnd )
				)
				( attribute "PACK_TYPE" "0402"
					( Origin gFrontEnd )
				)
				( attribute "PART_NUMBER" "G21796-066"
					( Origin gFrontEnd )
				)
				( attribute "PHYS_PAGE" "71"
					( Origin gFrontEnd )
				)
				( attribute "ROOM" "CPU1"
					( Origin gFrontEnd )
				)
				( attribute "ROT" "0"
					( Origin gFrontEnd )
				)
				( attribute "SEC" "1"
					( Origin gFrontEnd )
				)
				( attribute "SEC_TYPE" "0402"
					( Origin gFrontEnd )
				)
				( attribute "TOLERANCE" "1%"
					( Origin gFrontEnd )
				)
				( attribute "VALUE" "10.0"
					( Origin gFrontEnd )
				)
				( attribute "VER" "2"
					( Origin gFrontEnd )
				)
				( attribute "WATTAGE" "1/16W"
					( Origin gFrontEnd )
				)
				( attribute "XY" "(-500,1200)"
					( Origin gFrontEnd )
				)
				( attribute "CHIPS_PART_NAME" "RES"
					( Origin gPackager )
				)
				( attribute "CDS_PART_NAME" "RES_0402-10.0,1%,1/16W,EMPTY,GA"
					( Origin gPackager )
				)
				( objectStatus "R3D32" )
				( pin "a"
					( attribute "PN" "1"
						( Origin gPackager )
					)
					( objectStatus "R3D32.1" )
				)
				( pin "b"
					( attribute "PN" "2"
						( Origin gPackager )
					)
					( objectStatus "R3D32.2" )
				)
			)
			( gate "@baseboard_fab2_lib.baseboard_fab2(sch_1):page72_i25"
				( attribute "BOM_COST" "PROC_SOCKET"
					( Origin gFrontEnd )
				)
				( attribute "CDS_LIB" "mstr_discrete"
					( Origin gPackager )
				)
				( attribute "CDS_LOCATION" "C3D3"
					( Origin gPackager )
				)
				( attribute "CDS_SEC" "1"
					( Origin gPackager )
				)
				( attribute "LOCATION" "C3D3"
					( Origin gFrontEnd )
				)
				( attribute "MATERIAL" "X6S"
					( Origin gFrontEnd )
				)
				( attribute "PACK_TYPE" "0603LF"
					( Origin gFrontEnd )
				)
				( attribute "PART_NUMBER" "E15431-001"
					( Origin gFrontEnd )
				)
				( attribute "PHYS_PAGE" "72"
					( Origin gFrontEnd )
				)
				( attribute "ROOM" "CPU1"
					( Origin gFrontEnd )
				)
				( attribute "ROT" "0"
					( Origin gFrontEnd )
				)
				( attribute "SEC" "1"
					( Origin gPackager )
				)
				( attribute "TOLERANCE" "20%"
					( Origin gFrontEnd )
				)
				( attribute "VALUE" "10UF"
					( Origin gFrontEnd )
				)
				( attribute "VER" "1"
					( Origin gFrontEnd )
				)
				( attribute "VOLTAGE" "4V"
					( Units "uVoltage" "V" 1.000000)
					( Origin gFrontEnd )
				)
				( attribute "XY" "(-525,1075)"
					( Origin gFrontEnd )
				)
				( attribute "CHIPS_PART_NAME" "CAP"
					( Origin gPackager )
				)
				( attribute "CDS_PART_NAME" "CAP_0603LF-10UF,4V,20%,X6S,E15A"
					( Origin gPackager )
				)
				( objectStatus "C3D3" )
				( pin "a"
					( attribute "PN" "1"
						( Origin gPackager )
					)
					( objectStatus "C3D3.1" )
				)
				( pin "b"
					( attribute "PN" "2"
						( Origin gPackager )
					)
					( objectStatus "C3D3.2" )
				)
			)
			( gate "@baseboard_fab2_lib.baseboard_fab2(sch_1):page72_i32"
				( attribute "CDS_LIB" "chpset_lib"
					( Origin gPackager )
				)
				( attribute "CDS_LOCATION" "U2D1"
					( Origin gPackager )
				)
				( attribute "CDS_SEC" "20"
					( Origin gPackager )
				)
				( attribute "LOCATION" "U2D1"
					( Origin gFrontEnd )
				)
				( attribute "MATERIAL" "IC"
					( Origin gFrontEnd )
				)
				( attribute "PACK_TYPE" "BGA1"
					( Origin gFrontEnd )
				)
				( attribute "PART_NUMBER" "TBD"
					( Origin gFrontEnd )
				)
				( attribute "PHYS_PAGE" "72"
					( Origin gFrontEnd )
				)
				( attribute "ROT" "0"
					( Origin gFrontEnd )
				)
				( attribute "SEC" "20"
					( Origin gFrontEnd )
				)
				( attribute "SEC_TYPE" "BGA1"
					( Origin gFrontEnd )
				)
				( attribute "VER" "20"
					( Origin gFrontEnd )
				)
				( attribute "XY" "(-6200,2550)"
					( Origin gFrontEnd )
				)
				( attribute "CHIPS_PART_NAME" "SKX_EXT_B"
					( Origin gPackager )
				)
				( attribute "CDS_PART_NAME" "SKX_EXT_B_BGA1-IC,TBD"
					( Origin gPackager )
				)
				( objectStatus "U2D1" )
				( pin "vccd012(0)"
					( attribute "PN" "B49"
						( Origin gPackager )
					)
					( objectStatus "U2D1.B49" )
				)
				( pin "vccd012(1)"
					( attribute "PN" "B53"
						( Origin gPackager )
					)
					( objectStatus "U2D1.B53" )
				)
				( pin "vccd012(2)"
					( attribute "PN" "B59"
						( Origin gPackager )
					)
					( objectStatus "U2D1.B59" )
				)
				( pin "vccd012(3)"
					( attribute "PN" "E46"
						( Origin gPackager )
					)
					( objectStatus "U2D1.E46" )
				)
				( pin "vccd012(4)"
					( attribute "PN" "E48"
						( Origin gPackager )
					)
					( objectStatus "U2D1.E48" )
				)
				( pin "vccd012(5)"
					( attribute "PN" "E50"
						( Origin gPackager )
					)
					( objectStatus "U2D1.E50" )
				)
				( pin "vccd012(6)"
					( attribute "PN" "E52"
						( Origin gPackager )
					)
					( objectStatus "U2D1.E52" )
				)
				( pin "vccd012(7)"
					( attribute "PN" "E54"
						( Origin gPackager )
					)
					( objectStatus "U2D1.E54" )
				)
				( pin "vccd012(8)"
					( attribute "PN" "E56"
						( Origin gPackager )
					)
					( objectStatus "U2D1.E56" )
				)
				( pin "vccd012(9)"
					( attribute "PN" "E58"
						( Origin gPackager )
					)
					( objectStatus "U2D1.E58" )
				)
				( pin "vccd012(10)"
					( attribute "PN" "E60"
						( Origin gPackager )
					)
					( objectStatus "U2D1.E60" )
				)
				( pin "vccd012(11)"
					( attribute "PN" "E62"
						( Origin gPackager )
					)
					( objectStatus "U2D1.E62" )
				)
				( pin "vccd012(12)"
					( attribute "PN" "E64"
						( Origin gPackager )
					)
					( objectStatus "U2D1.E64" )
				)
				( pin "vccd012(13)"
					( attribute "PN" "L46"
						( Origin gPackager )
					)
					( objectStatus "U2D1.L46" )
				)
				( pin "vccd012(14)"
					( attribute "PN" "L48"
						( Origin gPackager )
					)
					( objectStatus "U2D1.L48" )
				)
				( pin "vccd012(15)"
					( attribute "PN" "L50"
						( Origin gPackager )
					)
					( objectStatus "U2D1.L50" )
				)
				( pin "vccd012(16)"
					( attribute "PN" "L52"
						( Origin gPackager )
					)
					( objectStatus "U2D1.L52" )
				)
				( pin "vccd012(17)"
					( attribute "PN" "L54"
						( Origin gPackager )
					)
					( objectStatus "U2D1.L54" )
				)
				( pin "vccd012(18)"
					( attribute "PN" "L56"
						( Origin gPackager )
					)
					( objectStatus "U2D1.L56" )
				)
				( pin "vccd012(19)"
					( attribute "PN" "L58"
						( Origin gPackager )
					)
					( objectStatus "U2D1.L58" )
				)
				( pin "vccd012(20)"
					( attribute "PN" "L60"
						( Origin gPackager )
					)
					( objectStatus "U2D1.L60" )
				)
				( pin "vccd012(21)"
					( attribute "PN" "L62"
						( Origin gPackager )
					)
					( objectStatus "U2D1.L62" )
				)
				( pin "vccd012(22)"
					( attribute "PN" "N64"
						( Origin gPackager )
					)
					( objectStatus "U2D1.N64" )
				)
				( pin "vccd012(23)"
					( attribute "PN" "U46"
						( Origin gPackager )
					)
					( objectStatus "U2D1.U46" )
				)
				( pin "vccd012(24)"
					( attribute "PN" "U48"
						( Origin gPackager )
					)
					( objectStatus "U2D1.U48" )
				)
				( pin "vccd012(25)"
					( attribute "PN" "U50"
						( Origin gPackager )
					)
					( objectStatus "U2D1.U50" )
				)
				( pin "vccd012(26)"
					( attribute "PN" "U52"
						( Origin gPackager )
					)
					( objectStatus "U2D1.U52" )
				)
				( pin "vccd012(27)"
					( attribute "PN" "U54"
						( Origin gPackager )
					)
					( objectStatus "U2D1.U54" )
				)
				( pin "vccd012(28)"
					( attribute "PN" "U56"
						( Origin gPackager )
					)
					( objectStatus "U2D1.U56" )
				)
				( pin "vccd012(29)"
					( attribute "PN" "U58"
						( Origin gPackager )
					)
					( objectStatus "U2D1.U58" )
				)
				( pin "vccd012(30)"
					( attribute "PN" "U60"
						( Origin gPackager )
					)
					( objectStatus "U2D1.U60" )
				)
				( pin "vccd012(31)"
					( attribute "PN" "U62"
						( Origin gPackager )
					)
					( objectStatus "U2D1.U62" )
				)
				( pin "vccd012(32)"
					( attribute "PN" "W64"
						( Origin gPackager )
					)
					( objectStatus "U2D1.W64" )
				)
				( pin "vccd012(33)"
					( attribute "PN" "Y45"
						( Origin gPackager )
					)
					( objectStatus "U2D1.Y45" )
				)
				( pin "vccd012(34)"
					( attribute "PN" "Y47"
						( Origin gPackager )
					)
					( objectStatus "U2D1.Y47" )
				)
				( pin "vccd012(35)"
					( attribute "PN" "Y49"
						( Origin gPackager )
					)
					( objectStatus "U2D1.Y49" )
				)
				( pin "vccd012(36)"
					( attribute "PN" "Y51"
						( Origin gPackager )
					)
					( objectStatus "U2D1.Y51" )
				)
				( pin "vccd012(37)"
					( attribute "PN" "Y53"
						( Origin gPackager )
					)
					( objectStatus "U2D1.Y53" )
				)
				( pin "vccd012(38)"
					( attribute "PN" "Y55"
						( Origin gPackager )
					)
					( objectStatus "U2D1.Y55" )
				)
				( pin "vccd012(39)"
					( attribute "PN" "Y57"
						( Origin gPackager )
					)
					( objectStatus "U2D1.Y57" )
				)
				( pin "vccd012(40)"
					( attribute "PN" "Y59"
						( Origin gPackager )
					)
					( objectStatus "U2D1.Y59" )
				)
				( pin "vccd012(41)"
					( attribute "PN" "Y61"
						( Origin gPackager )
					)
					( objectStatus "U2D1.Y61" )
				)
				( pin "vccd012(42)"
					( attribute "PN" "Y63"
						( Origin gPackager )
					)
					( objectStatus "U2D1.Y63" )
				)
				( pin "vccd012(43)"
					( attribute "PN" "AD45"
						( Origin gPackager )
					)
					( objectStatus "U2D1.AD45" )
				)
				( pin "vccd012(44)"
					( attribute "PN" "AF55"
						( Origin gPackager )
					)
					( objectStatus "U2D1.AF55" )
				)
				( pin "vccd012(45)"
					( attribute "PN" "AF57"
						( Origin gPackager )
					)
					( objectStatus "U2D1.AF57" )
				)
				( pin "vccd012(46)"
					( attribute "PN" "AF59"
						( Origin gPackager )
					)
					( objectStatus "U2D1.AF59" )
				)
				( pin "vccd012(47)"
					( attribute "PN" "AF61"
						( Origin gPackager )
					)
					( objectStatus "U2D1.AF61" )
				)
				( pin "vccd012(48)"
					( attribute "PN" "AF63"
						( Origin gPackager )
					)
					( objectStatus "U2D1.AF63" )
				)
				( pin "vccd012(49)"
					( attribute "PN" "D45"
						( Origin gPackager )
					)
					( objectStatus "U2D1.D45" )
				)
				( pin "vccd012(50)"
					( attribute "PN" "C46"
						( Origin gPackager )
					)
					( objectStatus "U2D1.C46" )
				)
				( pin "vccd012(51)"
					( attribute "PN" "B47"
						( Origin gPackager )
					)
					( objectStatus "U2D1.B47" )
				)
				( pin "vccd345(0)"
					( attribute "PN" "EF59"
						( Origin gPackager )
					)
					( objectStatus "U2D1.EF59" )
				)
				( pin "vccd345(1)"
					( attribute "PN" "EF53"
						( Origin gPackager )
					)
					( objectStatus "U2D1.EF53" )
				)
				( pin "vccd345(2)"
					( attribute "PN" "EF49"
						( Origin gPackager )
					)
					( objectStatus "U2D1.EF49" )
				)
				( pin "vccd345(3)"
					( attribute "PN" "EC62"
						( Origin gPackager )
					)
					( objectStatus "U2D1.EC62" )
				)
				( pin "vccd345(4)"
					( attribute "PN" "EC60"
						( Origin gPackager )
					)
					( objectStatus "U2D1.EC60" )
				)
				( pin "vccd345(5)"
					( attribute "PN" "EC58"
						( Origin gPackager )
					)
					( objectStatus "U2D1.EC58" )
				)
				( pin "vccd345(6)"
					( attribute "PN" "EC56"
						( Origin gPackager )
					)
					( objectStatus "U2D1.EC56" )
				)
				( pin "vccd345(7)"
					( attribute "PN" "EC54"
						( Origin gPackager )
					)
					( objectStatus "U2D1.EC54" )
				)
				( pin "vccd345(8)"
					( attribute "PN" "EC52"
						( Origin gPackager )
					)
					( objectStatus "U2D1.EC52" )
				)
				( pin "vccd345(9)"
					( attribute "PN" "EC50"
						( Origin gPackager )
					)
					( objectStatus "U2D1.EC50" )
				)
				( pin "vccd345(10)"
					( attribute "PN" "EC48"
						( Origin gPackager )
					)
					( objectStatus "U2D1.EC48" )
				)
				( pin "vccd345(11)"
					( attribute "PN" "EC46"
						( Origin gPackager )
					)
					( objectStatus "U2D1.EC46" )
				)
				( pin "vccd345(12)"
					( attribute "PN" "DU64"
						( Origin gPackager )
					)
					( objectStatus "U2D1.DU64" )
				)
				( pin "vccd345(13)"
					( attribute "PN" "DU62"
						( Origin gPackager )
					)
					( objectStatus "U2D1.DU62" )
				)
				( pin "vccd345(14)"
					( attribute "PN" "DU60"
						( Origin gPackager )
					)
					( objectStatus "U2D1.DU60" )
				)
				( pin "vccd345(15)"
					( attribute "PN" "DU58"
						( Origin gPackager )
					)
					( objectStatus "U2D1.DU58" )
				)
				( pin "vccd345(16)"
					( attribute "PN" "DU56"
						( Origin gPackager )
					)
					( objectStatus "U2D1.DU56" )
				)
				( pin "vccd345(17)"
					( attribute "PN" "DU54"
						( Origin gPackager )
					)
					( objectStatus "U2D1.DU54" )
				)
				( pin "vccd345(18)"
					( attribute "PN" "DU52"
						( Origin gPackager )
					)
					( objectStatus "U2D1.DU52" )
				)
				( pin "vccd345(19)"
					( attribute "PN" "DU50"
						( Origin gPackager )
					)
					( objectStatus "U2D1.DU50" )
				)
				( pin "vccd345(20)"
					( attribute "PN" "DU48"
						( Origin gPackager )
					)
					( objectStatus "U2D1.DU48" )
				)
				( pin "vccd345(21)"
					( attribute "PN" "DU46"
						( Origin gPackager )
					)
					( objectStatus "U2D1.DU46" )
				)
				( pin "vccd345(22)"
					( attribute "PN" "DL62"
						( Origin gPackager )
					)
					( objectStatus "U2D1.DL62" )
				)
				( pin "vccd345(23)"
					( attribute "PN" "DL60"
						( Origin gPackager )
					)
					( objectStatus "U2D1.DL60" )
				)
				( pin "vccd345(24)"
					( attribute "PN" "DL58"
						( Origin gPackager )
					)
					( objectStatus "U2D1.DL58" )
				)
				( pin "vccd345(25)"
					( attribute "PN" "DL56"
						( Origin gPackager )
					)
					( objectStatus "U2D1.DL56" )
				)
				( pin "vccd345(26)"
					( attribute "PN" "DL54"
						( Origin gPackager )
					)
					( objectStatus "U2D1.DL54" )
				)
				( pin "vccd345(27)"
					( attribute "PN" "DL52"
						( Origin gPackager )
					)
					( objectStatus "U2D1.DL52" )
				)
				( pin "vccd345(28)"
					( attribute "PN" "DL50"
						( Origin gPackager )
					)
					( objectStatus "U2D1.DL50" )
				)
				( pin "vccd345(29)"
					( attribute "PN" "DL48"
						( Origin gPackager )
					)
					( objectStatus "U2D1.DL48" )
				)
				( pin "vccd345(30)"
					( attribute "PN" "DL46"
						( Origin gPackager )
					)
					( objectStatus "U2D1.DL46" )
				)
				( pin "vccd345(31)"
					( attribute "PN" "DJ64"
						( Origin gPackager )
					)
					( objectStatus "U2D1.DJ64" )
				)
				( pin "vccd345(32)"
					( attribute "PN" "DH63"
						( Origin gPackager )
					)
					( objectStatus "U2D1.DH63" )
				)
				( pin "vccd345(33)"
					( attribute "PN" "DH61"
						( Origin gPackager )
					)
					( objectStatus "U2D1.DH61" )
				)
				( pin "vccd345(34)"
					( attribute "PN" "DH59"
						( Origin gPackager )
					)
					( objectStatus "U2D1.DH59" )
				)
				( pin "vccd345(35)"
					( attribute "PN" "DH57"
						( Origin gPackager )
					)
					( objectStatus "U2D1.DH57" )
				)
				( pin "vccd345(36)"
					( attribute "PN" "DH55"
						( Origin gPackager )
					)
					( objectStatus "U2D1.DH55" )
				)
				( pin "vccd345(37)"
					( attribute "PN" "DH53"
						( Origin gPackager )
					)
					( objectStatus "U2D1.DH53" )
				)
				( pin "vccd345(38)"
					( attribute "PN" "DH51"
						( Origin gPackager )
					)
					( objectStatus "U2D1.DH51" )
				)
				( pin "vccd345(39)"
					( attribute "PN" "DH49"
						( Origin gPackager )
					)
					( objectStatus "U2D1.DH49" )
				)
				( pin "vccd345(40)"
					( attribute "PN" "DH47"
						( Origin gPackager )
					)
					( objectStatus "U2D1.DH47" )
				)
				( pin "vccd345(41)"
					( attribute "PN" "DH45"
						( Origin gPackager )
					)
					( objectStatus "U2D1.DH45" )
				)
				( pin "vccd345(42)"
					( attribute "PN" "DD45"
						( Origin gPackager )
					)
					( objectStatus "U2D1.DD45" )
				)
				( pin "vccd345(43)"
					( attribute "PN" "DB63"
						( Origin gPackager )
					)
					( objectStatus "U2D1.DB63" )
				)
				( pin "vccd345(44)"
					( attribute "PN" "DB61"
						( Origin gPackager )
					)
					( objectStatus "U2D1.DB61" )
				)
				( pin "vccd345(45)"
					( attribute "PN" "DB59"
						( Origin gPackager )
					)
					( objectStatus "U2D1.DB59" )
				)
				( pin "vccd345(46)"
					( attribute "PN" "DB57"
						( Origin gPackager )
					)
					( objectStatus "U2D1.DB57" )
				)
				( pin "vccd345(47)"
					( attribute "PN" "DB55"
						( Origin gPackager )
					)
					( objectStatus "U2D1.DB55" )
				)
				( pin "vccd345(48)"
					( attribute "PN" "DB53"
						( Origin gPackager )
					)
					( objectStatus "U2D1.DB53" )
				)
				( pin "vccd345(49)"
					( attribute "PN" "EF45"
						( Origin gPackager )
					)
					( objectStatus "U2D1.EF45" )
				)
				( pin "vccd345(50)"
					( attribute "PN" "EE44"
						( Origin gPackager )
					)
					( objectStatus "U2D1.EE44" )
				)
			)
			( gate "@baseboard_fab2_lib.baseboard_fab2(sch_1):page72_i33"
				( attribute "CDS_LIB" "chpset_lib"
					( Origin gPackager )
				)
				( attribute "CDS_LOCATION" "U2D1"
					( Origin gPackager )
				)
				( attribute "CDS_SEC" "21"
					( Origin gPackager )
				)
				( attribute "LOCATION" "U2D1"
					( Origin gFrontEnd )
				)
				( attribute "MATERIAL" "IC"
					( Origin gFrontEnd )
				)
				( attribute "PACK_TYPE" "BGA1"
					( Origin gFrontEnd )
				)
				( attribute "PART_NUMBER" "TBD"
					( Origin gFrontEnd )
				)
				( attribute "PHYS_PAGE" "72"
					( Origin gFrontEnd )
				)
				( attribute "ROT" "0"
					( Origin gFrontEnd )
				)
				( attribute "SEC" "21"
					( Origin gFrontEnd )
				)
				( attribute "SEC_TYPE" "BGA1"
					( Origin gFrontEnd )
				)
				( attribute "VER" "21"
					( Origin gFrontEnd )
				)
				( attribute "XY" "(-2700,2575)"
					( Origin gFrontEnd )
				)
				( attribute "CHIPS_PART_NAME" "SKX_EXT_B"
					( Origin gPackager )
				)
				( attribute "CDS_PART_NAME" "SKX_EXT_B_BGA1-IC,TBD"
					( Origin gPackager )
				)
				( objectStatus "U2D1" )
				( pin "cd_vcc_core(0)"
					( attribute "PN" "BL14"
						( Origin gPackager )
					)
					( objectStatus "U2D1.BL14" )
				)
				( pin "cd_vcc_core(1)"
					( attribute "PN" "BK15"
						( Origin gPackager )
					)
					( objectStatus "U2D1.BK15" )
				)
				( pin "cd_vcc_core(2)"
					( attribute "PN" "BK13"
						( Origin gPackager )
					)
					( objectStatus "U2D1.BK13" )
				)
				( pin "cd_vcc_core(3)"
					( attribute "PN" "BJ14"
						( Origin gPackager )
					)
					( objectStatus "U2D1.BJ14" )
				)
				( pin "cd_vcc_core(4)"
					( attribute "PN" "BJ12"
						( Origin gPackager )
					)
					( objectStatus "U2D1.BJ12" )
				)
				( pin "cd_vcc_core(5)"
					( attribute "PN" "BH13"
						( Origin gPackager )
					)
					( objectStatus "U2D1.BH13" )
				)
				( pin "cd_vcc_core(6)"
					( attribute "PN" "BG14"
						( Origin gPackager )
					)
					( objectStatus "U2D1.BG14" )
				)
				( pin "cd_vcc_core(7)"
					( attribute "PN" "BG12"
						( Origin gPackager )
					)
					( objectStatus "U2D1.BG12" )
				)
				( pin "cd_vcc_core(8)"
					( attribute "PN" "BF13"
						( Origin gPackager )
					)
					( objectStatus "U2D1.BF13" )
				)
				( pin "cd_vcc_core(9)"
					( attribute "PN" "BF11"
						( Origin gPackager )
					)
					( objectStatus "U2D1.BF11" )
				)
				( pin "cd_vcc_core(10)"
					( attribute "PN" "BE14"
						( Origin gPackager )
					)
					( objectStatus "U2D1.BE14" )
				)
				( pin "cd_vcc_core(11)"
					( attribute "PN" "BE12"
						( Origin gPackager )
					)
					( objectStatus "U2D1.BE12" )
				)
				( pin "cd_vcc_core(12)"
					( attribute "PN" "BD13"
						( Origin gPackager )
					)
					( objectStatus "U2D1.BD13" )
				)
				( pin "cd_vccin(0)"
					( attribute "PN" "BT27"
						( Origin gPackager )
					)
					( objectStatus "U2D1.BT27" )
				)
				( pin "cd_vccin(1)"
					( attribute "PN" "BU26"
						( Origin gPackager )
					)
					( objectStatus "U2D1.BU26" )
				)
				( pin "cd_vccin(2)"
					( attribute "PN" "BV27"
						( Origin gPackager )
					)
					( objectStatus "U2D1.BV27" )
				)
				( pin "cd_vccin(3)"
					( attribute "PN" "BY27"
						( Origin gPackager )
					)
					( objectStatus "U2D1.BY27" )
				)
				( pin "cd_vccp(0)"
					( attribute "PN" "BV15"
						( Origin gPackager )
					)
					( objectStatus "U2D1.BV15" )
				)
				( pin "cd_vccp(1)"
					( attribute "PN" "BV13"
						( Origin gPackager )
					)
					( objectStatus "U2D1.BV13" )
				)
				( pin "cd_vccp(2)"
					( attribute "PN" "BV11"
						( Origin gPackager )
					)
					( objectStatus "U2D1.BV11" )
				)
				( pin "cd_vccp(3)"
					( attribute "PN" "BU14"
						( Origin gPackager )
					)
					( objectStatus "U2D1.BU14" )
				)
				( pin "cd_vccp(4)"
					( attribute "PN" "BU12"
						( Origin gPackager )
					)
					( objectStatus "U2D1.BU12" )
				)
				( pin "cd_vccp(5)"
					( attribute "PN" "BT15"
						( Origin gPackager )
					)
					( objectStatus "U2D1.BT15" )
				)
				( pin "cd_vccp(6)"
					( attribute "PN" "BT13"
						( Origin gPackager )
					)
					( objectStatus "U2D1.BT13" )
				)
				( pin "cd_vccp(7)"
					( attribute "PN" "BT11"
						( Origin gPackager )
					)
					( objectStatus "U2D1.BT11" )
				)
				( pin "cd_vccp(8)"
					( attribute "PN" "BR14"
						( Origin gPackager )
					)
					( objectStatus "U2D1.BR14" )
				)
				( pin "cd_vccp(9)"
					( attribute "PN" "BR12"
						( Origin gPackager )
					)
					( objectStatus "U2D1.BR12" )
				)
				( pin "cd_vccp(10)"
					( attribute "PN" "BP15"
						( Origin gPackager )
					)
					( objectStatus "U2D1.BP15" )
				)
				( pin "cd_vccp(11)"
					( attribute "PN" "BP13"
						( Origin gPackager )
					)
					( objectStatus "U2D1.BP13" )
				)
				( pin "cd_vccp(12)"
					( attribute "PN" "BP11"
						( Origin gPackager )
					)
					( objectStatus "U2D1.BP11" )
				)
				( pin "cd_vccp(13)"
					( attribute "PN" "BN14"
						( Origin gPackager )
					)
					( objectStatus "U2D1.BN14" )
				)
				( pin "cd_vccp(14)"
					( attribute "PN" "BN12"
						( Origin gPackager )
					)
					( objectStatus "U2D1.BN12" )
				)
				( pin "cd_vccp(15)"
					( attribute "PN" "BM11"
						( Origin gPackager )
					)
					( objectStatus "U2D1.BM11" )
				)
				( pin "cd_vpp(0)"
					( attribute "PN" "B11"
						( Origin gPackager )
					)
					( objectStatus "U2D1.B11" )
				)
				( pin "cd_vpp(1)"
					( attribute "PN" "A12"
						( Origin gPackager )
					)
					( objectStatus "U2D1.A12" )
				)
				( pin "cd_vpp(2)"
					( attribute "PN" "A10"
						( Origin gPackager )
					)
					( objectStatus "U2D1.A10" )
				)
				( pin "cd_vpp(3)"
					( attribute "PN" "A8"
						( Origin gPackager )
					)
					( objectStatus "U2D1.A8" )
				)
				( pin "vcc33"
					( attribute "PN" "CY55"
						( Origin gPackager )
					)
					( objectStatus "U2D1.CY55" )
				)
				( pin "vccio(20)"
					( attribute "PN" "CM15"
						( Origin gPackager )
					)
					( objectStatus "U2D1.CM15" )
				)
				( pin "vccio(21)"
					( attribute "PN" "CL12"
						( Origin gPackager )
					)
					( objectStatus "U2D1.CL12" )
				)
				( pin "vccio(22)"
					( attribute "PN" "CK5"
						( Origin gPackager )
					)
					( objectStatus "U2D1.CK5" )
				)
				( pin "vccio(23)"
					( attribute "PN" "CV7"
						( Origin gPackager )
					)
					( objectStatus "U2D1.CV7" )
				)
				( pin "vccio(24)"
					( attribute "PN" "CH9"
						( Origin gPackager )
					)
					( objectStatus "U2D1.CH9" )
				)
				( pin "vccio(25)"
					( attribute "PN" "D7"
						( Origin gPackager )
					)
					( objectStatus "U2D1.D7" )
				)
				( pin "vccio(26)"
					( attribute "PN" "CE18"
						( Origin gPackager )
					)
					( objectStatus "U2D1.CE18" )
				)
				( pin "vccio(27)"
					( attribute "PN" "CD9"
						( Origin gPackager )
					)
					( objectStatus "U2D1.CD9" )
				)
				( pin "vccio(28)"
					( attribute "PN" "CB17"
						( Origin gPackager )
					)
					( objectStatus "U2D1.CB17" )
				)
				( pin "vccio(29)"
					( attribute "PN" "CB13"
						( Origin gPackager )
					)
					( objectStatus "U2D1.CB13" )
				)
				( pin "vccio(30)"
					( attribute "PN" "BP25"
						( Origin gPackager )
					)
					( objectStatus "U2D1.BP25" )
				)
				( pin "vccio(31)"
					( attribute "PN" "BJ24"
						( Origin gPackager )
					)
					( objectStatus "U2D1.BJ24" )
				)
				( pin "vccio(32)"
					( attribute "PN" "BF23"
						( Origin gPackager )
					)
					( objectStatus "U2D1.BF23" )
				)
				( pin "vccio(33)"
					( attribute "PN" "DA14"
						( Origin gPackager )
					)
					( objectStatus "U2D1.DA14" )
				)
				( pin "vccio(34)"
					( attribute "PN" "BB5"
						( Origin gPackager )
					)
					( objectStatus "U2D1.BB5" )
				)
				( pin "vccio(35)"
					( attribute "PN" "BA24"
						( Origin gPackager )
					)
					( objectStatus "U2D1.BA24" )
				)
				( pin "vccio(36)"
					( attribute "PN" "AY11"
						( Origin gPackager )
					)
					( objectStatus "U2D1.AY11" )
				)
				( pin "vccio(37)"
					( attribute "PN" "AW6"
						( Origin gPackager )
					)
					( objectStatus "U2D1.AW6" )
				)
				( pin "vccio(38)"
					( attribute "PN" "AT11"
						( Origin gPackager )
					)
					( objectStatus "U2D1.AT11" )
				)
				( pin "vccio(39)"
					( attribute "PN" "DD7"
						( Origin gPackager )
					)
					( objectStatus "U2D1.DD7" )
				)
				( pin "vccio(40)"
					( attribute "PN" "AN10"
						( Origin gPackager )
					)
					( objectStatus "U2D1.AN10" )
				)
				( pin "vccio(41)"
					( attribute "PN" "DF13"
						( Origin gPackager )
					)
					( objectStatus "U2D1.DF13" )
				)
				( pin "vccio(42)"
					( attribute "PN" "AH9"
						( Origin gPackager )
					)
					( objectStatus "U2D1.AH9" )
				)
				( pin "vccio(43)"
					( attribute "PN" "AC4"
						( Origin gPackager )
					)
					( objectStatus "U2D1.AC4" )
				)
				( pin "vccio(44)"
					( attribute "PN" "AC20"
						( Origin gPackager )
					)
					( objectStatus "U2D1.AC20" )
				)
				( pin "vccio(45)"
					( attribute "PN" "AA10"
						( Origin gPackager )
					)
					( objectStatus "U2D1.AA10" )
				)
				( pin "vccio(46)"
					( attribute "PN" "W6"
						( Origin gPackager )
					)
					( objectStatus "U2D1.W6" )
				)
				( pin "vccio(47)"
					( attribute "PN" "W4"
						( Origin gPackager )
					)
					( objectStatus "U2D1.W4" )
				)
				( pin "vccio(48)"
					( attribute "PN" "DF21"
						( Origin gPackager )
					)
					( objectStatus "U2D1.DF21" )
				)
				( pin "vccio(49)"
					( attribute "PN" "U14"
						( Origin gPackager )
					)
					( objectStatus "U2D1.U14" )
				)
				( pin "vccio(50)"
					( attribute "PN" "T3"
						( Origin gPackager )
					)
					( objectStatus "U2D1.T3" )
				)
				( pin "vccio(51)"
					( attribute "PN" "P5"
						( Origin gPackager )
					)
					( objectStatus "U2D1.P5" )
				)
				( pin "vccio(52)"
					( attribute "PN" "M21"
						( Origin gPackager )
					)
					( objectStatus "U2D1.M21" )
				)
				( pin "vccio(53)"
					( attribute "PN" "M11"
						( Origin gPackager )
					)
					( objectStatus "U2D1.M11" )
				)
				( pin "vccio(54)"
					( attribute "PN" "DG8"
						( Origin gPackager )
					)
					( objectStatus "U2D1.DG8" )
				)
				( pin "vccio(55)"
					( attribute "PN" "DH7"
						( Origin gPackager )
					)
					( objectStatus "U2D1.DH7" )
				)
				( pin "vccio(56)"
					( attribute "PN" "L16"
						( Origin gPackager )
					)
					( objectStatus "U2D1.L16" )
				)
				( pin "vccio(57)"
					( attribute "PN" "L14"
						( Origin gPackager )
					)
					( objectStatus "U2D1.L14" )
				)
				( pin "vccio(58)"
					( attribute "PN" "J10"
						( Origin gPackager )
					)
					( objectStatus "U2D1.J10" )
				)
				( pin "vccio(59)"
					( attribute "PN" "H13"
						( Origin gPackager )
					)
					( objectStatus "U2D1.H13" )
				)
				( pin "vccio(60)"
					( attribute "PN" "DJ16"
						( Origin gPackager )
					)
					( objectStatus "U2D1.DJ16" )
				)
				( pin "vccio(61)"
					( attribute "PN" "DM17"
						( Origin gPackager )
					)
					( objectStatus "U2D1.DM17" )
				)
				( pin "vccio(62)"
					( attribute "PN" "DN8"
						( Origin gPackager )
					)
					( objectStatus "U2D1.DN8" )
				)
				( pin "vccio(63)"
					( attribute "PN" "DP19"
						( Origin gPackager )
					)
					( objectStatus "U2D1.DP19" )
				)
				( pin "vccio(64)"
					( attribute "PN" "DR10"
						( Origin gPackager )
					)
					( objectStatus "U2D1.DR10" )
				)
				( pin "vccio(65)"
					( attribute "PN" "DR2"
						( Origin gPackager )
					)
					( objectStatus "U2D1.DR2" )
				)
				( pin "vccio(66)"
					( attribute "PN" "DU20"
						( Origin gPackager )
					)
					( objectStatus "U2D1.DU20" )
				)
				( pin "vccio(67)"
					( attribute "PN" "EA12"
						( Origin gPackager )
					)
					( objectStatus "U2D1.EA12" )
				)
				( pin "vccio(68)"
					( attribute "PN" "EB15"
						( Origin gPackager )
					)
					( objectStatus "U2D1.EB15" )
				)
				( pin "vccio(69)"
					( attribute "PN" "J2"
						( Origin gPackager )
					)
					( objectStatus "U2D1.J2" )
				)
				( pin "vccio(70)"
					( attribute "PN" "K15"
						( Origin gPackager )
					)
					( objectStatus "U2D1.K15" )
				)
				( pin "vccio(71)"
					( attribute "PN" "M7"
						( Origin gPackager )
					)
					( objectStatus "U2D1.M7" )
				)
				( pin "vccio(72)"
					( attribute "PN" "M9"
						( Origin gPackager )
					)
					( objectStatus "U2D1.M9" )
				)
				( pin "vccio(73)"
					( attribute "PN" "N18"
						( Origin gPackager )
					)
					( objectStatus "U2D1.N18" )
				)
				( pin "vccio(74)"
					( attribute "PN" "W10"
						( Origin gPackager )
					)
					( objectStatus "U2D1.W10" )
				)
				( pin "vccio(75)"
					( attribute "PN" "BC26"
						( Origin gPackager )
					)
					( objectStatus "U2D1.BC26" )
				)
				( pin "vccio(76)"
					( attribute "PN" "BB27"
						( Origin gPackager )
					)
					( objectStatus "U2D1.BB27" )
				)
				( pin "vccio(77)"
					( attribute "PN" "BA26"
						( Origin gPackager )
					)
					( objectStatus "U2D1.BA26" )
				)
				( pin "vccio(78)"
					( attribute "PN" "AY27"
						( Origin gPackager )
					)
					( objectStatus "U2D1.AY27" )
				)
				( pin "vccio(79)"
					( attribute "PN" "AW26"
						( Origin gPackager )
					)
					( objectStatus "U2D1.AW26" )
				)
				( pin "vccio(80)"
					( attribute "PN" "AV27"
						( Origin gPackager )
					)
					( objectStatus "U2D1.AV27" )
				)
				( pin "vccio(81)"
					( attribute "PN" "CF27"
						( Origin gPackager )
					)
					( objectStatus "U2D1.CF27" )
				)
				( pin "vccio(82)"
					( attribute "PN" "CD27"
						( Origin gPackager )
					)
					( objectStatus "U2D1.CD27" )
				)
				( pin "vccio(83)"
					( attribute "PN" "CC26"
						( Origin gPackager )
					)
					( objectStatus "U2D1.CC26" )
				)
				( pin "vccio(84)"
					( attribute "PN" "CJ28"
						( Origin gPackager )
					)
					( objectStatus "U2D1.CJ28" )
				)
				( pin "vccio(85)"
					( attribute "PN" "CH27"
						( Origin gPackager )
					)
					( objectStatus "U2D1.CH27" )
				)
				( pin "vccio(86)"
					( attribute "PN" "BM27"
						( Origin gPackager )
					)
					( objectStatus "U2D1.BM27" )
				)
				( pin "vccio(87)"
					( attribute "PN" "BL26"
						( Origin gPackager )
					)
					( objectStatus "U2D1.BL26" )
				)
				( pin "vccio(88)"
					( attribute "PN" "BK27"
						( Origin gPackager )
					)
					( objectStatus "U2D1.BK27" )
				)
				( pin "vccio(89)"
					( attribute "PN" "BK25"
						( Origin gPackager )
					)
					( objectStatus "U2D1.BK25" )
				)
				( pin "vccio(90)"
					( attribute "PN" "BJ26"
						( Origin gPackager )
					)
					( objectStatus "U2D1.BJ26" )
				)
				( pin "vccio(91)"
					( attribute "PN" "BH27"
						( Origin gPackager )
					)
					( objectStatus "U2D1.BH27" )
				)
				( pin "vccio(92)"
					( attribute "PN" "BH25"
						( Origin gPackager )
					)
					( objectStatus "U2D1.BH25" )
				)
				( pin "vccio(93)"
					( attribute "PN" "BG26"
						( Origin gPackager )
					)
					( objectStatus "U2D1.BG26" )
				)
				( pin "vccio(94)"
					( attribute "PN" "BF27"
						( Origin gPackager )
					)
					( objectStatus "U2D1.BF27" )
				)
				( pin "vccio(95)"
					( attribute "PN" "AE36"
						( Origin gPackager )
					)
					( objectStatus "U2D1.AE36" )
				)
				( pin "vccio(96)"
					( attribute "PN" "AD37"
						( Origin gPackager )
					)
					( objectStatus "U2D1.AD37" )
				)
				( pin "vccio(97)"
					( attribute "PN" "AC36"
						( Origin gPackager )
					)
					( objectStatus "U2D1.AC36" )
				)
				( pin "vccio(98)"
					( attribute "PN" "AF35"
						( Origin gPackager )
					)
					( objectStatus "U2D1.AF35" )
				)
				( pin "vccio(99)"
					( attribute "PN" "AD35"
						( Origin gPackager )
					)
					( objectStatus "U2D1.AD35" )
				)
				( pin "vccio(100)"
					( attribute "PN" "AE34"
						( Origin gPackager )
					)
					( objectStatus "U2D1.AE34" )
				)
				( pin "vccio(101)"
					( attribute "PN" "AG34"
						( Origin gPackager )
					)
					( objectStatus "U2D1.AG34" )
				)
				( pin "vccio(102)"
					( attribute "PN" "AM29"
						( Origin gPackager )
					)
					( objectStatus "U2D1.AM29" )
				)
				( pin "vccio(103)"
					( attribute "PN" "AL28"
						( Origin gPackager )
					)
					( objectStatus "U2D1.AL28" )
				)
				( pin "vccio(104)"
					( attribute "PN" "AR28"
						( Origin gPackager )
					)
					( objectStatus "U2D1.AR28" )
				)
				( pin "vccsa(0)"
					( attribute "PN" "CJ66"
						( Origin gPackager )
					)
					( objectStatus "U2D1.CJ66" )
				)
				( pin "vccsa(1)"
					( attribute "PN" "CJ64"
						( Origin gPackager )
					)
					( objectStatus "U2D1.CJ64" )
				)
				( pin "vccsa(2)"
					( attribute "PN" "CH75"
						( Origin gPackager )
					)
					( objectStatus "U2D1.CH75" )
				)
				( pin "vccsa(3)"
					( attribute "PN" "CH65"
						( Origin gPackager )
					)
					( objectStatus "U2D1.CH65" )
				)
				( pin "vccsa(4)"
					( attribute "PN" "CG74"
						( Origin gPackager )
					)
					( objectStatus "U2D1.CG74" )
				)
				( pin "vccsa(5)"
					( attribute "PN" "CG66"
						( Origin gPackager )
					)
					( objectStatus "U2D1.CG66" )
				)
				( pin "vccsa(6)"
					( attribute "PN" "CG64"
						( Origin gPackager )
					)
					( objectStatus "U2D1.CG64" )
				)
				( pin "vccsa(7)"
					( attribute "PN" "CF75"
						( Origin gPackager )
					)
					( objectStatus "U2D1.CF75" )
				)
				( pin "vccsa(8)"
					( attribute "PN" "CF73"
						( Origin gPackager )
					)
					( objectStatus "U2D1.CF73" )
				)
				( pin "vccsa(9)"
					( attribute "PN" "CF67"
						( Origin gPackager )
					)
					( objectStatus "U2D1.CF67" )
				)
				( pin "vccsa(10)"
					( attribute "PN" "CF65"
						( Origin gPackager )
					)
					( objectStatus "U2D1.CF65" )
				)
				( pin "vccsa(11)"
					( attribute "PN" "CE74"
						( Origin gPackager )
					)
					( objectStatus "U2D1.CE74" )
				)
				( pin "vccsa(12)"
					( attribute "PN" "CE72"
						( Origin gPackager )
					)
					( objectStatus "U2D1.CE72" )
				)
				( pin "vccsa(13)"
					( attribute "PN" "CE68"
						( Origin gPackager )
					)
					( objectStatus "U2D1.CE68" )
				)
				( pin "vccsa(14)"
					( attribute "PN" "CE66"
						( Origin gPackager )
					)
					( objectStatus "U2D1.CE66" )
				)
				( pin "vccsa(15)"
					( attribute "PN" "CE64"
						( Origin gPackager )
					)
					( objectStatus "U2D1.CE64" )
				)
				( pin "vccsa(16)"
					( attribute "PN" "CD71"
						( Origin gPackager )
					)
					( objectStatus "U2D1.CD71" )
				)
				( pin "vccsa(17)"
					( attribute "PN" "CD69"
						( Origin gPackager )
					)
					( objectStatus "U2D1.CD69" )
				)
				( pin "vccsa(18)"
					( attribute "PN" "CD67"
						( Origin gPackager )
					)
					( objectStatus "U2D1.CD67" )
				)
				( pin "vccsa(19)"
					( attribute "PN" "CD65"
						( Origin gPackager )
					)
					( objectStatus "U2D1.CD65" )
				)
				( pin "vccsa(20)"
					( attribute "PN" "CC70"
						( Origin gPackager )
					)
					( objectStatus "U2D1.CC70" )
				)
				( pin "vccsa(21)"
					( attribute "PN" "CC68"
						( Origin gPackager )
					)
					( objectStatus "U2D1.CC68" )
				)
				( pin "vccsa(22)"
					( attribute "PN" "CC66"
						( Origin gPackager )
					)
					( objectStatus "U2D1.CC66" )
				)
				( pin "vccsa(23)"
					( attribute "PN" "CB69"
						( Origin gPackager )
					)
					( objectStatus "U2D1.CB69" )
				)
				( pin "vccsa(24)"
					( attribute "PN" "CB67"
						( Origin gPackager )
					)
					( objectStatus "U2D1.CB67" )
				)
				( pin "vccsa(25)"
					( attribute "PN" "CB65"
						( Origin gPackager )
					)
					( objectStatus "U2D1.CB65" )
				)
			)
			( gate "@baseboard_fab2_lib.baseboard_fab2(sch_1):page73_i107"
				( attribute "CDS_LIB" "chpset_lib"
					( Origin gPackager )
				)
				( attribute "CDS_LOCATION" "U2D1"
					( Origin gPackager )
				)
				( attribute "CDS_SEC" "22"
					( Origin gPackager )
				)
				( attribute "LOCATION" "U2D1"
					( Origin gFrontEnd )
				)
				( attribute "MATERIAL" "IC"
					( Origin gFrontEnd )
				)
				( attribute "PACK_TYPE" "BGA1"
					( Origin gFrontEnd )
				)
				( attribute "PART_NUMBER" "TBD"
					( Origin gFrontEnd )
				)
				( attribute "PHYS_PAGE" "73"
					( Origin gFrontEnd )
				)
				( attribute "ROT" "0"
					( Origin gFrontEnd )
				)
				( attribute "SEC" "22"
					( Origin gFrontEnd )
				)
				( attribute "SEC_TYPE" "BGA1"
					( Origin gFrontEnd )
				)
				( attribute "VER" "22"
					( Origin gFrontEnd )
				)
				( attribute "XY" "(-4000,2550)"
					( Origin gFrontEnd )
				)
				( attribute "CHIPS_PART_NAME" "SKX_EXT_B"
					( Origin gPackager )
				)
				( attribute "CDS_PART_NAME" "SKX_EXT_B_BGA1-IC,TBD"
					( Origin gPackager )
				)
				( objectStatus "U2D1" )
				( pin "cd_vcc_core_sense"
					( attribute "PN" "BN16"
						( Origin gPackager )
					)
					( objectStatus "U2D1.BN16" )
				)
				( pin "cd_vccp_sense(0)"
					( attribute "PN" "BU16"
						( Origin gPackager )
					)
					( objectStatus "U2D1.BU16" )
				)
				( pin "cd_vccp_sense(1)"
					( attribute "PN" "BT17"
						( Origin gPackager )
					)
					( objectStatus "U2D1.BT17" )
				)
				( pin "cd_vss_vcc_core_sense"
					( attribute "PN" "BL16"
						( Origin gPackager )
					)
					( objectStatus "U2D1.BL16" )
				)
				( pin "rsvd(0)"
					( attribute "PN" "EF83"
						( Origin gPackager )
					)
					( objectStatus "U2D1.EF83" )
				)
				( pin "rsvd(1)"
					( attribute "PN" "EF81"
						( Origin gPackager )
					)
					( objectStatus "U2D1.EF81" )
				)
				( pin "rsvd(2)"
					( attribute "PN" "EF77"
						( Origin gPackager )
					)
					( objectStatus "U2D1.EF77" )
				)
				( pin "rsvd(3)"
					( attribute "PN" "EF47"
						( Origin gPackager )
					)
					( objectStatus "U2D1.EF47" )
				)
				( pin "rsvd(4)"
					( attribute "PN" "EE84"
						( Origin gPackager )
					)
					( objectStatus "U2D1.EE84" )
				)
				( pin "rsvd(5)"
					( attribute "PN" "EE82"
						( Origin gPackager )
					)
					( objectStatus "U2D1.EE82" )
				)
				( pin "rsvd(6)"
					( attribute "PN" "EE6"
						( Origin gPackager )
					)
					( objectStatus "U2D1.EE6" )
				)
				( pin "rsvd(7)"
					( attribute "PN" "EE46"
						( Origin gPackager )
					)
					( objectStatus "U2D1.EE46" )
				)
				( pin "rsvd(8)"
					( attribute "PN" "EE16"
						( Origin gPackager )
					)
					( objectStatus "U2D1.EE16" )
				)
				( pin "rsvd(9)"
					( attribute "PN" "ED83"
						( Origin gPackager )
					)
					( objectStatus "U2D1.ED83" )
				)
				( pin "rsvd(10)"
					( attribute "PN" "ED5"
						( Origin gPackager )
					)
					( objectStatus "U2D1.ED5" )
				)
				( pin "rsvd(11)"
					( attribute "PN" "ED45"
						( Origin gPackager )
					)
					( objectStatus "U2D1.ED45" )
				)
				( pin "rsvd(12)"
					( attribute "PN" "EC84"
						( Origin gPackager )
					)
					( objectStatus "U2D1.EC84" )
				)
				( pin "rsvd(13)"
					( attribute "PN" "EC44"
						( Origin gPackager )
					)
					( objectStatus "U2D1.EC44" )
				)
				( pin "rsvd(14)"
					( attribute "PN" "EC4"
						( Origin gPackager )
					)
					( objectStatus "U2D1.EC4" )
				)
				( pin "rsvd(15)"
					( attribute "PN" "EC16"
						( Origin gPackager )
					)
					( objectStatus "U2D1.EC16" )
				)
				( pin "rsvd(16)"
					( attribute "PN" "EB85"
						( Origin gPackager )
					)
					( objectStatus "U2D1.EB85" )
				)
				( pin "rsvd(17)"
					( attribute "PN" "EB5"
						( Origin gPackager )
					)
					( objectStatus "U2D1.EB5" )
				)
				( pin "rsvd(18)"
					( attribute "PN" "EB3"
						( Origin gPackager )
					)
					( objectStatus "U2D1.EB3" )
				)
				( pin "rsvd(19)"
					( attribute "PN" "EA44"
						( Origin gPackager )
					)
					( objectStatus "U2D1.EA44" )
				)
				( pin "rsvd(20)"
					( attribute "PN" "EA4"
						( Origin gPackager )
					)
					( objectStatus "U2D1.EA4" )
				)
				( pin "rsvd(21)"
					( attribute "PN" "DY3"
						( Origin gPackager )
					)
					( objectStatus "U2D1.DY3" )
				)
				( pin "rsvd(22)"
					( attribute "PN" "DW46"
						( Origin gPackager )
					)
					( objectStatus "U2D1.DW46" )
				)
				( pin "rsvd(23)"
					( attribute "PN" "DW44"
						( Origin gPackager )
					)
					( objectStatus "U2D1.DW44" )
				)
				( pin "rsvd(24)"
					( attribute "PN" "DV71"
						( Origin gPackager )
					)
					( objectStatus "U2D1.DV71" )
				)
				( pin "rsvd(25)"
					( attribute "PN" "DV61"
						( Origin gPackager )
					)
					( objectStatus "U2D1.DV61" )
				)
				( pin "rsvd(26)"
					( attribute "PN" "DU44"
						( Origin gPackager )
					)
					( objectStatus "U2D1.DU44" )
				)
				( pin "rsvd(27)"
					( attribute "PN" "DT71"
						( Origin gPackager )
					)
					( objectStatus "U2D1.DT71" )
				)
				( pin "rsvd(28)"
					( attribute "PN" "DR44"
						( Origin gPackager )
					)
					( objectStatus "U2D1.DR44" )
				)
				( pin "rsvd(29)"
					( attribute "PN" "DP65"
						( Origin gPackager )
					)
					( objectStatus "U2D1.DP65" )
				)
				( pin "rsvd(30)"
					( attribute "PN" "DP17"
						( Origin gPackager )
					)
					( objectStatus "U2D1.DP17" )
				)
				( pin "rsvd(31)"
					( attribute "PN" "DN66"
						( Origin gPackager )
					)
					( objectStatus "U2D1.DN66" )
				)
				( pin "rsvd(32)"
					( attribute "PN" "DN62"
						( Origin gPackager )
					)
					( objectStatus "U2D1.DN62" )
				)
				( pin "rsvd(33)"
					( attribute "PN" "DM67"
						( Origin gPackager )
					)
					( objectStatus "U2D1.DM67" )
				)
				( pin "rsvd(34)"
					( attribute "PN" "DL66"
						( Origin gPackager )
					)
					( objectStatus "U2D1.DL66" )
				)
				( pin "rsvd(35)"
					( attribute "PN" "DL38"
						( Origin gPackager )
					)
					( objectStatus "U2D1.DL38" )
				)
				( pin "rsvd(36)"
					( attribute "PN" "DK67"
						( Origin gPackager )
					)
					( objectStatus "U2D1.DK67" )
				)
				( pin "rsvd(37)"
					( attribute "PN" "DK65"
						( Origin gPackager )
					)
					( objectStatus "U2D1.DK65" )
				)
				( pin "rsvd(38)"
					( attribute "PN" "DK37"
						( Origin gPackager )
					)
					( objectStatus "U2D1.DK37" )
				)
				( pin "rsvd(39)"
					( attribute "PN" "DK15"
						( Origin gPackager )
					)
					( objectStatus "U2D1.DK15" )
				)
				( pin "rsvd(40)"
					( attribute "PN" "DJ66"
						( Origin gPackager )
					)
					( objectStatus "U2D1.DJ66" )
				)
				( pin "rsvd(41)"
					( attribute "PN" "DJ36"
						( Origin gPackager )
					)
					( objectStatus "U2D1.DJ36" )
				)
				( pin "rsvd(42)"
					( attribute "PN" "DH65"
						( Origin gPackager )
					)
					( objectStatus "U2D1.DH65" )
				)
				( pin "rsvd(43)"
					( attribute "PN" "DG64"
						( Origin gPackager )
					)
					( objectStatus "U2D1.DG64" )
				)
				( pin "rsvd(44)"
					( attribute "PN" "DG36"
						( Origin gPackager )
					)
					( objectStatus "U2D1.DG36" )
				)
				( pin "rsvd(45)"
					( attribute "PN" "DD51"
						( Origin gPackager )
					)
					( objectStatus "U2D1.DD51" )
				)
				( pin "rsvd(46)"
					( attribute "PN" "DC52"
						( Origin gPackager )
					)
					( objectStatus "U2D1.DC52" )
				)
				( pin "rsvd(47)"
					( attribute "PN" "DC46"
						( Origin gPackager )
					)
					( objectStatus "U2D1.DC46" )
				)
				( pin "rsvd(48)"
					( attribute "PN" "DA56"
						( Origin gPackager )
					)
					( objectStatus "U2D1.DA56" )
				)
				( pin "rsvd(49)"
					( attribute "PN" "DA54"
						( Origin gPackager )
					)
					( objectStatus "U2D1.DA54" )
				)
				( pin "rsvd(50)"
					( attribute "PN" "DA52"
						( Origin gPackager )
					)
					( objectStatus "U2D1.DA52" )
				)
				( pin "rsvd(51)"
					( attribute "PN" "DA40"
						( Origin gPackager )
					)
					( objectStatus "U2D1.DA40" )
				)
				( pin "rsvd(52)"
					( attribute "PN" "DA24"
						( Origin gPackager )
					)
					( objectStatus "U2D1.DA24" )
				)
				( pin "rsvd(53)"
					( attribute "PN" "CY73"
						( Origin gPackager )
					)
					( objectStatus "U2D1.CY73" )
				)
				( pin "rsvd(54)"
					( attribute "PN" "CY63"
						( Origin gPackager )
					)
					( objectStatus "U2D1.CY63" )
				)
				( pin "rsvd(55)"
					( attribute "PN" "CY57"
						( Origin gPackager )
					)
					( objectStatus "U2D1.CY57" )
				)
				( pin "rsvd(56)"
					( attribute "PN" "CY53"
						( Origin gPackager )
					)
					( objectStatus "U2D1.CY53" )
				)
				( pin "rsvd(57)"
					( attribute "PN" "CY39"
						( Origin gPackager )
					)
					( objectStatus "U2D1.CY39" )
				)
				( pin "rsvd(58)"
					( attribute "PN" "CY25"
						( Origin gPackager )
					)
					( objectStatus "U2D1.CY25" )
				)
				( pin "rsvd(59)"
					( attribute "PN" "CY23"
						( Origin gPackager )
					)
					( objectStatus "U2D1.CY23" )
				)
				( pin "rsvd(60)"
					( attribute "PN" "CW62"
						( Origin gPackager )
					)
					( objectStatus "U2D1.CW62" )
				)
				( pin "rsvd(61)"
					( attribute "PN" "CW60"
						( Origin gPackager )
					)
					( objectStatus "U2D1.CW60" )
				)
				( pin "rsvd(62)"
					( attribute "PN" "CW24"
						( Origin gPackager )
					)
					( objectStatus "U2D1.CW24" )
				)
				( pin "rsvd(63)"
					( attribute "PN" "CW22"
						( Origin gPackager )
					)
					( objectStatus "U2D1.CW22" )
				)
				( pin "rsvd(64)"
					( attribute "PN" "CV69"
						( Origin gPackager )
					)
					( objectStatus "U2D1.CV69" )
				)
				( pin "rsvd(65)"
					( attribute "PN" "CV23"
						( Origin gPackager )
					)
					( objectStatus "U2D1.CV23" )
				)
				( pin "rsvd(66)"
					( attribute "PN" "CU60"
						( Origin gPackager )
					)
					( objectStatus "U2D1.CU60" )
				)
				( pin "rsvd(67)"
					( attribute "PN" "CU6"
						( Origin gPackager )
					)
					( objectStatus "U2D1.CU6" )
				)
				( pin "rsvd(68)"
					( attribute "PN" "CU24"
						( Origin gPackager )
					)
					( objectStatus "U2D1.CU24" )
				)
				( pin "rsvd(69)"
					( attribute "PN" "CT69"
						( Origin gPackager )
					)
					( objectStatus "U2D1.CT69" )
				)
				( pin "rsvd(70)"
					( attribute "PN" "CT5"
						( Origin gPackager )
					)
					( objectStatus "U2D1.CT5" )
				)
				( pin "rsvd(71)"
					( attribute "PN" "CT23"
						( Origin gPackager )
					)
					( objectStatus "U2D1.CT23" )
				)
				( pin "rsvd(72)"
					( attribute "PN" "CR60"
						( Origin gPackager )
					)
					( objectStatus "U2D1.CR60" )
				)
				( pin "rsvd(73)"
					( attribute "PN" "CP31"
						( Origin gPackager )
					)
					( objectStatus "U2D1.CP31" )
				)
				( pin "rsvd(74)"
					( attribute "PN" "CP23"
						( Origin gPackager )
					)
					( objectStatus "U2D1.CP23" )
				)
				( pin "rsvd(75)"
					( attribute "PN" "CN28"
						( Origin gPackager )
					)
					( objectStatus "U2D1.CN28" )
				)
				( pin "rsvd(76)"
					( attribute "PN" "CN24"
						( Origin gPackager )
					)
					( objectStatus "U2D1.CN24" )
				)
				( pin "rsvd(77)"
					( attribute "PN" "CN22"
						( Origin gPackager )
					)
					( objectStatus "U2D1.CN22" )
				)
				( pin "rsvd(78)"
					( attribute "PN" "CM25"
						( Origin gPackager )
					)
					( objectStatus "U2D1.CM25" )
				)
				( pin "rsvd(79)"
					( attribute "PN" "CM23"
						( Origin gPackager )
					)
					( objectStatus "U2D1.CM23" )
				)
				( pin "rsvd(80)"
					( attribute "PN" "CL26"
						( Origin gPackager )
					)
					( objectStatus "U2D1.CL26" )
				)
				( pin "vccio(0)"
					( attribute "PN" "EE10"
						( Origin gPackager )
					)
					( objectStatus "U2D1.EE10" )
				)
				( pin "vccio(1)"
					( attribute "PN" "AE10"
						( Origin gPackager )
					)
					( objectStatus "U2D1.AE10" )
				)
				( pin "vccio(2)"
					( attribute "PN" "AF5"
						( Origin gPackager )
					)
					( objectStatus "U2D1.AF5" )
				)
				( pin "vccio(3)"
					( attribute "PN" "DV11"
						( Origin gPackager )
					)
					( objectStatus "U2D1.DV11" )
				)
				( pin "vccio(4)"
					( attribute "PN" "AM5"
						( Origin gPackager )
					)
					( objectStatus "U2D1.AM5" )
				)
				( pin "vccio(5)"
					( attribute "PN" "AT5"
						( Origin gPackager )
					)
					( objectStatus "U2D1.AT5" )
				)
				( pin "vccio(6)"
					( attribute "PN" "AT7"
						( Origin gPackager )
					)
					( objectStatus "U2D1.AT7" )
				)
				( pin "vccio(7)"
					( attribute "PN" "BE24"
						( Origin gPackager )
					)
					( objectStatus "U2D1.BE24" )
				)
				( pin "vccio(8)"
					( attribute "PN" "DK21"
						( Origin gPackager )
					)
					( objectStatus "U2D1.DK21" )
				)
				( pin "vccio(9)"
					( attribute "PN" "CF5"
						( Origin gPackager )
					)
					( objectStatus "U2D1.CF5" )
				)
				( pin "vccio(10)"
					( attribute "PN" "CG14"
						( Origin gPackager )
					)
					( objectStatus "U2D1.CG14" )
				)
				( pin "vccio(11)"
					( attribute "PN" "CL20"
						( Origin gPackager )
					)
					( objectStatus "U2D1.CL20" )
				)
				( pin "vccio(12)"
					( attribute "PN" "CP13"
						( Origin gPackager )
					)
					( objectStatus "U2D1.CP13" )
				)
				( pin "vccio(13)"
					( attribute "PN" "DE14"
						( Origin gPackager )
					)
					( objectStatus "U2D1.DE14" )
				)
				( pin "vccio(14)"
					( attribute "PN" "DC18"
						( Origin gPackager )
					)
					( objectStatus "U2D1.DC18" )
				)
				( pin "vccio(15)"
					( attribute "PN" "CY17"
						( Origin gPackager )
					)
					( objectStatus "U2D1.CY17" )
				)
				( pin "vccio(16)"
					( attribute "PN" "CU18"
						( Origin gPackager )
					)
					( objectStatus "U2D1.CU18" )
				)
				( pin "vccio(17)"
					( attribute "PN" "CV21"
						( Origin gPackager )
					)
					( objectStatus "U2D1.CV21" )
				)
				( pin "vccio(18)"
					( attribute "PN" "CU12"
						( Origin gPackager )
					)
					( objectStatus "U2D1.CU12" )
				)
				( pin "vccio(19)"
					( attribute "PN" "CN6"
						( Origin gPackager )
					)
					( objectStatus "U2D1.CN6" )
				)
				( pin "vccio_sense"
					( attribute "PN" "BH5"
						( Origin gPackager )
					)
					( objectStatus "U2D1.BH5" )
				)
				( pin "vccsa_sense"
					( attribute "PN" "CE76"
						( Origin gPackager )
					)
					( objectStatus "U2D1.CE76" )
				)
				( pin "vss_vccio_sense"
					( attribute "PN" "BF5"
						( Origin gPackager )
					)
					( objectStatus "U2D1.BF5" )
				)
				( pin "vss_vccsa_sense"
					( attribute "PN" "CG76"
						( Origin gPackager )
					)
					( objectStatus "U2D1.CG76" )
				)
			)
			( gate "@baseboard_fab2_lib.baseboard_fab2(sch_1):page74_i20"
				( attribute "CDS_LIB" "chpset_lib"
					( Origin gPackager )
				)
				( attribute "CDS_LOCATION" "U2D1"
					( Origin gPackager )
				)
				( attribute "CDS_SEC" "23"
					( Origin gPackager )
				)
				( attribute "LOCATION" "U2D1"
					( Origin gFrontEnd )
				)
				( attribute "MATERIAL" "IC"
					( Origin gFrontEnd )
				)
				( attribute "PACK_TYPE" "BGA1"
					( Origin gFrontEnd )
				)
				( attribute "PART_NUMBER" "TBD"
					( Origin gFrontEnd )
				)
				( attribute "PHYS_PAGE" "74"
					( Origin gFrontEnd )
				)
				( attribute "ROT" "0"
					( Origin gFrontEnd )
				)
				( attribute "SEC" "23"
					( Origin gFrontEnd )
				)
				( attribute "SEC_TYPE" "BGA1"
					( Origin gFrontEnd )
				)
				( attribute "VER" "23"
					( Origin gFrontEnd )
				)
				( attribute "XY" "(-6875,2600)"
					( Origin gFrontEnd )
				)
				( attribute "CHIPS_PART_NAME" "SKX_EXT_B"
					( Origin gPackager )
				)
				( attribute "CDS_PART_NAME" "SKX_EXT_B_BGA1-IC,TBD"
					( Origin gPackager )
				)
				( objectStatus "U2D1" )
				( pin "vss(1094)"
					( attribute "PN" "J74"
						( Origin gPackager )
					)
					( objectStatus "U2D1.J74" )
				)
				( pin "vss(1095)"
					( attribute "PN" "J72"
						( Origin gPackager )
					)
					( objectStatus "U2D1.J72" )
				)
				( pin "vss(1096)"
					( attribute "PN" "J40"
						( Origin gPackager )
					)
					( objectStatus "U2D1.J40" )
				)
				( pin "vss(1097)"
					( attribute "PN" "J38"
						( Origin gPackager )
					)
					( objectStatus "U2D1.J38" )
				)
				( pin "vss(1098)"
					( attribute "PN" "J34"
						( Origin gPackager )
					)
					( objectStatus "U2D1.J34" )
				)
				( pin "vss(1099)"
					( attribute "PN" "J32"
						( Origin gPackager )
					)
					( objectStatus "U2D1.J32" )
				)
				( pin "vss(1100)"
					( attribute "PN" "J28"
						( Origin gPackager )
					)
					( objectStatus "U2D1.J28" )
				)
				( pin "vss(1101)"
					( attribute "PN" "J26"
						( Origin gPackager )
					)
					( objectStatus "U2D1.J26" )
				)
				( pin "vss(1102)"
					( attribute "PN" "J22"
						( Origin gPackager )
					)
					( objectStatus "U2D1.J22" )
				)
				( pin "vss(1103)"
					( attribute "PN" "J14"
						( Origin gPackager )
					)
					( objectStatus "U2D1.J14" )
				)
				( pin "vss(1104)"
					( attribute "PN" "J12"
						( Origin gPackager )
					)
					( objectStatus "U2D1.J12" )
				)
				( pin "vss(1105)"
					( attribute "PN" "J4"
						( Origin gPackager )
					)
					( objectStatus "U2D1.J4" )
				)
				( pin "vss(1106)"
					( attribute "PN" "DN44"
						( Origin gPackager )
					)
					( objectStatus "U2D1.DN44" )
				)
				( pin "vss(1107)"
					( attribute "PN" "H75"
						( Origin gPackager )
					)
					( objectStatus "U2D1.H75" )
				)
				( pin "vss(1108)"
					( attribute "PN" "H71"
						( Origin gPackager )
					)
					( objectStatus "U2D1.H71" )
				)
				( pin "vss(1109)"
					( attribute "PN" "H65"
						( Origin gPackager )
					)
					( objectStatus "U2D1.H65" )
				)
				( pin "vss(1110)"
					( attribute "PN" "H41"
						( Origin gPackager )
					)
					( objectStatus "U2D1.H41" )
				)
				( pin "vss(1111)"
					( attribute "PN" "H39"
						( Origin gPackager )
					)
					( objectStatus "U2D1.H39" )
				)
				( pin "vss(1112)"
					( attribute "PN" "H37"
						( Origin gPackager )
					)
					( objectStatus "U2D1.H37" )
				)
				( pin "vss(1113)"
					( attribute "PN" "H35"
						( Origin gPackager )
					)
					( objectStatus "U2D1.H35" )
				)
				( pin "vss(1114)"
					( attribute "PN" "H33"
						( Origin gPackager )
					)
					( objectStatus "U2D1.H33" )
				)
				( pin "vss(1115)"
					( attribute "PN" "H31"
						( Origin gPackager )
					)
					( objectStatus "U2D1.H31" )
				)
				( pin "vss(1116)"
					( attribute "PN" "H29"
						( Origin gPackager )
					)
					( objectStatus "U2D1.H29" )
				)
				( pin "vss(1117)"
					( attribute "PN" "H27"
						( Origin gPackager )
					)
					( objectStatus "U2D1.H27" )
				)
				( pin "vss(1118)"
					( attribute "PN" "H25"
						( Origin gPackager )
					)
					( objectStatus "U2D1.H25" )
				)
				( pin "vss(1119)"
					( attribute "PN" "H11"
						( Origin gPackager )
					)
					( objectStatus "U2D1.H11" )
				)
				( pin "vss(1120)"
					( attribute "PN" "H3"
						( Origin gPackager )
					)
					( objectStatus "U2D1.H3" )
				)
				( pin "vss(1121)"
					( attribute "PN" "G82"
						( Origin gPackager )
					)
					( objectStatus "U2D1.G82" )
				)
				( pin "vss(1122)"
					( attribute "PN" "G80"
						( Origin gPackager )
					)
					( objectStatus "U2D1.G80" )
				)
				( pin "vss(1123)"
					( attribute "PN" "G78"
						( Origin gPackager )
					)
					( objectStatus "U2D1.G78" )
				)
				( pin "vss(1124)"
					( attribute "PN" "G76"
						( Origin gPackager )
					)
					( objectStatus "U2D1.G76" )
				)
				( pin "vss(1125)"
					( attribute "PN" "G70"
						( Origin gPackager )
					)
					( objectStatus "U2D1.G70" )
				)
				( pin "vss(1126)"
					( attribute "PN" "G66"
						( Origin gPackager )
					)
					( objectStatus "U2D1.G66" )
				)
				( pin "vss(1127)"
					( attribute "PN" "G42"
						( Origin gPackager )
					)
					( objectStatus "U2D1.G42" )
				)
				( pin "vss(1128)"
					( attribute "PN" "G38"
						( Origin gPackager )
					)
					( objectStatus "U2D1.G38" )
				)
				( pin "vss(1129)"
					( attribute "PN" "G36"
						( Origin gPackager )
					)
					( objectStatus "U2D1.G36" )
				)
				( pin "vss(1130)"
					( attribute "PN" "G32"
						( Origin gPackager )
					)
					( objectStatus "U2D1.G32" )
				)
				( pin "vss(1131)"
					( attribute "PN" "G30"
						( Origin gPackager )
					)
					( objectStatus "U2D1.G30" )
				)
				( pin "vss(1132)"
					( attribute "PN" "G26"
						( Origin gPackager )
					)
					( objectStatus "U2D1.G26" )
				)
				( pin "vss(1133)"
					( attribute "PN" "G24"
						( Origin gPackager )
					)
					( objectStatus "U2D1.G24" )
				)
				( pin "vss(1134)"
					( attribute "PN" "G22"
						( Origin gPackager )
					)
					( objectStatus "U2D1.G22" )
				)
				( pin "vss(1135)"
					( attribute "PN" "G8"
						( Origin gPackager )
					)
					( objectStatus "U2D1.G8" )
				)
				( pin "vss(1136)"
					( attribute "PN" "G4"
						( Origin gPackager )
					)
					( objectStatus "U2D1.G4" )
				)
				( pin "vss(1137)"
					( attribute "PN" "F69"
						( Origin gPackager )
					)
					( objectStatus "U2D1.F69" )
				)
				( pin "vss(1138)"
					( attribute "PN" "F67"
						( Origin gPackager )
					)
					( objectStatus "U2D1.F67" )
				)
				( pin "vss(1139)"
					( attribute "PN" "F43"
						( Origin gPackager )
					)
					( objectStatus "U2D1.F43" )
				)
				( pin "vss(1140)"
					( attribute "PN" "F37"
						( Origin gPackager )
					)
					( objectStatus "U2D1.F37" )
				)
				( pin "vss(1141)"
					( attribute "PN" "F31"
						( Origin gPackager )
					)
					( objectStatus "U2D1.F31" )
				)
				( pin "vss(1142)"
					( attribute "PN" "F25"
						( Origin gPackager )
					)
					( objectStatus "U2D1.F25" )
				)
				( pin "vss(1143)"
					( attribute "PN" "F19"
						( Origin gPackager )
					)
					( objectStatus "U2D1.F19" )
				)
				( pin "vss(1144)"
					( attribute "PN" "F17"
						( Origin gPackager )
					)
					( objectStatus "U2D1.F17" )
				)
				( pin "vss(1145)"
					( attribute "PN" "F5"
						( Origin gPackager )
					)
					( objectStatus "U2D1.F5" )
				)
				( pin "vss(1146)"
					( attribute "PN" "E76"
						( Origin gPackager )
					)
					( objectStatus "U2D1.E76" )
				)
				( pin "vss(1147)"
					( attribute "PN" "E74"
						( Origin gPackager )
					)
					( objectStatus "U2D1.E74" )
				)
				( pin "vss(1148)"
					( attribute "PN" "E72"
						( Origin gPackager )
					)
					( objectStatus "U2D1.E72" )
				)
				( pin "vss(1149)"
					( attribute "PN" "E22"
						( Origin gPackager )
					)
					( objectStatus "U2D1.E22" )
				)
				( pin "vss(1150)"
					( attribute "PN" "E20"
						( Origin gPackager )
					)
					( objectStatus "U2D1.E20" )
				)
				( pin "vss(1151)"
					( attribute "PN" "E18"
						( Origin gPackager )
					)
					( objectStatus "U2D1.E18" )
				)
				( pin "vss(1152)"
					( attribute "PN" "E16"
						( Origin gPackager )
					)
					( objectStatus "U2D1.E16" )
				)
				( pin "vss(1153)"
					( attribute "PN" "E8"
						( Origin gPackager )
					)
					( objectStatus "U2D1.E8" )
				)
				( pin "vss(1154)"
					( attribute "PN" "E6"
						( Origin gPackager )
					)
					( objectStatus "U2D1.E6" )
				)
				( pin "vss(1155)"
					( attribute "PN" "D77"
						( Origin gPackager )
					)
					( objectStatus "U2D1.D77" )
				)
				( pin "vss(1156)"
					( attribute "PN" "D43"
						( Origin gPackager )
					)
					( objectStatus "U2D1.D43" )
				)
				( pin "vss(1157)"
					( attribute "PN" "D41"
						( Origin gPackager )
					)
					( objectStatus "U2D1.D41" )
				)
				( pin "vss(1158)"
					( attribute "PN" "D39"
						( Origin gPackager )
					)
					( objectStatus "U2D1.D39" )
				)
				( pin "vss(1159)"
					( attribute "PN" "D37"
						( Origin gPackager )
					)
					( objectStatus "U2D1.D37" )
				)
				( pin "vss(1160)"
					( attribute "PN" "D35"
						( Origin gPackager )
					)
					( objectStatus "U2D1.D35" )
				)
				( pin "vss(1161)"
					( attribute "PN" "D33"
						( Origin gPackager )
					)
					( objectStatus "U2D1.D33" )
				)
				( pin "vss(1162)"
					( attribute "PN" "D31"
						( Origin gPackager )
					)
					( objectStatus "U2D1.D31" )
				)
				( pin "vss(1163)"
					( attribute "PN" "D29"
						( Origin gPackager )
					)
					( objectStatus "U2D1.D29" )
				)
				( pin "vss(1164)"
					( attribute "PN" "D27"
						( Origin gPackager )
					)
					( objectStatus "U2D1.D27" )
				)
				( pin "vss(1165)"
					( attribute "PN" "D25"
						( Origin gPackager )
					)
					( objectStatus "U2D1.D25" )
				)
				( pin "vss(1166)"
					( attribute "PN" "D13"
						( Origin gPackager )
					)
					( objectStatus "U2D1.D13" )
				)
				( pin "vss(1167)"
					( attribute "PN" "D11"
						( Origin gPackager )
					)
					( objectStatus "U2D1.D11" )
				)
				( pin "vss(1168)"
					( attribute "PN" "CM27"
						( Origin gPackager )
					)
					( objectStatus "U2D1.CM27" )
				)
				( pin "vss(1169)"
					( attribute "PN" "C78"
						( Origin gPackager )
					)
					( objectStatus "U2D1.C78" )
				)
				( pin "vss(1170)"
					( attribute "PN" "C76"
						( Origin gPackager )
					)
					( objectStatus "U2D1.C76" )
				)
				( pin "vss(1171)"
					( attribute "PN" "C16"
						( Origin gPackager )
					)
					( objectStatus "U2D1.C16" )
				)
				( pin "vss(1172)"
					( attribute "PN" "C14"
						( Origin gPackager )
					)
					( objectStatus "U2D1.C14" )
				)
				( pin "vss(1173)"
					( attribute "PN" "C12"
						( Origin gPackager )
					)
					( objectStatus "U2D1.C12" )
				)
				( pin "vss(1174)"
					( attribute "PN" "C10"
						( Origin gPackager )
					)
					( objectStatus "U2D1.C10" )
				)
				( pin "vss(1175)"
					( attribute "PN" "C8"
						( Origin gPackager )
					)
					( objectStatus "U2D1.C8" )
				)
				( pin "vss(1176)"
					( attribute "PN" "B75"
						( Origin gPackager )
					)
					( objectStatus "U2D1.B75" )
				)
				( pin "vss(1177)"
					( attribute "PN" "B71"
						( Origin gPackager )
					)
					( objectStatus "U2D1.B71" )
				)
				( pin "vss(1178)"
					( attribute "PN" "B37"
						( Origin gPackager )
					)
					( objectStatus "U2D1.B37" )
				)
				( pin "vss(1179)"
					( attribute "PN" "B31"
						( Origin gPackager )
					)
					( objectStatus "U2D1.B31" )
				)
				( pin "vss(1180)"
					( attribute "PN" "B25"
						( Origin gPackager )
					)
					( objectStatus "U2D1.B25" )
				)
				( pin "vss(1181)"
					( attribute "PN" "A38"
						( Origin gPackager )
					)
					( objectStatus "U2D1.A38" )
				)
				( pin "vss(1182)"
					( attribute "PN" "A36"
						( Origin gPackager )
					)
					( objectStatus "U2D1.A36" )
				)
				( pin "vss(1183)"
					( attribute "PN" "A32"
						( Origin gPackager )
					)
					( objectStatus "U2D1.A32" )
				)
				( pin "vss(1184)"
					( attribute "PN" "A30"
						( Origin gPackager )
					)
					( objectStatus "U2D1.A30" )
				)
				( pin "vss(1185)"
					( attribute "PN" "A26"
						( Origin gPackager )
					)
					( objectStatus "U2D1.A26" )
				)
				( pin "vss(1186)"
					( attribute "PN" "AC58"
						( Origin gPackager )
					)
					( objectStatus "U2D1.AC58" )
				)
				( pin "vss(1187)"
					( attribute "PN" "AC60"
						( Origin gPackager )
					)
					( objectStatus "U2D1.AC60" )
				)
				( pin "vss(1188)"
					( attribute "PN" "AC62"
						( Origin gPackager )
					)
					( objectStatus "U2D1.AC62" )
				)
				( pin "vss(1189)"
					( attribute "PN" "AJ4"
						( Origin gPackager )
					)
					( objectStatus "U2D1.AJ4" )
				)
				( pin "vss(1190)"
					( attribute "PN" "AR6"
						( Origin gPackager )
					)
					( objectStatus "U2D1.AR6" )
				)
				( pin "vss(1191)"
					( attribute "PN" "CG6"
						( Origin gPackager )
					)
					( objectStatus "U2D1.CG6" )
				)
				( pin "vss(1192)"
					( attribute "PN" "CW6"
						( Origin gPackager )
					)
					( objectStatus "U2D1.CW6" )
				)
				( pin "vss(1193)"
					( attribute "PN" "DE48"
						( Origin gPackager )
					)
					( objectStatus "U2D1.DE48" )
				)
				( pin "vss(1194)"
					( attribute "PN" "DE50"
						( Origin gPackager )
					)
					( objectStatus "U2D1.DE50" )
				)
				( pin "vss(1195)"
					( attribute "PN" "DE52"
						( Origin gPackager )
					)
					( objectStatus "U2D1.DE52" )
				)
				( pin "vss(1196)"
					( attribute "PN" "DE54"
						( Origin gPackager )
					)
					( objectStatus "U2D1.DE54" )
				)
				( pin "vss(1197)"
					( attribute "PN" "DE56"
						( Origin gPackager )
					)
					( objectStatus "U2D1.DE56" )
				)
				( pin "vss(1198)"
					( attribute "PN" "DE58"
						( Origin gPackager )
					)
					( objectStatus "U2D1.DE58" )
				)
				( pin "vss(1199)"
					( attribute "PN" "DE60"
						( Origin gPackager )
					)
					( objectStatus "U2D1.DE60" )
				)
				( pin "vss(1200)"
					( attribute "PN" "DE62"
						( Origin gPackager )
					)
					( objectStatus "U2D1.DE62" )
				)
				( pin "vss(1201)"
					( attribute "PN" "DL8"
						( Origin gPackager )
					)
					( objectStatus "U2D1.DL8" )
				)
				( pin "vss(1202)"
					( attribute "PN" "DN18"
						( Origin gPackager )
					)
					( objectStatus "U2D1.DN18" )
				)
				( pin "vss(1203)"
					( attribute "PN" "DP45"
						( Origin gPackager )
					)
					( objectStatus "U2D1.DP45" )
				)
				( pin "vss(1204)"
					( attribute "PN" "DP47"
						( Origin gPackager )
					)
					( objectStatus "U2D1.DP47" )
				)
				( pin "vss(1205)"
					( attribute "PN" "DP49"
						( Origin gPackager )
					)
					( objectStatus "U2D1.DP49" )
				)
				( pin "vss(1206)"
					( attribute "PN" "DP51"
						( Origin gPackager )
					)
					( objectStatus "U2D1.DP51" )
				)
				( pin "vss(1207)"
					( attribute "PN" "DP53"
						( Origin gPackager )
					)
					( objectStatus "U2D1.DP53" )
				)
				( pin "vss(1208)"
					( attribute "PN" "DP55"
						( Origin gPackager )
					)
					( objectStatus "U2D1.DP55" )
				)
				( pin "vss(1209)"
					( attribute "PN" "DP57"
						( Origin gPackager )
					)
					( objectStatus "U2D1.DP57" )
				)
				( pin "vss(1210)"
					( attribute "PN" "DP59"
						( Origin gPackager )
					)
					( objectStatus "U2D1.DP59" )
				)
				( pin "vss(1211)"
					( attribute "PN" "DP61"
						( Origin gPackager )
					)
					( objectStatus "U2D1.DP61" )
				)
				( pin "vss(1212)"
					( attribute "PN" "DP63"
						( Origin gPackager )
					)
					( objectStatus "U2D1.DP63" )
				)
				( pin "vss(1213)"
					( attribute "PN" "DP9"
						( Origin gPackager )
					)
					( objectStatus "U2D1.DP9" )
				)
				( pin "vss(1214)"
					( attribute "PN" "DV19"
						( Origin gPackager )
					)
					( objectStatus "U2D1.DV19" )
				)
				( pin "vss(1215)"
					( attribute "PN" "DY45"
						( Origin gPackager )
					)
					( objectStatus "U2D1.DY45" )
				)
				( pin "vss(1216)"
					( attribute "PN" "DY47"
						( Origin gPackager )
					)
					( objectStatus "U2D1.DY47" )
				)
				( pin "vss(1217)"
					( attribute "PN" "DY49"
						( Origin gPackager )
					)
					( objectStatus "U2D1.DY49" )
				)
				( pin "vss(1218)"
					( attribute "PN" "DY51"
						( Origin gPackager )
					)
					( objectStatus "U2D1.DY51" )
				)
				( pin "vss(1219)"
					( attribute "PN" "DY53"
						( Origin gPackager )
					)
					( objectStatus "U2D1.DY53" )
				)
				( pin "vss(1220)"
					( attribute "PN" "DY55"
						( Origin gPackager )
					)
					( objectStatus "U2D1.DY55" )
				)
				( pin "vss(1221)"
					( attribute "PN" "DY57"
						( Origin gPackager )
					)
					( objectStatus "U2D1.DY57" )
				)
				( pin "vss(1222)"
					( attribute "PN" "DY59"
						( Origin gPackager )
					)
					( objectStatus "U2D1.DY59" )
				)
				( pin "vss(1223)"
					( attribute "PN" "DY61"
						( Origin gPackager )
					)
					( objectStatus "U2D1.DY61" )
				)
				( pin "vss(1224)"
					( attribute "PN" "DY63"
						( Origin gPackager )
					)
					( objectStatus "U2D1.DY63" )
				)
				( pin "vss(1225)"
					( attribute "PN" "EA14"
						( Origin gPackager )
					)
					( objectStatus "U2D1.EA14" )
				)
				( pin "vss(1226)"
					( attribute "PN" "L8"
						( Origin gPackager )
					)
					( objectStatus "U2D1.L8" )
				)
				( pin "vss(1227)"
					( attribute "PN" "V11"
						( Origin gPackager )
					)
					( objectStatus "U2D1.V11" )
				)
				( pin "vss(1228)"
					( attribute "PN" "E66"
						( Origin gPackager )
					)
					( objectStatus "U2D1.E66" )
				)
				( pin "vss(1229)"
					( attribute "PN" "ED69"
						( Origin gPackager )
					)
					( objectStatus "U2D1.ED69" )
				)
				( pin "vss(1230)"
					( attribute "PN" "EE80"
						( Origin gPackager )
					)
					( objectStatus "U2D1.EE80" )
				)
				( pin "vss(1231)"
					( attribute "PN" "EE8"
						( Origin gPackager )
					)
					( objectStatus "U2D1.EE8" )
				)
				( pin "vss(1232)"
					( attribute "PN" "EE40"
						( Origin gPackager )
					)
					( objectStatus "U2D1.EE40" )
				)
				( pin "vss(1233)"
					( attribute "PN" "ED81"
						( Origin gPackager )
					)
					( objectStatus "U2D1.ED81" )
				)
				( pin "vss(1234)"
					( attribute "PN" "ED7"
						( Origin gPackager )
					)
					( objectStatus "U2D1.ED7" )
				)
				( pin "vss(1235)"
					( attribute "PN" "ED41"
						( Origin gPackager )
					)
					( objectStatus "U2D1.ED41" )
				)
				( pin "vss(1236)"
					( attribute "PN" "EC82"
						( Origin gPackager )
					)
					( objectStatus "U2D1.EC82" )
				)
				( pin "vss(1237)"
					( attribute "PN" "EC6"
						( Origin gPackager )
					)
					( objectStatus "U2D1.EC6" )
				)
				( pin "vss(1238)"
					( attribute "PN" "EC42"
						( Origin gPackager )
					)
					( objectStatus "U2D1.EC42" )
				)
				( pin "vss(1239)"
					( attribute "PN" "DW2"
						( Origin gPackager )
					)
					( objectStatus "U2D1.DW2" )
				)
				( pin "vss(1240)"
					( attribute "PN" "EB83"
						( Origin gPackager )
					)
					( objectStatus "U2D1.EB83" )
				)
				( pin "vss(1241)"
					( attribute "PN" "EA84"
						( Origin gPackager )
					)
					( objectStatus "U2D1.EA84" )
				)
				( pin "vss(1242)"
					( attribute "PN" "DY85"
						( Origin gPackager )
					)
					( objectStatus "U2D1.DY85" )
				)
				( pin "vss(1243)"
					( attribute "PN" "J86"
						( Origin gPackager )
					)
					( objectStatus "U2D1.J86" )
				)
				( pin "vss(1244)"
					( attribute "PN" "E82"
						( Origin gPackager )
					)
					( objectStatus "U2D1.E82" )
				)
				( pin "vss(1245)"
					( attribute "PN" "D81"
						( Origin gPackager )
					)
					( objectStatus "U2D1.D81" )
				)
				( pin "vss(1246)"
					( attribute "PN" "D3"
						( Origin gPackager )
					)
					( objectStatus "U2D1.D3" )
				)
				( pin "vss(1247)"
					( attribute "PN" "C80"
						( Origin gPackager )
					)
					( objectStatus "U2D1.C80" )
				)
				( pin "vss(1248)"
					( attribute "PN" "C4"
						( Origin gPackager )
					)
					( objectStatus "U2D1.C4" )
				)
				( pin "vss(1249)"
					( attribute "PN" "B79"
						( Origin gPackager )
					)
					( objectStatus "U2D1.B79" )
				)
				( pin "vss(1250)"
					( attribute "PN" "B5"
						( Origin gPackager )
					)
					( objectStatus "U2D1.B5" )
				)
				( pin "vss(1251)"
					( attribute "PN" "B43"
						( Origin gPackager )
					)
					( objectStatus "U2D1.B43" )
				)
				( pin "vss(1252)"
					( attribute "PN" "A42"
						( Origin gPackager )
					)
					( objectStatus "U2D1.A42" )
				)
				( pin "vss(1253)"
					( attribute "PN" "B9"
						( Origin gPackager )
					)
					( objectStatus "U2D1.B9" )
				)
			)
			( gate "@baseboard_fab2_lib.baseboard_fab2(sch_1):page74_i21"
				( attribute "CDS_LIB" "chpset_lib"
					( Origin gPackager )
				)
				( attribute "CDS_LOCATION" "U2D1"
					( Origin gPackager )
				)
				( attribute "CDS_SEC" "24"
					( Origin gPackager )
				)
				( attribute "LOCATION" "U2D1"
					( Origin gFrontEnd )
				)
				( attribute "MATERIAL" "IC"
					( Origin gFrontEnd )
				)
				( attribute "PACK_TYPE" "BGA1"
					( Origin gFrontEnd )
				)
				( attribute "PART_NUMBER" "TBD"
					( Origin gFrontEnd )
				)
				( attribute "PHYS_PAGE" "74"
					( Origin gFrontEnd )
				)
				( attribute "ROT" "0"
					( Origin gFrontEnd )
				)
				( attribute "SEC" "24"
					( Origin gFrontEnd )
				)
				( attribute "SEC_TYPE" "BGA1"
					( Origin gFrontEnd )
				)
				( attribute "VER" "24"
					( Origin gFrontEnd )
				)
				( attribute "XY" "(-5025,2625)"
					( Origin gFrontEnd )
				)
				( attribute "CHIPS_PART_NAME" "SKX_EXT_B"
					( Origin gPackager )
				)
				( attribute "CDS_PART_NAME" "SKX_EXT_B_BGA1-IC,TBD"
					( Origin gPackager )
				)
				( objectStatus "U2D1" )
				( pin "vss(934)"
					( attribute "PN" "AA16"
						( Origin gPackager )
					)
					( objectStatus "U2D1.AA16" )
				)
				( pin "vss(935)"
					( attribute "PN" "AA4"
						( Origin gPackager )
					)
					( objectStatus "U2D1.AA4" )
				)
				( pin "vss(936)"
					( attribute "PN" "Y85"
						( Origin gPackager )
					)
					( objectStatus "U2D1.Y85" )
				)
				( pin "vss(937)"
					( attribute "PN" "Y83"
						( Origin gPackager )
					)
					( objectStatus "U2D1.Y83" )
				)
				( pin "vss(938)"
					( attribute "PN" "Y81"
						( Origin gPackager )
					)
					( objectStatus "U2D1.Y81" )
				)
				( pin "vss(939)"
					( attribute "PN" "Y79"
						( Origin gPackager )
					)
					( objectStatus "U2D1.Y79" )
				)
				( pin "vss(940)"
					( attribute "PN" "Y73"
						( Origin gPackager )
					)
					( objectStatus "U2D1.Y73" )
				)
				( pin "vss(941)"
					( attribute "PN" "Y71"
						( Origin gPackager )
					)
					( objectStatus "U2D1.Y71" )
				)
				( pin "vss(942)"
					( attribute "PN" "Y9"
						( Origin gPackager )
					)
					( objectStatus "U2D1.Y9" )
				)
				( pin "vss(943)"
					( attribute "PN" "Y7"
						( Origin gPackager )
					)
					( objectStatus "U2D1.Y7" )
				)
				( pin "vss(944)"
					( attribute "PN" "Y67"
						( Origin gPackager )
					)
					( objectStatus "U2D1.Y67" )
				)
				( pin "vss(945)"
					( attribute "PN" "Y5"
						( Origin gPackager )
					)
					( objectStatus "U2D1.Y5" )
				)
				( pin "vss(946)"
					( attribute "PN" "Y17"
						( Origin gPackager )
					)
					( objectStatus "U2D1.Y17" )
				)
				( pin "vss(947)"
					( attribute "PN" "Y15"
						( Origin gPackager )
					)
					( objectStatus "U2D1.Y15" )
				)
				( pin "vss(948)"
					( attribute "PN" "W82"
						( Origin gPackager )
					)
					( objectStatus "U2D1.W82" )
				)
				( pin "vss(949)"
					( attribute "PN" "W78"
						( Origin gPackager )
					)
					( objectStatus "U2D1.W78" )
				)
				( pin "vss(950)"
					( attribute "PN" "W74"
						( Origin gPackager )
					)
					( objectStatus "U2D1.W74" )
				)
				( pin "vss(951)"
					( attribute "PN" "W68"
						( Origin gPackager )
					)
					( objectStatus "U2D1.W68" )
				)
				( pin "vss(952)"
					( attribute "PN" "W42"
						( Origin gPackager )
					)
					( objectStatus "U2D1.W42" )
				)
				( pin "vss(953)"
					( attribute "PN" "W40"
						( Origin gPackager )
					)
					( objectStatus "U2D1.W40" )
				)
				( pin "vss(954)"
					( attribute "PN" "W38"
						( Origin gPackager )
					)
					( objectStatus "U2D1.W38" )
				)
				( pin "vss(955)"
					( attribute "PN" "W36"
						( Origin gPackager )
					)
					( objectStatus "U2D1.W36" )
				)
				( pin "vss(956)"
					( attribute "PN" "W34"
						( Origin gPackager )
					)
					( objectStatus "U2D1.W34" )
				)
				( pin "vss(957)"
					( attribute "PN" "W32"
						( Origin gPackager )
					)
					( objectStatus "U2D1.W32" )
				)
				( pin "vss(958)"
					( attribute "PN" "W30"
						( Origin gPackager )
					)
					( objectStatus "U2D1.W30" )
				)
				( pin "vss(959)"
					( attribute "PN" "W28"
						( Origin gPackager )
					)
					( objectStatus "U2D1.W28" )
				)
				( pin "vss(960)"
					( attribute "PN" "W26"
						( Origin gPackager )
					)
					( objectStatus "U2D1.W26" )
				)
				( pin "vss(961)"
					( attribute "PN" "W24"
						( Origin gPackager )
					)
					( objectStatus "U2D1.W24" )
				)
				( pin "vss(962)"
					( attribute "PN" "W22"
						( Origin gPackager )
					)
					( objectStatus "U2D1.W22" )
				)
				( pin "vss(963)"
					( attribute "PN" "W12"
						( Origin gPackager )
					)
					( objectStatus "U2D1.W12" )
				)
				( pin "vss(964)"
					( attribute "PN" "AC56"
						( Origin gPackager )
					)
					( objectStatus "U2D1.AC56" )
				)
				( pin "vss(965)"
					( attribute "PN" "W8"
						( Origin gPackager )
					)
					( objectStatus "U2D1.W8" )
				)
				( pin "vss(966)"
					( attribute "PN" "V83"
						( Origin gPackager )
					)
					( objectStatus "U2D1.V83" )
				)
				( pin "vss(967)"
					( attribute "PN" "V77"
						( Origin gPackager )
					)
					( objectStatus "U2D1.V77" )
				)
				( pin "vss(968)"
					( attribute "PN" "V75"
						( Origin gPackager )
					)
					( objectStatus "U2D1.V75" )
				)
				( pin "vss(969)"
					( attribute "PN" "V73"
						( Origin gPackager )
					)
					( objectStatus "U2D1.V73" )
				)
				( pin "vss(970)"
					( attribute "PN" "V43"
						( Origin gPackager )
					)
					( objectStatus "U2D1.V43" )
				)
				( pin "vss(971)"
					( attribute "PN" "V23"
						( Origin gPackager )
					)
					( objectStatus "U2D1.V23" )
				)
				( pin "vss(972)"
					( attribute "PN" "V21"
						( Origin gPackager )
					)
					( objectStatus "U2D1.V21" )
				)
				( pin "vss(973)"
					( attribute "PN" "V15"
						( Origin gPackager )
					)
					( objectStatus "U2D1.V15" )
				)
				( pin "vss(974)"
					( attribute "PN" "V13"
						( Origin gPackager )
					)
					( objectStatus "U2D1.V13" )
				)
				( pin "vss(975)"
					( attribute "PN" "V9"
						( Origin gPackager )
					)
					( objectStatus "U2D1.V9" )
				)
				( pin "vss(976)"
					( attribute "PN" "V5"
						( Origin gPackager )
					)
					( objectStatus "U2D1.V5" )
				)
				( pin "vss(977)"
					( attribute "PN" "V1"
						( Origin gPackager )
					)
					( objectStatus "U2D1.V1" )
				)
				( pin "vss(978)"
					( attribute "PN" "U86"
						( Origin gPackager )
					)
					( objectStatus "U2D1.U86" )
				)
				( pin "vss(979)"
					( attribute "PN" "U80"
						( Origin gPackager )
					)
					( objectStatus "U2D1.U80" )
				)
				( pin "vss(980)"
					( attribute "PN" "U78"
						( Origin gPackager )
					)
					( objectStatus "U2D1.U78" )
				)
				( pin "vss(981)"
					( attribute "PN" "U76"
						( Origin gPackager )
					)
					( objectStatus "U2D1.U76" )
				)
				( pin "vss(982)"
					( attribute "PN" "U74"
						( Origin gPackager )
					)
					( objectStatus "U2D1.U74" )
				)
				( pin "vss(983)"
					( attribute "PN" "U70"
						( Origin gPackager )
					)
					( objectStatus "U2D1.U70" )
				)
				( pin "vss(984)"
					( attribute "PN" "U68"
						( Origin gPackager )
					)
					( objectStatus "U2D1.U68" )
				)
				( pin "vss(985)"
					( attribute "PN" "U42"
						( Origin gPackager )
					)
					( objectStatus "U2D1.U42" )
				)
				( pin "vss(986)"
					( attribute "PN" "U36"
						( Origin gPackager )
					)
					( objectStatus "U2D1.U36" )
				)
				( pin "vss(987)"
					( attribute "PN" "U30"
						( Origin gPackager )
					)
					( objectStatus "U2D1.U30" )
				)
				( pin "vss(988)"
					( attribute "PN" "U24"
						( Origin gPackager )
					)
					( objectStatus "U2D1.U24" )
				)
				( pin "vss(989)"
					( attribute "PN" "U22"
						( Origin gPackager )
					)
					( objectStatus "U2D1.U22" )
				)
				( pin "vss(990)"
					( attribute "PN" "U20"
						( Origin gPackager )
					)
					( objectStatus "U2D1.U20" )
				)
				( pin "vss(991)"
					( attribute "PN" "U6"
						( Origin gPackager )
					)
					( objectStatus "U2D1.U6" )
				)
				( pin "vss(992)"
					( attribute "PN" "U4"
						( Origin gPackager )
					)
					( objectStatus "U2D1.U4" )
				)
				( pin "vss(993)"
					( attribute "PN" "U2"
						( Origin gPackager )
					)
					( objectStatus "U2D1.U2" )
				)
				( pin "vss(994)"
					( attribute "PN" "T85"
						( Origin gPackager )
					)
					( objectStatus "U2D1.T85" )
				)
				( pin "vss(995)"
					( attribute "PN" "T83"
						( Origin gPackager )
					)
					( objectStatus "U2D1.T83" )
				)
				( pin "vss(996)"
					( attribute "PN" "T77"
						( Origin gPackager )
					)
					( objectStatus "U2D1.T77" )
				)
				( pin "vss(997)"
					( attribute "PN" "T73"
						( Origin gPackager )
					)
					( objectStatus "U2D1.T73" )
				)
				( pin "vss(998)"
					( attribute "PN" "T65"
						( Origin gPackager )
					)
					( objectStatus "U2D1.T65" )
				)
				( pin "vss(999)"
					( attribute "PN" "T41"
						( Origin gPackager )
					)
					( objectStatus "U2D1.T41" )
				)
				( pin "vss(1000)"
					( attribute "PN" "T37"
						( Origin gPackager )
					)
					( objectStatus "U2D1.T37" )
				)
				( pin "vss(1001)"
					( attribute "PN" "T35"
						( Origin gPackager )
					)
					( objectStatus "U2D1.T35" )
				)
				( pin "vss(1002)"
					( attribute "PN" "T31"
						( Origin gPackager )
					)
					( objectStatus "U2D1.T31" )
				)
				( pin "vss(1003)"
					( attribute "PN" "T29"
						( Origin gPackager )
					)
					( objectStatus "U2D1.T29" )
				)
				( pin "vss(1004)"
					( attribute "PN" "T25"
						( Origin gPackager )
					)
					( objectStatus "U2D1.T25" )
				)
				( pin "vss(1005)"
					( attribute "PN" "T17"
						( Origin gPackager )
					)
					( objectStatus "U2D1.T17" )
				)
				( pin "vss(1006)"
					( attribute "PN" "T13"
						( Origin gPackager )
					)
					( objectStatus "U2D1.T13" )
				)
				( pin "vss(1007)"
					( attribute "PN" "R86"
						( Origin gPackager )
					)
					( objectStatus "U2D1.R86" )
				)
				( pin "vss(1008)"
					( attribute "PN" "R78"
						( Origin gPackager )
					)
					( objectStatus "U2D1.R78" )
				)
				( pin "vss(1009)"
					( attribute "PN" "R72"
						( Origin gPackager )
					)
					( objectStatus "U2D1.R72" )
				)
				( pin "vss(1010)"
					( attribute "PN" "R68"
						( Origin gPackager )
					)
					( objectStatus "U2D1.R68" )
				)
				( pin "vss(1011)"
					( attribute "PN" "R40"
						( Origin gPackager )
					)
					( objectStatus "U2D1.R40" )
				)
				( pin "vss(1012)"
					( attribute "PN" "R38"
						( Origin gPackager )
					)
					( objectStatus "U2D1.R38" )
				)
				( pin "vss(1013)"
					( attribute "PN" "R34"
						( Origin gPackager )
					)
					( objectStatus "U2D1.R34" )
				)
				( pin "vss(1014)"
					( attribute "PN" "R32"
						( Origin gPackager )
					)
					( objectStatus "U2D1.R32" )
				)
				( pin "vss(1015)"
					( attribute "PN" "R28"
						( Origin gPackager )
					)
					( objectStatus "U2D1.R28" )
				)
				( pin "vss(1016)"
					( attribute "PN" "R26"
						( Origin gPackager )
					)
					( objectStatus "U2D1.R26" )
				)
				( pin "vss(1017)"
					( attribute "PN" "R22"
						( Origin gPackager )
					)
					( objectStatus "U2D1.R22" )
				)
				( pin "vss(1018)"
					( attribute "PN" "R4"
						( Origin gPackager )
					)
					( objectStatus "U2D1.R4" )
				)
				( pin "vss(1019)"
					( attribute "PN" "R2"
						( Origin gPackager )
					)
					( objectStatus "U2D1.R2" )
				)
				( pin "vss(1020)"
					( attribute "PN" "R18"
						( Origin gPackager )
					)
					( objectStatus "U2D1.R18" )
				)
				( pin "vss(1021)"
					( attribute "PN" "R14"
						( Origin gPackager )
					)
					( objectStatus "U2D1.R14" )
				)
				( pin "vss(1022)"
					( attribute "PN" "P83"
						( Origin gPackager )
					)
					( objectStatus "U2D1.P83" )
				)
				( pin "vss(1023)"
					( attribute "PN" "P81"
						( Origin gPackager )
					)
					( objectStatus "U2D1.P81" )
				)
				( pin "vss(1024)"
					( attribute "PN" "P71"
						( Origin gPackager )
					)
					( objectStatus "U2D1.P71" )
				)
				( pin "vss(1025)"
					( attribute "PN" "P69"
						( Origin gPackager )
					)
					( objectStatus "U2D1.P69" )
				)
				( pin "vss(1026)"
					( attribute "PN" "P67"
						( Origin gPackager )
					)
					( objectStatus "U2D1.P67" )
				)
				( pin "vss(1027)"
					( attribute "PN" "P39"
						( Origin gPackager )
					)
					( objectStatus "U2D1.P39" )
				)
				( pin "vss(1028)"
					( attribute "PN" "P33"
						( Origin gPackager )
					)
					( objectStatus "U2D1.P33" )
				)
				( pin "vss(1029)"
					( attribute "PN" "P27"
						( Origin gPackager )
					)
					( objectStatus "U2D1.P27" )
				)
				( pin "vss(1030)"
					( attribute "PN" "P15"
						( Origin gPackager )
					)
					( objectStatus "U2D1.P15" )
				)
				( pin "vss(1031)"
					( attribute "PN" "P11"
						( Origin gPackager )
					)
					( objectStatus "U2D1.P11" )
				)
				( pin "vss(1032)"
					( attribute "PN" "N8"
						( Origin gPackager )
					)
					( objectStatus "U2D1.N8" )
				)
				( pin "vss(1033)"
					( attribute "PN" "N4"
						( Origin gPackager )
					)
					( objectStatus "U2D1.N4" )
				)
				( pin "vss(1034)"
					( attribute "PN" "N78"
						( Origin gPackager )
					)
					( objectStatus "U2D1.N78" )
				)
				( pin "vss(1035)"
					( attribute "PN" "N76"
						( Origin gPackager )
					)
					( objectStatus "U2D1.N76" )
				)
				( pin "vss(1036)"
					( attribute "PN" "N74"
						( Origin gPackager )
					)
					( objectStatus "U2D1.N74" )
				)
				( pin "vss(1037)"
					( attribute "PN" "N72"
						( Origin gPackager )
					)
					( objectStatus "U2D1.N72" )
				)
				( pin "vss(1038)"
					( attribute "PN" "N70"
						( Origin gPackager )
					)
					( objectStatus "U2D1.N70" )
				)
				( pin "vss(1039)"
					( attribute "PN" "N66"
						( Origin gPackager )
					)
					( objectStatus "U2D1.N66" )
				)
				( pin "vss(1040)"
					( attribute "PN" "N6"
						( Origin gPackager )
					)
					( objectStatus "U2D1.N6" )
				)
				( pin "vss(1041)"
					( attribute "PN" "N22"
						( Origin gPackager )
					)
					( objectStatus "U2D1.N22" )
				)
				( pin "vss(1042)"
					( attribute "PN" "N20"
						( Origin gPackager )
					)
					( objectStatus "U2D1.N20" )
				)
				( pin "vss(1043)"
					( attribute "PN" "DM19"
						( Origin gPackager )
					)
					( objectStatus "U2D1.DM19" )
				)
				( pin "vss(1044)"
					( attribute "PN" "M85"
						( Origin gPackager )
					)
					( objectStatus "U2D1.M85" )
				)
				( pin "vss(1045)"
					( attribute "PN" "M83"
						( Origin gPackager )
					)
					( objectStatus "U2D1.M83" )
				)
				( pin "vss(1046)"
					( attribute "PN" "M79"
						( Origin gPackager )
					)
					( objectStatus "U2D1.M79" )
				)
				( pin "vss(1047)"
					( attribute "PN" "M71"
						( Origin gPackager )
					)
					( objectStatus "U2D1.M71" )
				)
				( pin "vss(1048)"
					( attribute "PN" "M65"
						( Origin gPackager )
					)
					( objectStatus "U2D1.M65" )
				)
				( pin "vss(1049)"
					( attribute "PN" "M43"
						( Origin gPackager )
					)
					( objectStatus "U2D1.M43" )
				)
				( pin "vss(1050)"
					( attribute "PN" "M41"
						( Origin gPackager )
					)
					( objectStatus "U2D1.M41" )
				)
				( pin "vss(1051)"
					( attribute "PN" "M39"
						( Origin gPackager )
					)
					( objectStatus "U2D1.M39" )
				)
				( pin "vss(1052)"
					( attribute "PN" "M37"
						( Origin gPackager )
					)
					( objectStatus "U2D1.M37" )
				)
				( pin "vss(1053)"
					( attribute "PN" "M35"
						( Origin gPackager )
					)
					( objectStatus "U2D1.M35" )
				)
				( pin "vss(1054)"
					( attribute "PN" "M33"
						( Origin gPackager )
					)
					( objectStatus "U2D1.M33" )
				)
				( pin "vss(1055)"
					( attribute "PN" "M31"
						( Origin gPackager )
					)
					( objectStatus "U2D1.M31" )
				)
				( pin "vss(1056)"
					( attribute "PN" "M29"
						( Origin gPackager )
					)
					( objectStatus "U2D1.M29" )
				)
				( pin "vss(1057)"
					( attribute "PN" "M27"
						( Origin gPackager )
					)
					( objectStatus "U2D1.M27" )
				)
				( pin "vss(1058)"
					( attribute "PN" "M25"
						( Origin gPackager )
					)
					( objectStatus "U2D1.M25" )
				)
				( pin "vss(1059)"
					( attribute "PN" "M23"
						( Origin gPackager )
					)
					( objectStatus "U2D1.M23" )
				)
				( pin "vss(1060)"
					( attribute "PN" "M19"
						( Origin gPackager )
					)
					( objectStatus "U2D1.M19" )
				)
				( pin "vss(1061)"
					( attribute "PN" "M17"
						( Origin gPackager )
					)
					( objectStatus "U2D1.M17" )
				)
				( pin "vss(1062)"
					( attribute "PN" "M15"
						( Origin gPackager )
					)
					( objectStatus "U2D1.M15" )
				)
				( pin "vss(1063)"
					( attribute "PN" "CT7"
						( Origin gPackager )
					)
					( objectStatus "U2D1.CT7" )
				)
				( pin "vss(1064)"
					( attribute "PN" "BT9"
						( Origin gPackager )
					)
					( objectStatus "U2D1.BT9" )
				)
				( pin "vss(1065)"
					( attribute "PN" "L82"
						( Origin gPackager )
					)
					( objectStatus "U2D1.L82" )
				)
				( pin "vss(1066)"
					( attribute "PN" "L80"
						( Origin gPackager )
					)
					( objectStatus "U2D1.L80" )
				)
				( pin "vss(1067)"
					( attribute "PN" "L78"
						( Origin gPackager )
					)
					( objectStatus "U2D1.L78" )
				)
				( pin "vss(1068)"
					( attribute "PN" "L72"
						( Origin gPackager )
					)
					( objectStatus "U2D1.L72" )
				)
				( pin "vss(1069)"
					( attribute "PN" "L22"
						( Origin gPackager )
					)
					( objectStatus "U2D1.L22" )
				)
				( pin "vss(1070)"
					( attribute "PN" "L20"
						( Origin gPackager )
					)
					( objectStatus "U2D1.L20" )
				)
				( pin "vss(1071)"
					( attribute "PN" "L6"
						( Origin gPackager )
					)
					( objectStatus "U2D1.L6" )
				)
				( pin "vss(1072)"
					( attribute "PN" "L2"
						( Origin gPackager )
					)
					( objectStatus "U2D1.L2" )
				)
				( pin "vss(1073)"
					( attribute "PN" "L10"
						( Origin gPackager )
					)
					( objectStatus "U2D1.L10" )
				)
				( pin "vss(1074)"
					( attribute "PN" "K85"
						( Origin gPackager )
					)
					( objectStatus "U2D1.K85" )
				)
				( pin "vss(1075)"
					( attribute "PN" "K83"
						( Origin gPackager )
					)
					( objectStatus "U2D1.K83" )
				)
				( pin "vss(1076)"
					( attribute "PN" "K81"
						( Origin gPackager )
					)
					( objectStatus "U2D1.K81" )
				)
				( pin "vss(1077)"
					( attribute "PN" "K77"
						( Origin gPackager )
					)
					( objectStatus "U2D1.K77" )
				)
				( pin "vss(1078)"
					( attribute "PN" "K73"
						( Origin gPackager )
					)
					( objectStatus "U2D1.K73" )
				)
				( pin "vss(1079)"
					( attribute "PN" "K71"
						( Origin gPackager )
					)
					( objectStatus "U2D1.K71" )
				)
				( pin "vss(1080)"
					( attribute "PN" "K69"
						( Origin gPackager )
					)
					( objectStatus "U2D1.K69" )
				)
				( pin "vss(1081)"
					( attribute "PN" "K67"
						( Origin gPackager )
					)
					( objectStatus "U2D1.K67" )
				)
				( pin "vss(1082)"
					( attribute "PN" "K65"
						( Origin gPackager )
					)
					( objectStatus "U2D1.K65" )
				)
				( pin "vss(1083)"
					( attribute "PN" "K39"
						( Origin gPackager )
					)
					( objectStatus "U2D1.K39" )
				)
				( pin "vss(1084)"
					( attribute "PN" "K33"
						( Origin gPackager )
					)
					( objectStatus "U2D1.K33" )
				)
				( pin "vss(1085)"
					( attribute "PN" "K27"
						( Origin gPackager )
					)
					( objectStatus "U2D1.K27" )
				)
				( pin "vss(1086)"
					( attribute "PN" "DB7"
						( Origin gPackager )
					)
					( objectStatus "U2D1.DB7" )
				)
				( pin "vss(1087)"
					( attribute "PN" "K17"
						( Origin gPackager )
					)
					( objectStatus "U2D1.K17" )
				)
				( pin "vss(1088)"
					( attribute "PN" "K13"
						( Origin gPackager )
					)
					( objectStatus "U2D1.K13" )
				)
				( pin "vss(1089)"
					( attribute "PN" "K11"
						( Origin gPackager )
					)
					( objectStatus "U2D1.K11" )
				)
				( pin "vss(1090)"
					( attribute "PN" "K1"
						( Origin gPackager )
					)
					( objectStatus "U2D1.K1" )
				)
				( pin "vss(1091)"
					( attribute "PN" "J84"
						( Origin gPackager )
					)
					( objectStatus "U2D1.J84" )
				)
				( pin "vss(1092)"
					( attribute "PN" "J82"
						( Origin gPackager )
					)
					( objectStatus "U2D1.J82" )
				)
				( pin "vss(1093)"
					( attribute "PN" "J76"
						( Origin gPackager )
					)
					( objectStatus "U2D1.J76" )
				)
			)
			( gate "@baseboard_fab2_lib.baseboard_fab2(sch_1):page74_i22"
				( attribute "CDS_LIB" "chpset_lib"
					( Origin gPackager )
				)
				( attribute "CDS_LOCATION" "U2D1"
					( Origin gPackager )
				)
				( attribute "CDS_SEC" "25"
					( Origin gPackager )
				)
				( attribute "LOCATION" "U2D1"
					( Origin gFrontEnd )
				)
				( attribute "MATERIAL" "IC"
					( Origin gFrontEnd )
				)
				( attribute "PACK_TYPE" "BGA1"
					( Origin gFrontEnd )
				)
				( attribute "PART_NUMBER" "TBD"
					( Origin gFrontEnd )
				)
				( attribute "PHYS_PAGE" "74"
					( Origin gFrontEnd )
				)
				( attribute "ROT" "0"
					( Origin gFrontEnd )
				)
				( attribute "SEC" "25"
					( Origin gFrontEnd )
				)
				( attribute "SEC_TYPE" "BGA1"
					( Origin gFrontEnd )
				)
				( attribute "VER" "25"
					( Origin gFrontEnd )
				)
				( attribute "XY" "(-3200,2625)"
					( Origin gFrontEnd )
				)
				( attribute "CHIPS_PART_NAME" "SKX_EXT_B"
					( Origin gPackager )
				)
				( attribute "CDS_PART_NAME" "SKX_EXT_B_BGA1-IC,TBD"
					( Origin gPackager )
				)
				( objectStatus "U2D1" )
				( pin "vss(774)"
					( attribute "PN" "AL68"
						( Origin gPackager )
					)
					( objectStatus "U2D1.AL68" )
				)
				( pin "vss(775)"
					( attribute "PN" "AL64"
						( Origin gPackager )
					)
					( objectStatus "U2D1.AL64" )
				)
				( pin "vss(776)"
					( attribute "PN" "AL56"
						( Origin gPackager )
					)
					( objectStatus "U2D1.AL56" )
				)
				( pin "vss(777)"
					( attribute "PN" "AL32"
						( Origin gPackager )
					)
					( objectStatus "U2D1.AL32" )
				)
				( pin "vss(778)"
					( attribute "PN" "AL30"
						( Origin gPackager )
					)
					( objectStatus "U2D1.AL30" )
				)
				( pin "vss(779)"
					( attribute "PN" "AL24"
						( Origin gPackager )
					)
					( objectStatus "U2D1.AL24" )
				)
				( pin "vss(780)"
					( attribute "PN" "AL10"
						( Origin gPackager )
					)
					( objectStatus "U2D1.AL10" )
				)
				( pin "vss(781)"
					( attribute "PN" "AL4"
						( Origin gPackager )
					)
					( objectStatus "U2D1.AL4" )
				)
				( pin "vss(782)"
					( attribute "PN" "AK85"
						( Origin gPackager )
					)
					( objectStatus "U2D1.AK85" )
				)
				( pin "vss(783)"
					( attribute "PN" "AK83"
						( Origin gPackager )
					)
					( objectStatus "U2D1.AK83" )
				)
				( pin "vss(784)"
					( attribute "PN" "AK81"
						( Origin gPackager )
					)
					( objectStatus "U2D1.AK81" )
				)
				( pin "vss(785)"
					( attribute "PN" "AK79"
						( Origin gPackager )
					)
					( objectStatus "U2D1.AK79" )
				)
				( pin "vss(786)"
					( attribute "PN" "AK73"
						( Origin gPackager )
					)
					( objectStatus "U2D1.AK73" )
				)
				( pin "vss(787)"
					( attribute "PN" "AK67"
						( Origin gPackager )
					)
					( objectStatus "U2D1.AK67" )
				)
				( pin "vss(788)"
					( attribute "PN" "AK65"
						( Origin gPackager )
					)
					( objectStatus "U2D1.AK65" )
				)
				( pin "vss(789)"
					( attribute "PN" "AK55"
						( Origin gPackager )
					)
					( objectStatus "U2D1.AK55" )
				)
				( pin "vss(790)"
					( attribute "PN" "AK33"
						( Origin gPackager )
					)
					( objectStatus "U2D1.AK33" )
				)
				( pin "vss(791)"
					( attribute "PN" "AK31"
						( Origin gPackager )
					)
					( objectStatus "U2D1.AK31" )
				)
				( pin "vss(792)"
					( attribute "PN" "AK29"
						( Origin gPackager )
					)
					( objectStatus "U2D1.AK29" )
				)
				( pin "vss(793)"
					( attribute "PN" "AK25"
						( Origin gPackager )
					)
					( objectStatus "U2D1.AK25" )
				)
				( pin "vss(794)"
					( attribute "PN" "AK23"
						( Origin gPackager )
					)
					( objectStatus "U2D1.AK23" )
				)
				( pin "vss(795)"
					( attribute "PN" "AK19"
						( Origin gPackager )
					)
					( objectStatus "U2D1.AK19" )
				)
				( pin "vss(796)"
					( attribute "PN" "AK13"
						( Origin gPackager )
					)
					( objectStatus "U2D1.AK13" )
				)
				( pin "vss(797)"
					( attribute "PN" "AK9"
						( Origin gPackager )
					)
					( objectStatus "U2D1.AK9" )
				)
				( pin "vss(798)"
					( attribute "PN" "AJ86"
						( Origin gPackager )
					)
					( objectStatus "U2D1.AJ86" )
				)
				( pin "vss(799)"
					( attribute "PN" "AJ82"
						( Origin gPackager )
					)
					( objectStatus "U2D1.AJ82" )
				)
				( pin "vss(800)"
					( attribute "PN" "AJ78"
						( Origin gPackager )
					)
					( objectStatus "U2D1.AJ78" )
				)
				( pin "vss(801)"
					( attribute "PN" "AJ74"
						( Origin gPackager )
					)
					( objectStatus "U2D1.AJ74" )
				)
				( pin "vss(802)"
					( attribute "PN" "AJ68"
						( Origin gPackager )
					)
					( objectStatus "U2D1.AJ68" )
				)
				( pin "vss(803)"
					( attribute "PN" "AJ66"
						( Origin gPackager )
					)
					( objectStatus "U2D1.AJ66" )
				)
				( pin "vss(804)"
					( attribute "PN" "AJ54"
						( Origin gPackager )
					)
					( objectStatus "U2D1.AJ54" )
				)
				( pin "vss(805)"
					( attribute "PN" "AJ52"
						( Origin gPackager )
					)
					( objectStatus "U2D1.AJ52" )
				)
				( pin "vss(806)"
					( attribute "PN" "AJ50"
						( Origin gPackager )
					)
					( objectStatus "U2D1.AJ50" )
				)
				( pin "vss(807)"
					( attribute "PN" "AJ48"
						( Origin gPackager )
					)
					( objectStatus "U2D1.AJ48" )
				)
				( pin "vss(808)"
					( attribute "PN" "AJ46"
						( Origin gPackager )
					)
					( objectStatus "U2D1.AJ46" )
				)
				( pin "vss(809)"
					( attribute "PN" "AJ34"
						( Origin gPackager )
					)
					( objectStatus "U2D1.AJ34" )
				)
				( pin "vss(810)"
					( attribute "PN" "AJ32"
						( Origin gPackager )
					)
					( objectStatus "U2D1.AJ32" )
				)
				( pin "vss(811)"
					( attribute "PN" "AJ28"
						( Origin gPackager )
					)
					( objectStatus "U2D1.AJ28" )
				)
				( pin "vss(812)"
					( attribute "PN" "AJ26"
						( Origin gPackager )
					)
					( objectStatus "U2D1.AJ26" )
				)
				( pin "vss(813)"
					( attribute "PN" "AJ22"
						( Origin gPackager )
					)
					( objectStatus "U2D1.AJ22" )
				)
				( pin "vss(814)"
					( attribute "PN" "AJ8"
						( Origin gPackager )
					)
					( objectStatus "U2D1.AJ8" )
				)
				( pin "vss(815)"
					( attribute "PN" "AH83"
						( Origin gPackager )
					)
					( objectStatus "U2D1.AH83" )
				)
				( pin "vss(816)"
					( attribute "PN" "AH77"
						( Origin gPackager )
					)
					( objectStatus "U2D1.AH77" )
				)
				( pin "vss(817)"
					( attribute "PN" "AH75"
						( Origin gPackager )
					)
					( objectStatus "U2D1.AH75" )
				)
				( pin "vss(818)"
					( attribute "PN" "AH69"
						( Origin gPackager )
					)
					( objectStatus "U2D1.AH69" )
				)
				( pin "vss(819)"
					( attribute "PN" "AH65"
						( Origin gPackager )
					)
					( objectStatus "U2D1.AH65" )
				)
				( pin "vss(820)"
					( attribute "PN" "AH61"
						( Origin gPackager )
					)
					( objectStatus "U2D1.AH61" )
				)
				( pin "vss(821)"
					( attribute "PN" "AH59"
						( Origin gPackager )
					)
					( objectStatus "U2D1.AH59" )
				)
				( pin "vss(822)"
					( attribute "PN" "AH53"
						( Origin gPackager )
					)
					( objectStatus "U2D1.AH53" )
				)
				( pin "vss(823)"
					( attribute "PN" "AH51"
						( Origin gPackager )
					)
					( objectStatus "U2D1.AH51" )
				)
				( pin "vss(824)"
					( attribute "PN" "AH49"
						( Origin gPackager )
					)
					( objectStatus "U2D1.AH49" )
				)
				( pin "vss(825)"
					( attribute "PN" "AH47"
						( Origin gPackager )
					)
					( objectStatus "U2D1.AH47" )
				)
				( pin "vss(826)"
					( attribute "PN" "AH45"
						( Origin gPackager )
					)
					( objectStatus "U2D1.AH45" )
				)
				( pin "vss(827)"
					( attribute "PN" "AH35"
						( Origin gPackager )
					)
					( objectStatus "U2D1.AH35" )
				)
				( pin "vss(828)"
					( attribute "PN" "AH33"
						( Origin gPackager )
					)
					( objectStatus "U2D1.AH33" )
				)
				( pin "vss(829)"
					( attribute "PN" "AH27"
						( Origin gPackager )
					)
					( objectStatus "U2D1.AH27" )
				)
				( pin "vss(830)"
					( attribute "PN" "AH21"
						( Origin gPackager )
					)
					( objectStatus "U2D1.AH21" )
				)
				( pin "vss(831)"
					( attribute "PN" "AH5"
						( Origin gPackager )
					)
					( objectStatus "U2D1.AH5" )
				)
				( pin "vss(832)"
					( attribute "PN" "AH1"
						( Origin gPackager )
					)
					( objectStatus "U2D1.AH1" )
				)
				( pin "vss(833)"
					( attribute "PN" "AG80"
						( Origin gPackager )
					)
					( objectStatus "U2D1.AG80" )
				)
				( pin "vss(834)"
					( attribute "PN" "AG78"
						( Origin gPackager )
					)
					( objectStatus "U2D1.AG78" )
				)
				( pin "vss(835)"
					( attribute "PN" "AG76"
						( Origin gPackager )
					)
					( objectStatus "U2D1.AG76" )
				)
				( pin "vss(836)"
					( attribute "PN" "AG74"
						( Origin gPackager )
					)
					( objectStatus "U2D1.AG74" )
				)
				( pin "vss(837)"
					( attribute "PN" "AG70"
						( Origin gPackager )
					)
					( objectStatus "U2D1.AG70" )
				)
				( pin "vss(838)"
					( attribute "PN" "AG64"
						( Origin gPackager )
					)
					( objectStatus "U2D1.AG64" )
				)
				( pin "vss(839)"
					( attribute "PN" "AG36"
						( Origin gPackager )
					)
					( objectStatus "U2D1.AG36" )
				)
				( pin "vss(840)"
					( attribute "PN" "AG18"
						( Origin gPackager )
					)
					( objectStatus "U2D1.AG18" )
				)
				( pin "vss(841)"
					( attribute "PN" "AG14"
						( Origin gPackager )
					)
					( objectStatus "U2D1.AG14" )
				)
				( pin "vss(842)"
					( attribute "PN" "AG12"
						( Origin gPackager )
					)
					( objectStatus "U2D1.AG12" )
				)
				( pin "vss(843)"
					( attribute "PN" "AF85"
						( Origin gPackager )
					)
					( objectStatus "U2D1.AF85" )
				)
				( pin "vss(844)"
					( attribute "PN" "AF83"
						( Origin gPackager )
					)
					( objectStatus "U2D1.AF83" )
				)
				( pin "vss(845)"
					( attribute "PN" "AF77"
						( Origin gPackager )
					)
					( objectStatus "U2D1.AF77" )
				)
				( pin "vss(846)"
					( attribute "PN" "AF73"
						( Origin gPackager )
					)
					( objectStatus "U2D1.AF73" )
				)
				( pin "vss(847)"
					( attribute "PN" "AF41"
						( Origin gPackager )
					)
					( objectStatus "U2D1.AF41" )
				)
				( pin "vss(848)"
					( attribute "PN" "AF39"
						( Origin gPackager )
					)
					( objectStatus "U2D1.AF39" )
				)
				( pin "vss(849)"
					( attribute "PN" "AF37"
						( Origin gPackager )
					)
					( objectStatus "U2D1.AF37" )
				)
				( pin "vss(850)"
					( attribute "PN" "AF33"
						( Origin gPackager )
					)
					( objectStatus "U2D1.AF33" )
				)
				( pin "vss(851)"
					( attribute "PN" "AF31"
						( Origin gPackager )
					)
					( objectStatus "U2D1.AF31" )
				)
				( pin "vss(852)"
					( attribute "PN" "AF29"
						( Origin gPackager )
					)
					( objectStatus "U2D1.AF29" )
				)
				( pin "vss(853)"
					( attribute "PN" "AF27"
						( Origin gPackager )
					)
					( objectStatus "U2D1.AF27" )
				)
				( pin "vss(854)"
					( attribute "PN" "AF25"
						( Origin gPackager )
					)
					( objectStatus "U2D1.AF25" )
				)
				( pin "vss(855)"
					( attribute "PN" "AF23"
						( Origin gPackager )
					)
					( objectStatus "U2D1.AF23" )
				)
				( pin "vss(856)"
					( attribute "PN" "AF21"
						( Origin gPackager )
					)
					( objectStatus "U2D1.AF21" )
				)
				( pin "vss(857)"
					( attribute "PN" "AF9"
						( Origin gPackager )
					)
					( objectStatus "U2D1.AF9" )
				)
				( pin "vss(858)"
					( attribute "PN" "AC52"
						( Origin gPackager )
					)
					( objectStatus "U2D1.AC52" )
				)
				( pin "vss(859)"
					( attribute "PN" "AF1"
						( Origin gPackager )
					)
					( objectStatus "U2D1.AF1" )
				)
				( pin "vss(860)"
					( attribute "PN" "AE78"
						( Origin gPackager )
					)
					( objectStatus "U2D1.AE78" )
				)
				( pin "vss(861)"
					( attribute "PN" "AE70"
						( Origin gPackager )
					)
					( objectStatus "U2D1.AE70" )
				)
				( pin "vss(862)"
					( attribute "PN" "AE68"
						( Origin gPackager )
					)
					( objectStatus "U2D1.AE68" )
				)
				( pin "vss(863)"
					( attribute "PN" "AE66"
						( Origin gPackager )
					)
					( objectStatus "U2D1.AE66" )
				)
				( pin "vss(864)"
					( attribute "PN" "AE64"
						( Origin gPackager )
					)
					( objectStatus "U2D1.AE64" )
				)
				( pin "vss(865)"
					( attribute "PN" "AE42"
						( Origin gPackager )
					)
					( objectStatus "U2D1.AE42" )
				)
				( pin "vss(866)"
					( attribute "PN" "AE40"
						( Origin gPackager )
					)
					( objectStatus "U2D1.AE40" )
				)
				( pin "vss(867)"
					( attribute "PN" "AE38"
						( Origin gPackager )
					)
					( objectStatus "U2D1.AE38" )
				)
				( pin "vss(868)"
					( attribute "PN" "AE16"
						( Origin gPackager )
					)
					( objectStatus "U2D1.AE16" )
				)
				( pin "vss(869)"
					( attribute "PN" "AC54"
						( Origin gPackager )
					)
					( objectStatus "U2D1.AC54" )
				)
				( pin "vss(870)"
					( attribute "PN" "AE8"
						( Origin gPackager )
					)
					( objectStatus "U2D1.AE8" )
				)
				( pin "vss(871)"
					( attribute "PN" "AE4"
						( Origin gPackager )
					)
					( objectStatus "U2D1.AE4" )
				)
				( pin "vss(872)"
					( attribute "PN" "AD85"
						( Origin gPackager )
					)
					( objectStatus "U2D1.AD85" )
				)
				( pin "vss(873)"
					( attribute "PN" "AD83"
						( Origin gPackager )
					)
					( objectStatus "U2D1.AD83" )
				)
				( pin "vss(874)"
					( attribute "PN" "AD81"
						( Origin gPackager )
					)
					( objectStatus "U2D1.AD81" )
				)
				( pin "vss(875)"
					( attribute "PN" "AD75"
						( Origin gPackager )
					)
					( objectStatus "U2D1.AD75" )
				)
				( pin "vss(876)"
					( attribute "PN" "AD73"
						( Origin gPackager )
					)
					( objectStatus "U2D1.AD73" )
				)
				( pin "vss(877)"
					( attribute "PN" "AD71"
						( Origin gPackager )
					)
					( objectStatus "U2D1.AD71" )
				)
				( pin "vss(878)"
					( attribute "PN" "AD43"
						( Origin gPackager )
					)
					( objectStatus "U2D1.AD43" )
				)
				( pin "vss(879)"
					( attribute "PN" "AD39"
						( Origin gPackager )
					)
					( objectStatus "U2D1.AD39" )
				)
				( pin "vss(880)"
					( attribute "PN" "AD33"
						( Origin gPackager )
					)
					( objectStatus "U2D1.AD33" )
				)
				( pin "vss(881)"
					( attribute "PN" "AD27"
						( Origin gPackager )
					)
					( objectStatus "U2D1.AD27" )
				)
				( pin "vss(882)"
					( attribute "PN" "AD21"
						( Origin gPackager )
					)
					( objectStatus "U2D1.AD21" )
				)
				( pin "vss(883)"
					( attribute "PN" "AD19"
						( Origin gPackager )
					)
					( objectStatus "U2D1.AD19" )
				)
				( pin "vss(884)"
					( attribute "PN" "AD15"
						( Origin gPackager )
					)
					( objectStatus "U2D1.AD15" )
				)
				( pin "vss(885)"
					( attribute "PN" "AD13"
						( Origin gPackager )
					)
					( objectStatus "U2D1.AD13" )
				)
				( pin "vss(886)"
					( attribute "PN" "AD11"
						( Origin gPackager )
					)
					( objectStatus "U2D1.AD11" )
				)
				( pin "vss(887)"
					( attribute "PN" "AD9"
						( Origin gPackager )
					)
					( objectStatus "U2D1.AD9" )
				)
				( pin "vss(888)"
					( attribute "PN" "AD7"
						( Origin gPackager )
					)
					( objectStatus "U2D1.AD7" )
				)
				( pin "vss(889)"
					( attribute "PN" "AD3"
						( Origin gPackager )
					)
					( objectStatus "U2D1.AD3" )
				)
				( pin "vss(890)"
					( attribute "PN" "AC86"
						( Origin gPackager )
					)
					( objectStatus "U2D1.AC86" )
				)
				( pin "vss(891)"
					( attribute "PN" "AC84"
						( Origin gPackager )
					)
					( objectStatus "U2D1.AC84" )
				)
				( pin "vss(892)"
					( attribute "PN" "AC78"
						( Origin gPackager )
					)
					( objectStatus "U2D1.AC78" )
				)
				( pin "vss(893)"
					( attribute "PN" "AC72"
						( Origin gPackager )
					)
					( objectStatus "U2D1.AC72" )
				)
				( pin "vss(894)"
					( attribute "PN" "AC70"
						( Origin gPackager )
					)
					( objectStatus "U2D1.AC70" )
				)
				( pin "vss(895)"
					( attribute "PN" "AC64"
						( Origin gPackager )
					)
					( objectStatus "U2D1.AC64" )
				)
				( pin "vss(896)"
					( attribute "PN" "AC40"
						( Origin gPackager )
					)
					( objectStatus "U2D1.AC40" )
				)
				( pin "vss(897)"
					( attribute "PN" "AC38"
						( Origin gPackager )
					)
					( objectStatus "U2D1.AC38" )
				)
				( pin "vss(898)"
					( attribute "PN" "AC34"
						( Origin gPackager )
					)
					( objectStatus "U2D1.AC34" )
				)
				( pin "vss(899)"
					( attribute "PN" "AC32"
						( Origin gPackager )
					)
					( objectStatus "U2D1.AC32" )
				)
				( pin "vss(900)"
					( attribute "PN" "AC28"
						( Origin gPackager )
					)
					( objectStatus "U2D1.AC28" )
				)
				( pin "vss(901)"
					( attribute "PN" "AC26"
						( Origin gPackager )
					)
					( objectStatus "U2D1.AC26" )
				)
				( pin "vss(902)"
					( attribute "PN" "AC22"
						( Origin gPackager )
					)
					( objectStatus "U2D1.AC22" )
				)
				( pin "vss(903)"
					( attribute "PN" "AC18"
						( Origin gPackager )
					)
					( objectStatus "U2D1.AC18" )
				)
				( pin "vss(904)"
					( attribute "PN" "AB85"
						( Origin gPackager )
					)
					( objectStatus "U2D1.AB85" )
				)
				( pin "vss(905)"
					( attribute "PN" "AB83"
						( Origin gPackager )
					)
					( objectStatus "U2D1.AB83" )
				)
				( pin "vss(906)"
					( attribute "PN" "AB79"
						( Origin gPackager )
					)
					( objectStatus "U2D1.AB79" )
				)
				( pin "vss(907)"
					( attribute "PN" "AB73"
						( Origin gPackager )
					)
					( objectStatus "U2D1.AB73" )
				)
				( pin "vss(908)"
					( attribute "PN" "AB69"
						( Origin gPackager )
					)
					( objectStatus "U2D1.AB69" )
				)
				( pin "vss(909)"
					( attribute "PN" "AB65"
						( Origin gPackager )
					)
					( objectStatus "U2D1.AB65" )
				)
				( pin "vss(910)"
					( attribute "PN" "AB41"
						( Origin gPackager )
					)
					( objectStatus "U2D1.AB41" )
				)
				( pin "vss(911)"
					( attribute "PN" "AB37"
						( Origin gPackager )
					)
					( objectStatus "U2D1.AB37" )
				)
				( pin "vss(912)"
					( attribute "PN" "AB35"
						( Origin gPackager )
					)
					( objectStatus "U2D1.AB35" )
				)
				( pin "vss(913)"
					( attribute "PN" "AB31"
						( Origin gPackager )
					)
					( objectStatus "U2D1.AB31" )
				)
				( pin "vss(914)"
					( attribute "PN" "AB29"
						( Origin gPackager )
					)
					( objectStatus "U2D1.AB29" )
				)
				( pin "vss(915)"
					( attribute "PN" "AB25"
						( Origin gPackager )
					)
					( objectStatus "U2D1.AB25" )
				)
				( pin "vss(916)"
					( attribute "PN" "AB23"
						( Origin gPackager )
					)
					( objectStatus "U2D1.AB23" )
				)
				( pin "vss(917)"
					( attribute "PN" "AB21"
						( Origin gPackager )
					)
					( objectStatus "U2D1.AB21" )
				)
				( pin "vss(918)"
					( attribute "PN" "AB11"
						( Origin gPackager )
					)
					( objectStatus "U2D1.AB11" )
				)
				( pin "vss(919)"
					( attribute "PN" "AB5"
						( Origin gPackager )
					)
					( objectStatus "U2D1.AB5" )
				)
				( pin "vss(920)"
					( attribute "PN" "AB1"
						( Origin gPackager )
					)
					( objectStatus "U2D1.AB1" )
				)
				( pin "vss(921)"
					( attribute "PN" "AA82"
						( Origin gPackager )
					)
					( objectStatus "U2D1.AA82" )
				)
				( pin "vss(922)"
					( attribute "PN" "AA80"
						( Origin gPackager )
					)
					( objectStatus "U2D1.AA80" )
				)
				( pin "vss(923)"
					( attribute "PN" "AA78"
						( Origin gPackager )
					)
					( objectStatus "U2D1.AA78" )
				)
				( pin "vss(924)"
					( attribute "PN" "AA76"
						( Origin gPackager )
					)
					( objectStatus "U2D1.AA76" )
				)
				( pin "vss(925)"
					( attribute "PN" "AA68"
						( Origin gPackager )
					)
					( objectStatus "U2D1.AA68" )
				)
				( pin "vss(926)"
					( attribute "PN" "AA66"
						( Origin gPackager )
					)
					( objectStatus "U2D1.AA66" )
				)
				( pin "vss(927)"
					( attribute "PN" "AA64"
						( Origin gPackager )
					)
					( objectStatus "U2D1.AA64" )
				)
				( pin "vss(928)"
					( attribute "PN" "AA42"
						( Origin gPackager )
					)
					( objectStatus "U2D1.AA42" )
				)
				( pin "vss(929)"
					( attribute "PN" "AA36"
						( Origin gPackager )
					)
					( objectStatus "U2D1.AA36" )
				)
				( pin "vss(930)"
					( attribute "PN" "AA30"
						( Origin gPackager )
					)
					( objectStatus "U2D1.AA30" )
				)
				( pin "vss(931)"
					( attribute "PN" "AA24"
						( Origin gPackager )
					)
					( objectStatus "U2D1.AA24" )
				)
				( pin "vss(932)"
					( attribute "PN" "AA22"
						( Origin gPackager )
					)
					( objectStatus "U2D1.AA22" )
				)
				( pin "vss(933)"
					( attribute "PN" "AA18"
						( Origin gPackager )
					)
					( objectStatus "U2D1.AA18" )
				)
			)
			( gate "@baseboard_fab2_lib.baseboard_fab2(sch_1):page74_i23"
				( attribute "CDS_LIB" "chpset_lib"
					( Origin gPackager )
				)
				( attribute "CDS_LOCATION" "U2D1"
					( Origin gPackager )
				)
				( attribute "CDS_SEC" "26"
					( Origin gPackager )
				)
				( attribute "LOCATION" "U2D1"
					( Origin gFrontEnd )
				)
				( attribute "MATERIAL" "IC"
					( Origin gFrontEnd )
				)
				( attribute "PACK_TYPE" "BGA1"
					( Origin gFrontEnd )
				)
				( attribute "PART_NUMBER" "TBD"
					( Origin gFrontEnd )
				)
				( attribute "PHYS_PAGE" "74"
					( Origin gFrontEnd )
				)
				( attribute "ROT" "0"
					( Origin gFrontEnd )
				)
				( attribute "SEC" "26"
					( Origin gFrontEnd )
				)
				( attribute "SEC_TYPE" "BGA1"
					( Origin gFrontEnd )
				)
				( attribute "VER" "26"
					( Origin gFrontEnd )
				)
				( attribute "XY" "(-1275,2600)"
					( Origin gFrontEnd )
				)
				( attribute "CHIPS_PART_NAME" "SKX_EXT_B"
					( Origin gPackager )
				)
				( attribute "CDS_PART_NAME" "SKX_EXT_B_BGA1-IC,TBD"
					( Origin gPackager )
				)
				( objectStatus "U2D1" )
				( pin "vss(614)"
					( attribute "PN" "BG72"
						( Origin gPackager )
					)
					( objectStatus "U2D1.BG72" )
				)
				( pin "vss(615)"
					( attribute "PN" "BG24"
						( Origin gPackager )
					)
					( objectStatus "U2D1.BG24" )
				)
				( pin "vss(616)"
					( attribute "PN" "BG22"
						( Origin gPackager )
					)
					( objectStatus "U2D1.BG22" )
				)
				( pin "vss(617)"
					( attribute "PN" "BG10"
						( Origin gPackager )
					)
					( objectStatus "U2D1.BG10" )
				)
				( pin "vss(618)"
					( attribute "PN" "BG8"
						( Origin gPackager )
					)
					( objectStatus "U2D1.BG8" )
				)
				( pin "vss(619)"
					( attribute "PN" "BG6"
						( Origin gPackager )
					)
					( objectStatus "U2D1.BG6" )
				)
				( pin "vss(620)"
					( attribute "PN" "BF71"
						( Origin gPackager )
					)
					( objectStatus "U2D1.BF71" )
				)
				( pin "vss(621)"
					( attribute "PN" "BF69"
						( Origin gPackager )
					)
					( objectStatus "U2D1.BF69" )
				)
				( pin "vss(622)"
					( attribute "PN" "BF67"
						( Origin gPackager )
					)
					( objectStatus "U2D1.BF67" )
				)
				( pin "vss(623)"
					( attribute "PN" "BF65"
						( Origin gPackager )
					)
					( objectStatus "U2D1.BF65" )
				)
				( pin "vss(624)"
					( attribute "PN" "BF63"
						( Origin gPackager )
					)
					( objectStatus "U2D1.BF63" )
				)
				( pin "vss(625)"
					( attribute "PN" "BF25"
						( Origin gPackager )
					)
					( objectStatus "U2D1.BF25" )
				)
				( pin "vss(626)"
					( attribute "PN" "BF19"
						( Origin gPackager )
					)
					( objectStatus "U2D1.BF19" )
				)
				( pin "vss(627)"
					( attribute "PN" "BF17"
						( Origin gPackager )
					)
					( objectStatus "U2D1.BF17" )
				)
				( pin "vss(628)"
					( attribute "PN" "BF15"
						( Origin gPackager )
					)
					( objectStatus "U2D1.BF15" )
				)
				( pin "vss(629)"
					( attribute "PN" "BF9"
						( Origin gPackager )
					)
					( objectStatus "U2D1.BF9" )
				)
				( pin "vss(630)"
					( attribute "PN" "BE70"
						( Origin gPackager )
					)
					( objectStatus "U2D1.BE70" )
				)
				( pin "vss(631)"
					( attribute "PN" "BE68"
						( Origin gPackager )
					)
					( objectStatus "U2D1.BE68" )
				)
				( pin "vss(632)"
					( attribute "PN" "BE66"
						( Origin gPackager )
					)
					( objectStatus "U2D1.BE66" )
				)
				( pin "vss(633)"
					( attribute "PN" "BE64"
						( Origin gPackager )
					)
					( objectStatus "U2D1.BE64" )
				)
				( pin "vss(634)"
					( attribute "PN" "BE26"
						( Origin gPackager )
					)
					( objectStatus "U2D1.BE26" )
				)
				( pin "vss(635)"
					( attribute "PN" "BE10"
						( Origin gPackager )
					)
					( objectStatus "U2D1.BE10" )
				)
				( pin "vss(636)"
					( attribute "PN" "BE8"
						( Origin gPackager )
					)
					( objectStatus "U2D1.BE8" )
				)
				( pin "vss(637)"
					( attribute "PN" "BE6"
						( Origin gPackager )
					)
					( objectStatus "U2D1.BE6" )
				)
				( pin "vss(638)"
					( attribute "PN" "BE4"
						( Origin gPackager )
					)
					( objectStatus "U2D1.BE4" )
				)
				( pin "vss(639)"
					( attribute "PN" "BD71"
						( Origin gPackager )
					)
					( objectStatus "U2D1.BD71" )
				)
				( pin "vss(640)"
					( attribute "PN" "BD63"
						( Origin gPackager )
					)
					( objectStatus "U2D1.BD63" )
				)
				( pin "vss(641)"
					( attribute "PN" "BD27"
						( Origin gPackager )
					)
					( objectStatus "U2D1.BD27" )
				)
				( pin "vss(642)"
					( attribute "PN" "BD21"
						( Origin gPackager )
					)
					( objectStatus "U2D1.BD21" )
				)
				( pin "vss(643)"
					( attribute "PN" "BD15"
						( Origin gPackager )
					)
					( objectStatus "U2D1.BD15" )
				)
				( pin "vss(644)"
					( attribute "PN" "BD11"
						( Origin gPackager )
					)
					( objectStatus "U2D1.BD11" )
				)
				( pin "vss(645)"
					( attribute "PN" "BD5"
						( Origin gPackager )
					)
					( objectStatus "U2D1.BD5" )
				)
				( pin "vss(646)"
					( attribute "PN" "BC82"
						( Origin gPackager )
					)
					( objectStatus "U2D1.BC82" )
				)
				( pin "vss(647)"
					( attribute "PN" "BC80"
						( Origin gPackager )
					)
					( objectStatus "U2D1.BC80" )
				)
				( pin "vss(648)"
					( attribute "PN" "BC78"
						( Origin gPackager )
					)
					( objectStatus "U2D1.BC78" )
				)
				( pin "vss(649)"
					( attribute "PN" "BC76"
						( Origin gPackager )
					)
					( objectStatus "U2D1.BC76" )
				)
				( pin "vss(650)"
					( attribute "PN" "BC74"
						( Origin gPackager )
					)
					( objectStatus "U2D1.BC74" )
				)
				( pin "vss(651)"
					( attribute "PN" "BC72"
						( Origin gPackager )
					)
					( objectStatus "U2D1.BC72" )
				)
				( pin "vss(652)"
					( attribute "PN" "BC70"
						( Origin gPackager )
					)
					( objectStatus "U2D1.BC70" )
				)
				( pin "vss(653)"
					( attribute "PN" "BC16"
						( Origin gPackager )
					)
					( objectStatus "U2D1.BC16" )
				)
				( pin "vss(654)"
					( attribute "PN" "BC12"
						( Origin gPackager )
					)
					( objectStatus "U2D1.BC12" )
				)
				( pin "vss(655)"
					( attribute "PN" "BC8"
						( Origin gPackager )
					)
					( objectStatus "U2D1.BC8" )
				)
				( pin "vss(656)"
					( attribute "PN" "BC4"
						( Origin gPackager )
					)
					( objectStatus "U2D1.BC4" )
				)
				( pin "vss(657)"
					( attribute "PN" "BB83"
						( Origin gPackager )
					)
					( objectStatus "U2D1.BB83" )
				)
				( pin "vss(658)"
					( attribute "PN" "BB81"
						( Origin gPackager )
					)
					( objectStatus "U2D1.BB81" )
				)
				( pin "vss(659)"
					( attribute "PN" "BB79"
						( Origin gPackager )
					)
					( objectStatus "U2D1.BB79" )
				)
				( pin "vss(660)"
					( attribute "PN" "BB77"
						( Origin gPackager )
					)
					( objectStatus "U2D1.BB77" )
				)
				( pin "vss(661)"
					( attribute "PN" "BB75"
						( Origin gPackager )
					)
					( objectStatus "U2D1.BB75" )
				)
				( pin "vss(662)"
					( attribute "PN" "BB73"
						( Origin gPackager )
					)
					( objectStatus "U2D1.BB73" )
				)
				( pin "vss(663)"
					( attribute "PN" "BB69"
						( Origin gPackager )
					)
					( objectStatus "U2D1.BB69" )
				)
				( pin "vss(664)"
					( attribute "PN" "BB63"
						( Origin gPackager )
					)
					( objectStatus "U2D1.BB63" )
				)
				( pin "vss(665)"
					( attribute "PN" "BB23"
						( Origin gPackager )
					)
					( objectStatus "U2D1.BB23" )
				)
				( pin "vss(666)"
					( attribute "PN" "BB19"
						( Origin gPackager )
					)
					( objectStatus "U2D1.BB19" )
				)
				( pin "vss(667)"
					( attribute "PN" "BA84"
						( Origin gPackager )
					)
					( objectStatus "U2D1.BA84" )
				)
				( pin "vss(668)"
					( attribute "PN" "BA80"
						( Origin gPackager )
					)
					( objectStatus "U2D1.BA80" )
				)
				( pin "vss(669)"
					( attribute "PN" "BA74"
						( Origin gPackager )
					)
					( objectStatus "U2D1.BA74" )
				)
				( pin "vss(670)"
					( attribute "PN" "BA68"
						( Origin gPackager )
					)
					( objectStatus "U2D1.BA68" )
				)
				( pin "vss(671)"
					( attribute "PN" "BA62"
						( Origin gPackager )
					)
					( objectStatus "U2D1.BA62" )
				)
				( pin "vss(672)"
					( attribute "PN" "BA12"
						( Origin gPackager )
					)
					( objectStatus "U2D1.BA12" )
				)
				( pin "vss(673)"
					( attribute "PN" "BA6"
						( Origin gPackager )
					)
					( objectStatus "U2D1.BA6" )
				)
				( pin "vss(674)"
					( attribute "PN" "BA2"
						( Origin gPackager )
					)
					( objectStatus "U2D1.BA2" )
				)
				( pin "vss(675)"
					( attribute "PN" "AY81"
						( Origin gPackager )
					)
					( objectStatus "U2D1.AY81" )
				)
				( pin "vss(676)"
					( attribute "PN" "AY79"
						( Origin gPackager )
					)
					( objectStatus "U2D1.AY79" )
				)
				( pin "vss(677)"
					( attribute "PN" "AY63"
						( Origin gPackager )
					)
					( objectStatus "U2D1.AY63" )
				)
				( pin "vss(678)"
					( attribute "PN" "AY25"
						( Origin gPackager )
					)
					( objectStatus "U2D1.AY25" )
				)
				( pin "vss(679)"
					( attribute "PN" "AY23"
						( Origin gPackager )
					)
					( objectStatus "U2D1.AY23" )
				)
				( pin "vss(680)"
					( attribute "PN" "AY21"
						( Origin gPackager )
					)
					( objectStatus "U2D1.AY21" )
				)
				( pin "vss(681)"
					( attribute "PN" "AY17"
						( Origin gPackager )
					)
					( objectStatus "U2D1.AY17" )
				)
				( pin "vss(682)"
					( attribute "PN" "AY15"
						( Origin gPackager )
					)
					( objectStatus "U2D1.AY15" )
				)
				( pin "vss(683)"
					( attribute "PN" "AY5"
						( Origin gPackager )
					)
					( objectStatus "U2D1.AY5" )
				)
				( pin "vss(684)"
					( attribute "PN" "AW84"
						( Origin gPackager )
					)
					( objectStatus "U2D1.AW84" )
				)
				( pin "vss(685)"
					( attribute "PN" "AW82"
						( Origin gPackager )
					)
					( objectStatus "U2D1.AW82" )
				)
				( pin "vss(686)"
					( attribute "PN" "AW78"
						( Origin gPackager )
					)
					( objectStatus "U2D1.AW78" )
				)
				( pin "vss(687)"
					( attribute "PN" "AW74"
						( Origin gPackager )
					)
					( objectStatus "U2D1.AW74" )
				)
				( pin "vss(688)"
					( attribute "PN" "AW72"
						( Origin gPackager )
					)
					( objectStatus "U2D1.AW72" )
				)
				( pin "vss(689)"
					( attribute "PN" "AW70"
						( Origin gPackager )
					)
					( objectStatus "U2D1.AW70" )
				)
				( pin "vss(690)"
					( attribute "PN" "AW68"
						( Origin gPackager )
					)
					( objectStatus "U2D1.AW68" )
				)
				( pin "vss(691)"
					( attribute "PN" "AW66"
						( Origin gPackager )
					)
					( objectStatus "U2D1.AW66" )
				)
				( pin "vss(692)"
					( attribute "PN" "AW62"
						( Origin gPackager )
					)
					( objectStatus "U2D1.AW62" )
				)
				( pin "vss(693)"
					( attribute "PN" "AW10"
						( Origin gPackager )
					)
					( objectStatus "U2D1.AW10" )
				)
				( pin "vss(694)"
					( attribute "PN" "AW2"
						( Origin gPackager )
					)
					( objectStatus "U2D1.AW2" )
				)
				( pin "vss(695)"
					( attribute "PN" "AV83"
						( Origin gPackager )
					)
					( objectStatus "U2D1.AV83" )
				)
				( pin "vss(696)"
					( attribute "PN" "AV75"
						( Origin gPackager )
					)
					( objectStatus "U2D1.AV75" )
				)
				( pin "vss(697)"
					( attribute "PN" "AV67"
						( Origin gPackager )
					)
					( objectStatus "U2D1.AV67" )
				)
				( pin "vss(698)"
					( attribute "PN" "AV65"
						( Origin gPackager )
					)
					( objectStatus "U2D1.AV65" )
				)
				( pin "vss(699)"
					( attribute "PN" "AV63"
						( Origin gPackager )
					)
					( objectStatus "U2D1.AV63" )
				)
				( pin "vss(700)"
					( attribute "PN" "AV25"
						( Origin gPackager )
					)
					( objectStatus "U2D1.AV25" )
				)
				( pin "vss(701)"
					( attribute "PN" "AV23"
						( Origin gPackager )
					)
					( objectStatus "U2D1.AV23" )
				)
				( pin "vss(702)"
					( attribute "PN" "AV19"
						( Origin gPackager )
					)
					( objectStatus "U2D1.AV19" )
				)
				( pin "vss(703)"
					( attribute "PN" "AV13"
						( Origin gPackager )
					)
					( objectStatus "U2D1.AV13" )
				)
				( pin "vss(704)"
					( attribute "PN" "AV11"
						( Origin gPackager )
					)
					( objectStatus "U2D1.AV11" )
				)
				( pin "vss(705)"
					( attribute "PN" "AV7"
						( Origin gPackager )
					)
					( objectStatus "U2D1.AV7" )
				)
				( pin "vss(706)"
					( attribute "PN" "AV3"
						( Origin gPackager )
					)
					( objectStatus "U2D1.AV3" )
				)
				( pin "vss(707)"
					( attribute "PN" "AV1"
						( Origin gPackager )
					)
					( objectStatus "U2D1.AV1" )
				)
				( pin "vss(708)"
					( attribute "PN" "AU86"
						( Origin gPackager )
					)
					( objectStatus "U2D1.AU86" )
				)
				( pin "vss(709)"
					( attribute "PN" "AU84"
						( Origin gPackager )
					)
					( objectStatus "U2D1.AU84" )
				)
				( pin "vss(710)"
					( attribute "PN" "AU80"
						( Origin gPackager )
					)
					( objectStatus "U2D1.AU80" )
				)
				( pin "vss(711)"
					( attribute "PN" "AU78"
						( Origin gPackager )
					)
					( objectStatus "U2D1.AU78" )
				)
				( pin "vss(712)"
					( attribute "PN" "AU76"
						( Origin gPackager )
					)
					( objectStatus "U2D1.AU76" )
				)
				( pin "vss(713)"
					( attribute "PN" "AU74"
						( Origin gPackager )
					)
					( objectStatus "U2D1.AU74" )
				)
				( pin "vss(714)"
					( attribute "PN" "AU68"
						( Origin gPackager )
					)
					( objectStatus "U2D1.AU68" )
				)
				( pin "vss(715)"
					( attribute "PN" "AU64"
						( Origin gPackager )
					)
					( objectStatus "U2D1.AU64" )
				)
				( pin "vss(716)"
					( attribute "PN" "AU62"
						( Origin gPackager )
					)
					( objectStatus "U2D1.AU62" )
				)
				( pin "vss(717)"
					( attribute "PN" "AU28"
						( Origin gPackager )
					)
					( objectStatus "U2D1.AU28" )
				)
				( pin "vss(718)"
					( attribute "PN" "AU26"
						( Origin gPackager )
					)
					( objectStatus "U2D1.AU26" )
				)
				( pin "vss(719)"
					( attribute "PN" "AU6"
						( Origin gPackager )
					)
					( objectStatus "U2D1.AU6" )
				)
				( pin "vss(720)"
					( attribute "PN" "AU2"
						( Origin gPackager )
					)
					( objectStatus "U2D1.AU2" )
				)
				( pin "vss(721)"
					( attribute "PN" "AT85"
						( Origin gPackager )
					)
					( objectStatus "U2D1.AT85" )
				)
				( pin "vss(722)"
					( attribute "PN" "AT83"
						( Origin gPackager )
					)
					( objectStatus "U2D1.AT83" )
				)
				( pin "vss(723)"
					( attribute "PN" "AT77"
						( Origin gPackager )
					)
					( objectStatus "U2D1.AT77" )
				)
				( pin "vss(724)"
					( attribute "PN" "AT73"
						( Origin gPackager )
					)
					( objectStatus "U2D1.AT73" )
				)
				( pin "vss(725)"
					( attribute "PN" "AT69"
						( Origin gPackager )
					)
					( objectStatus "U2D1.AT69" )
				)
				( pin "vss(726)"
					( attribute "PN" "AT63"
						( Origin gPackager )
					)
					( objectStatus "U2D1.AT63" )
				)
				( pin "vss(727)"
					( attribute "PN" "AT61"
						( Origin gPackager )
					)
					( objectStatus "U2D1.AT61" )
				)
				( pin "vss(728)"
					( attribute "PN" "AT27"
						( Origin gPackager )
					)
					( objectStatus "U2D1.AT27" )
				)
				( pin "vss(729)"
					( attribute "PN" "AT21"
						( Origin gPackager )
					)
					( objectStatus "U2D1.AT21" )
				)
				( pin "vss(730)"
					( attribute "PN" "AT17"
						( Origin gPackager )
					)
					( objectStatus "U2D1.AT17" )
				)
				( pin "vss(731)"
					( attribute "PN" "AT15"
						( Origin gPackager )
					)
					( objectStatus "U2D1.AT15" )
				)
				( pin "vss(732)"
					( attribute "PN" "P63"
						( Origin gPackager )
					)
					( objectStatus "U2D1.P63" )
				)
				( pin "vss(733)"
					( attribute "PN" "AC48"
						( Origin gPackager )
					)
					( objectStatus "U2D1.AC48" )
				)
				( pin "vss(734)"
					( attribute "PN" "AR78"
						( Origin gPackager )
					)
					( objectStatus "U2D1.AR78" )
				)
				( pin "vss(735)"
					( attribute "PN" "AR72"
						( Origin gPackager )
					)
					( objectStatus "U2D1.AR72" )
				)
				( pin "vss(736)"
					( attribute "PN" "AR60"
						( Origin gPackager )
					)
					( objectStatus "U2D1.AR60" )
				)
				( pin "vss(737)"
					( attribute "PN" "AR30"
						( Origin gPackager )
					)
					( objectStatus "U2D1.AR30" )
				)
				( pin "vss(738)"
					( attribute "PN" "AR24"
						( Origin gPackager )
					)
					( objectStatus "U2D1.AR24" )
				)
				( pin "vss(739)"
					( attribute "PN" "AR10"
						( Origin gPackager )
					)
					( objectStatus "U2D1.AR10" )
				)
				( pin "vss(740)"
					( attribute "PN" "AP85"
						( Origin gPackager )
					)
					( objectStatus "U2D1.AP85" )
				)
				( pin "vss(741)"
					( attribute "PN" "AP83"
						( Origin gPackager )
					)
					( objectStatus "U2D1.AP83" )
				)
				( pin "vss(742)"
					( attribute "PN" "AP81"
						( Origin gPackager )
					)
					( objectStatus "U2D1.AP81" )
				)
				( pin "vss(743)"
					( attribute "PN" "AP75"
						( Origin gPackager )
					)
					( objectStatus "U2D1.AP75" )
				)
				( pin "vss(744)"
					( attribute "PN" "AP73"
						( Origin gPackager )
					)
					( objectStatus "U2D1.AP73" )
				)
				( pin "vss(745)"
					( attribute "PN" "AP69"
						( Origin gPackager )
					)
					( objectStatus "U2D1.AP69" )
				)
				( pin "vss(746)"
					( attribute "PN" "AP67"
						( Origin gPackager )
					)
					( objectStatus "U2D1.AP67" )
				)
				( pin "vss(747)"
					( attribute "PN" "AP65"
						( Origin gPackager )
					)
					( objectStatus "U2D1.AP65" )
				)
				( pin "vss(748)"
					( attribute "PN" "AP63"
						( Origin gPackager )
					)
					( objectStatus "U2D1.AP63" )
				)
				( pin "vss(749)"
					( attribute "PN" "AP59"
						( Origin gPackager )
					)
					( objectStatus "U2D1.AP59" )
				)
				( pin "vss(750)"
					( attribute "PN" "AP31"
						( Origin gPackager )
					)
					( objectStatus "U2D1.AP31" )
				)
				( pin "vss(751)"
					( attribute "PN" "AP19"
						( Origin gPackager )
					)
					( objectStatus "U2D1.AP19" )
				)
				( pin "vss(752)"
					( attribute "PN" "AP13"
						( Origin gPackager )
					)
					( objectStatus "U2D1.AP13" )
				)
				( pin "vss(753)"
					( attribute "PN" "AP9"
						( Origin gPackager )
					)
					( objectStatus "U2D1.AP9" )
				)
				( pin "vss(754)"
					( attribute "PN" "AP5"
						( Origin gPackager )
					)
					( objectStatus "U2D1.AP5" )
				)
				( pin "vss(755)"
					( attribute "PN" "AN78"
						( Origin gPackager )
					)
					( objectStatus "U2D1.AN78" )
				)
				( pin "vss(756)"
					( attribute "PN" "AN58"
						( Origin gPackager )
					)
					( objectStatus "U2D1.AN58" )
				)
				( pin "vss(757)"
					( attribute "PN" "AN28"
						( Origin gPackager )
					)
					( objectStatus "U2D1.AN28" )
				)
				( pin "vss(758)"
					( attribute "PN" "AN6"
						( Origin gPackager )
					)
					( objectStatus "U2D1.AN6" )
				)
				( pin "vss(759)"
					( attribute "PN" "AN2"
						( Origin gPackager )
					)
					( objectStatus "U2D1.AN2" )
				)
				( pin "vss(760)"
					( attribute "PN" "AM83"
						( Origin gPackager )
					)
					( objectStatus "U2D1.AM83" )
				)
				( pin "vss(761)"
					( attribute "PN" "AM79"
						( Origin gPackager )
					)
					( objectStatus "U2D1.AM79" )
				)
				( pin "vss(762)"
					( attribute "PN" "AM73"
						( Origin gPackager )
					)
					( objectStatus "U2D1.AM73" )
				)
				( pin "vss(763)"
					( attribute "PN" "AM69"
						( Origin gPackager )
					)
					( objectStatus "U2D1.AM69" )
				)
				( pin "vss(764)"
					( attribute "PN" "AM63"
						( Origin gPackager )
					)
					( objectStatus "U2D1.AM63" )
				)
				( pin "vss(765)"
					( attribute "PN" "AM57"
						( Origin gPackager )
					)
					( objectStatus "U2D1.AM57" )
				)
				( pin "vss(766)"
					( attribute "PN" "AM31"
						( Origin gPackager )
					)
					( objectStatus "U2D1.AM31" )
				)
				( pin "vss(767)"
					( attribute "PN" "AC50"
						( Origin gPackager )
					)
					( objectStatus "U2D1.AC50" )
				)
				( pin "vss(768)"
					( attribute "PN" "AM1"
						( Origin gPackager )
					)
					( objectStatus "U2D1.AM1" )
				)
				( pin "vss(769)"
					( attribute "PN" "AL86"
						( Origin gPackager )
					)
					( objectStatus "U2D1.AL86" )
				)
				( pin "vss(770)"
					( attribute "PN" "AL82"
						( Origin gPackager )
					)
					( objectStatus "U2D1.AL82" )
				)
				( pin "vss(771)"
					( attribute "PN" "AL80"
						( Origin gPackager )
					)
					( objectStatus "U2D1.AL80" )
				)
				( pin "vss(772)"
					( attribute "PN" "AL78"
						( Origin gPackager )
					)
					( objectStatus "U2D1.AL78" )
				)
				( pin "vss(773)"
					( attribute "PN" "AL76"
						( Origin gPackager )
					)
					( objectStatus "U2D1.AL76" )
				)
			)
			( gate "@baseboard_fab2_lib.baseboard_fab2(sch_1):page75_i17"
				( attribute "CDS_LIB" "chpset_lib"
					( Origin gPackager )
				)
				( attribute "CDS_LOCATION" "U2D1"
					( Origin gPackager )
				)
				( attribute "CDS_SEC" "27"
					( Origin gPackager )
				)
				( attribute "LOCATION" "U2D1"
					( Origin gFrontEnd )
				)
				( attribute "MATERIAL" "IC"
					( Origin gFrontEnd )
				)
				( attribute "PACK_TYPE" "BGA1"
					( Origin gFrontEnd )
				)
				( attribute "PART_NUMBER" "TBD"
					( Origin gFrontEnd )
				)
				( attribute "PHYS_PAGE" "75"
					( Origin gFrontEnd )
				)
				( attribute "ROT" "0"
					( Origin gFrontEnd )
				)
				( attribute "SEC" "27"
					( Origin gFrontEnd )
				)
				( attribute "SEC_TYPE" "BGA1"
					( Origin gFrontEnd )
				)
				( attribute "VER" "27"
					( Origin gFrontEnd )
				)
				( attribute "XY" "(-6725,2525)"
					( Origin gFrontEnd )
				)
				( attribute "CHIPS_PART_NAME" "SKX_EXT_B"
					( Origin gPackager )
				)
				( attribute "CDS_PART_NAME" "SKX_EXT_B_BGA1-IC,TBD"
					( Origin gPackager )
				)
				( objectStatus "U2D1" )
				( pin "vss(454)"
					( attribute "PN" "P49"
						( Origin gPackager )
					)
					( objectStatus "U2D1.P49" )
				)
				( pin "vss(455)"
					( attribute "PN" "CJ12"
						( Origin gPackager )
					)
					( objectStatus "U2D1.CJ12" )
				)
				( pin "vss(456)"
					( attribute "PN" "CJ10"
						( Origin gPackager )
					)
					( objectStatus "U2D1.CJ10" )
				)
				( pin "vss(457)"
					( attribute "PN" "CJ8"
						( Origin gPackager )
					)
					( objectStatus "U2D1.CJ8" )
				)
				( pin "vss(458)"
					( attribute "PN" "CJ6"
						( Origin gPackager )
					)
					( objectStatus "U2D1.CJ6" )
				)
				( pin "vss(459)"
					( attribute "PN" "CJ2"
						( Origin gPackager )
					)
					( objectStatus "U2D1.CJ2" )
				)
				( pin "vss(460)"
					( attribute "PN" "CH83"
						( Origin gPackager )
					)
					( objectStatus "U2D1.CH83" )
				)
				( pin "vss(461)"
					( attribute "PN" "CH81"
						( Origin gPackager )
					)
					( objectStatus "U2D1.CH81" )
				)
				( pin "vss(462)"
					( attribute "PN" "CH79"
						( Origin gPackager )
					)
					( objectStatus "U2D1.CH79" )
				)
				( pin "vss(463)"
					( attribute "PN" "CH73"
						( Origin gPackager )
					)
					( objectStatus "U2D1.CH73" )
				)
				( pin "vss(464)"
					( attribute "PN" "CH67"
						( Origin gPackager )
					)
					( objectStatus "U2D1.CH67" )
				)
				( pin "vss(465)"
					( attribute "PN" "CH63"
						( Origin gPackager )
					)
					( objectStatus "U2D1.CH63" )
				)
				( pin "vss(466)"
					( attribute "PN" "CH19"
						( Origin gPackager )
					)
					( objectStatus "U2D1.CH19" )
				)
				( pin "vss(467)"
					( attribute "PN" "CH15"
						( Origin gPackager )
					)
					( objectStatus "U2D1.CH15" )
				)
				( pin "vss(468)"
					( attribute "PN" "CH3"
						( Origin gPackager )
					)
					( objectStatus "U2D1.CH3" )
				)
				( pin "vss(469)"
					( attribute "PN" "CH1"
						( Origin gPackager )
					)
					( objectStatus "U2D1.CH1" )
				)
				( pin "vss(470)"
					( attribute "PN" "CG80"
						( Origin gPackager )
					)
					( objectStatus "U2D1.CG80" )
				)
				( pin "vss(471)"
					( attribute "PN" "CG72"
						( Origin gPackager )
					)
					( objectStatus "U2D1.CG72" )
				)
				( pin "vss(472)"
					( attribute "PN" "CG68"
						( Origin gPackager )
					)
					( objectStatus "U2D1.CG68" )
				)
				( pin "vss(473)"
					( attribute "PN" "CG62"
						( Origin gPackager )
					)
					( objectStatus "U2D1.CG62" )
				)
				( pin "vss(474)"
					( attribute "PN" "CG22"
						( Origin gPackager )
					)
					( objectStatus "U2D1.CG22" )
				)
				( pin "vss(475)"
					( attribute "PN" "CG18"
						( Origin gPackager )
					)
					( objectStatus "U2D1.CG18" )
				)
				( pin "vss(476)"
					( attribute "PN" "P51"
						( Origin gPackager )
					)
					( objectStatus "U2D1.P51" )
				)
				( pin "vss(477)"
					( attribute "PN" "CF83"
						( Origin gPackager )
					)
					( objectStatus "U2D1.CF83" )
				)
				( pin "vss(478)"
					( attribute "PN" "CF77"
						( Origin gPackager )
					)
					( objectStatus "U2D1.CF77" )
				)
				( pin "vss(479)"
					( attribute "PN" "CF71"
						( Origin gPackager )
					)
					( objectStatus "U2D1.CF71" )
				)
				( pin "vss(480)"
					( attribute "PN" "CF69"
						( Origin gPackager )
					)
					( objectStatus "U2D1.CF69" )
				)
				( pin "vss(481)"
					( attribute "PN" "CF63"
						( Origin gPackager )
					)
					( objectStatus "U2D1.CF63" )
				)
				( pin "vss(482)"
					( attribute "PN" "CF9"
						( Origin gPackager )
					)
					( objectStatus "U2D1.CF9" )
				)
				( pin "vss(483)"
					( attribute "PN" "P53"
						( Origin gPackager )
					)
					( objectStatus "U2D1.P53" )
				)
				( pin "vss(484)"
					( attribute "PN" "CE82"
						( Origin gPackager )
					)
					( objectStatus "U2D1.CE82" )
				)
				( pin "vss(485)"
					( attribute "PN" "CE70"
						( Origin gPackager )
					)
					( objectStatus "U2D1.CE70" )
				)
				( pin "vss(486)"
					( attribute "PN" "CE62"
						( Origin gPackager )
					)
					( objectStatus "U2D1.CE62" )
				)
				( pin "vss(487)"
					( attribute "PN" "CE26"
						( Origin gPackager )
					)
					( objectStatus "U2D1.CE26" )
				)
				( pin "vss(488)"
					( attribute "PN" "CE20"
						( Origin gPackager )
					)
					( objectStatus "U2D1.CE20" )
				)
				( pin "vss(489)"
					( attribute "PN" "CE14"
						( Origin gPackager )
					)
					( objectStatus "U2D1.CE14" )
				)
				( pin "vss(490)"
					( attribute "PN" "CE10"
						( Origin gPackager )
					)
					( objectStatus "U2D1.CE10" )
				)
				( pin "vss(491)"
					( attribute "PN" "CD81"
						( Origin gPackager )
					)
					( objectStatus "U2D1.CD81" )
				)
				( pin "vss(492)"
					( attribute "PN" "CD79"
						( Origin gPackager )
					)
					( objectStatus "U2D1.CD79" )
				)
				( pin "vss(493)"
					( attribute "PN" "CD77"
						( Origin gPackager )
					)
					( objectStatus "U2D1.CD77" )
				)
				( pin "vss(494)"
					( attribute "PN" "CD75"
						( Origin gPackager )
					)
					( objectStatus "U2D1.CD75" )
				)
				( pin "vss(495)"
					( attribute "PN" "CD73"
						( Origin gPackager )
					)
					( objectStatus "U2D1.CD73" )
				)
				( pin "vss(496)"
					( attribute "PN" "CD63"
						( Origin gPackager )
					)
					( objectStatus "U2D1.CD63" )
				)
				( pin "vss(497)"
					( attribute "PN" "CD13"
						( Origin gPackager )
					)
					( objectStatus "U2D1.CD13" )
				)
				( pin "vss(498)"
					( attribute "PN" "CD5"
						( Origin gPackager )
					)
					( objectStatus "U2D1.CD5" )
				)
				( pin "vss(499)"
					( attribute "PN" "CC82"
						( Origin gPackager )
					)
					( objectStatus "U2D1.CC82" )
				)
				( pin "vss(500)"
					( attribute "PN" "CC80"
						( Origin gPackager )
					)
					( objectStatus "U2D1.CC80" )
				)
				( pin "vss(501)"
					( attribute "PN" "CC78"
						( Origin gPackager )
					)
					( objectStatus "U2D1.CC78" )
				)
				( pin "vss(502)"
					( attribute "PN" "CC76"
						( Origin gPackager )
					)
					( objectStatus "U2D1.CC76" )
				)
				( pin "vss(503)"
					( attribute "PN" "CC74"
						( Origin gPackager )
					)
					( objectStatus "U2D1.CC74" )
				)
				( pin "vss(504)"
					( attribute "PN" "CC72"
						( Origin gPackager )
					)
					( objectStatus "U2D1.CC72" )
				)
				( pin "vss(505)"
					( attribute "PN" "CC64"
						( Origin gPackager )
					)
					( objectStatus "U2D1.CC64" )
				)
				( pin "vss(506)"
					( attribute "PN" "CC24"
						( Origin gPackager )
					)
					( objectStatus "U2D1.CC24" )
				)
				( pin "vss(507)"
					( attribute "PN" "CC18"
						( Origin gPackager )
					)
					( objectStatus "U2D1.CC18" )
				)
				( pin "vss(508)"
					( attribute "PN" "CC16"
						( Origin gPackager )
					)
					( objectStatus "U2D1.CC16" )
				)
				( pin "vss(509)"
					( attribute "PN" "CC4"
						( Origin gPackager )
					)
					( objectStatus "U2D1.CC4" )
				)
				( pin "vss(510)"
					( attribute "PN" "CB71"
						( Origin gPackager )
					)
					( objectStatus "U2D1.CB71" )
				)
				( pin "vss(511)"
					( attribute "PN" "CB63"
						( Origin gPackager )
					)
					( objectStatus "U2D1.CB63" )
				)
				( pin "vss(512)"
					( attribute "PN" "CB27"
						( Origin gPackager )
					)
					( objectStatus "U2D1.CB27" )
				)
				( pin "vss(513)"
					( attribute "PN" "CB9"
						( Origin gPackager )
					)
					( objectStatus "U2D1.CB9" )
				)
				( pin "vss(514)"
					( attribute "PN" "CB7"
						( Origin gPackager )
					)
					( objectStatus "U2D1.CB7" )
				)
				( pin "vss(515)"
					( attribute "PN" "CA70"
						( Origin gPackager )
					)
					( objectStatus "U2D1.CA70" )
				)
				( pin "vss(516)"
					( attribute "PN" "CA68"
						( Origin gPackager )
					)
					( objectStatus "U2D1.CA68" )
				)
				( pin "vss(517)"
					( attribute "PN" "CA66"
						( Origin gPackager )
					)
					( objectStatus "U2D1.CA66" )
				)
				( pin "vss(518)"
					( attribute "PN" "CA64"
						( Origin gPackager )
					)
					( objectStatus "U2D1.CA64" )
				)
				( pin "vss(519)"
					( attribute "PN" "CA26"
						( Origin gPackager )
					)
					( objectStatus "U2D1.CA26" )
				)
				( pin "vss(520)"
					( attribute "PN" "CA18"
						( Origin gPackager )
					)
					( objectStatus "U2D1.CA18" )
				)
				( pin "vss(521)"
					( attribute "PN" "CA14"
						( Origin gPackager )
					)
					( objectStatus "U2D1.CA14" )
				)
				( pin "vss(522)"
					( attribute "PN" "CA10"
						( Origin gPackager )
					)
					( objectStatus "U2D1.CA10" )
				)
				( pin "vss(523)"
					( attribute "PN" "CA8"
						( Origin gPackager )
					)
					( objectStatus "U2D1.CA8" )
				)
				( pin "vss(524)"
					( attribute "PN" "CA6"
						( Origin gPackager )
					)
					( objectStatus "U2D1.CA6" )
				)
				( pin "vss(525)"
					( attribute "PN" "CA2"
						( Origin gPackager )
					)
					( objectStatus "U2D1.CA2" )
				)
				( pin "vss(526)"
					( attribute "PN" "BY71"
						( Origin gPackager )
					)
					( objectStatus "U2D1.BY71" )
				)
				( pin "vss(527)"
					( attribute "PN" "BY69"
						( Origin gPackager )
					)
					( objectStatus "U2D1.BY69" )
				)
				( pin "vss(528)"
					( attribute "PN" "BY67"
						( Origin gPackager )
					)
					( objectStatus "U2D1.BY67" )
				)
				( pin "vss(529)"
					( attribute "PN" "BY65"
						( Origin gPackager )
					)
					( objectStatus "U2D1.BY65" )
				)
				( pin "vss(530)"
					( attribute "PN" "BY63"
						( Origin gPackager )
					)
					( objectStatus "U2D1.BY63" )
				)
				( pin "vss(531)"
					( attribute "PN" "BY23"
						( Origin gPackager )
					)
					( objectStatus "U2D1.BY23" )
				)
				( pin "vss(532)"
					( attribute "PN" "BY13"
						( Origin gPackager )
					)
					( objectStatus "U2D1.BY13" )
				)
				( pin "vss(533)"
					( attribute "PN" "BY11"
						( Origin gPackager )
					)
					( objectStatus "U2D1.BY11" )
				)
				( pin "vss(534)"
					( attribute "PN" "BW82"
						( Origin gPackager )
					)
					( objectStatus "U2D1.BW82" )
				)
				( pin "vss(535)"
					( attribute "PN" "BW80"
						( Origin gPackager )
					)
					( objectStatus "U2D1.BW80" )
				)
				( pin "vss(536)"
					( attribute "PN" "BW78"
						( Origin gPackager )
					)
					( objectStatus "U2D1.BW78" )
				)
				( pin "vss(537)"
					( attribute "PN" "BW76"
						( Origin gPackager )
					)
					( objectStatus "U2D1.BW76" )
				)
				( pin "vss(538)"
					( attribute "PN" "BW74"
						( Origin gPackager )
					)
					( objectStatus "U2D1.BW74" )
				)
				( pin "vss(539)"
					( attribute "PN" "BW72"
						( Origin gPackager )
					)
					( objectStatus "U2D1.BW72" )
				)
				( pin "vss(540)"
					( attribute "PN" "BW26"
						( Origin gPackager )
					)
					( objectStatus "U2D1.BW26" )
				)
				( pin "vss(541)"
					( attribute "PN" "BW18"
						( Origin gPackager )
					)
					( objectStatus "U2D1.BW18" )
				)
				( pin "vss(542)"
					( attribute "PN" "BW16"
						( Origin gPackager )
					)
					( objectStatus "U2D1.BW16" )
				)
				( pin "vss(543)"
					( attribute "PN" "BW14"
						( Origin gPackager )
					)
					( objectStatus "U2D1.BW14" )
				)
				( pin "vss(544)"
					( attribute "PN" "BW12"
						( Origin gPackager )
					)
					( objectStatus "U2D1.BW12" )
				)
				( pin "vss(545)"
					( attribute "PN" "P55"
						( Origin gPackager )
					)
					( objectStatus "U2D1.P55" )
				)
				( pin "vss(546)"
					( attribute "PN" "BW6"
						( Origin gPackager )
					)
					( objectStatus "U2D1.BW6" )
				)
				( pin "vss(547)"
					( attribute "PN" "BV25"
						( Origin gPackager )
					)
					( objectStatus "U2D1.BV25" )
				)
				( pin "vss(548)"
					( attribute "PN" "BV17"
						( Origin gPackager )
					)
					( objectStatus "U2D1.BV17" )
				)
				( pin "vss(549)"
					( attribute "PN" "BU10"
						( Origin gPackager )
					)
					( objectStatus "U2D1.BU10" )
				)
				( pin "vss(550)"
					( attribute "PN" "BV5"
						( Origin gPackager )
					)
					( objectStatus "U2D1.BV5" )
				)
				( pin "vss(551)"
					( attribute "PN" "BU8"
						( Origin gPackager )
					)
					( objectStatus "U2D1.BU8" )
				)
				( pin "vss(552)"
					( attribute "PN" "BT25"
						( Origin gPackager )
					)
					( objectStatus "U2D1.BT25" )
				)
				( pin "vss(553)"
					( attribute "PN" "BT23"
						( Origin gPackager )
					)
					( objectStatus "U2D1.BT23" )
				)
				( pin "vss(554)"
					( attribute "PN" "BT21"
						( Origin gPackager )
					)
					( objectStatus "U2D1.BT21" )
				)
				( pin "vss(555)"
					( attribute "PN" "BT5"
						( Origin gPackager )
					)
					( objectStatus "U2D1.BT5" )
				)
				( pin "vss(556)"
					( attribute "PN" "BT3"
						( Origin gPackager )
					)
					( objectStatus "U2D1.BT3" )
				)
				( pin "vss(557)"
					( attribute "PN" "BR82"
						( Origin gPackager )
					)
					( objectStatus "U2D1.BR82" )
				)
				( pin "vss(558)"
					( attribute "PN" "BR80"
						( Origin gPackager )
					)
					( objectStatus "U2D1.BR80" )
				)
				( pin "vss(559)"
					( attribute "PN" "BR78"
						( Origin gPackager )
					)
					( objectStatus "U2D1.BR78" )
				)
				( pin "vss(560)"
					( attribute "PN" "BR76"
						( Origin gPackager )
					)
					( objectStatus "U2D1.BR76" )
				)
				( pin "vss(561)"
					( attribute "PN" "BR74"
						( Origin gPackager )
					)
					( objectStatus "U2D1.BR74" )
				)
				( pin "vss(562)"
					( attribute "PN" "BR72"
						( Origin gPackager )
					)
					( objectStatus "U2D1.BR72" )
				)
				( pin "vss(563)"
					( attribute "PN" "BR70"
						( Origin gPackager )
					)
					( objectStatus "U2D1.BR70" )
				)
				( pin "vss(564)"
					( attribute "PN" "BR68"
						( Origin gPackager )
					)
					( objectStatus "U2D1.BR68" )
				)
				( pin "vss(565)"
					( attribute "PN" "BR66"
						( Origin gPackager )
					)
					( objectStatus "U2D1.BR66" )
				)
				( pin "vss(566)"
					( attribute "PN" "BR64"
						( Origin gPackager )
					)
					( objectStatus "U2D1.BR64" )
				)
				( pin "vss(567)"
					( attribute "PN" "P57"
						( Origin gPackager )
					)
					( objectStatus "U2D1.P57" )
				)
				( pin "vss(568)"
					( attribute "PN" "BR16"
						( Origin gPackager )
					)
					( objectStatus "U2D1.BR16" )
				)
				( pin "vss(569)"
					( attribute "PN" "BR10"
						( Origin gPackager )
					)
					( objectStatus "U2D1.BR10" )
				)
				( pin "vss(570)"
					( attribute "PN" "BR6"
						( Origin gPackager )
					)
					( objectStatus "U2D1.BR6" )
				)
				( pin "vss(571)"
					( attribute "PN" "BP27"
						( Origin gPackager )
					)
					( objectStatus "U2D1.BP27" )
				)
				( pin "vss(572)"
					( attribute "PN" "BP3"
						( Origin gPackager )
					)
					( objectStatus "U2D1.BP3" )
				)
				( pin "vss(573)"
					( attribute "PN" "BN26"
						( Origin gPackager )
					)
					( objectStatus "U2D1.BN26" )
				)
				( pin "vss(574)"
					( attribute "PN" "BN20"
						( Origin gPackager )
					)
					( objectStatus "U2D1.BN20" )
				)
				( pin "vss(575)"
					( attribute "PN" "BN10"
						( Origin gPackager )
					)
					( objectStatus "U2D1.BN10" )
				)
				( pin "vss(576)"
					( attribute "PN" "BN6"
						( Origin gPackager )
					)
					( objectStatus "U2D1.BN6" )
				)
				( pin "vss(577)"
					( attribute "PN" "BM25"
						( Origin gPackager )
					)
					( objectStatus "U2D1.BM25" )
				)
				( pin "vss(578)"
					( attribute "PN" "P59"
						( Origin gPackager )
					)
					( objectStatus "U2D1.P59" )
				)
				( pin "vss(579)"
					( attribute "PN" "BM15"
						( Origin gPackager )
					)
					( objectStatus "U2D1.BM15" )
				)
				( pin "vss(580)"
					( attribute "PN" "BM13"
						( Origin gPackager )
					)
					( objectStatus "U2D1.BM13" )
				)
				( pin "vss(581)"
					( attribute "PN" "BM9"
						( Origin gPackager )
					)
					( objectStatus "U2D1.BM9" )
				)
				( pin "vss(582)"
					( attribute "PN" "BL82"
						( Origin gPackager )
					)
					( objectStatus "U2D1.BL82" )
				)
				( pin "vss(583)"
					( attribute "PN" "BL80"
						( Origin gPackager )
					)
					( objectStatus "U2D1.BL80" )
				)
				( pin "vss(584)"
					( attribute "PN" "BL78"
						( Origin gPackager )
					)
					( objectStatus "U2D1.BL78" )
				)
				( pin "vss(585)"
					( attribute "PN" "BL76"
						( Origin gPackager )
					)
					( objectStatus "U2D1.BL76" )
				)
				( pin "vss(586)"
					( attribute "PN" "BL74"
						( Origin gPackager )
					)
					( objectStatus "U2D1.BL74" )
				)
				( pin "vss(587)"
					( attribute "PN" "BL72"
						( Origin gPackager )
					)
					( objectStatus "U2D1.BL72" )
				)
				( pin "vss(588)"
					( attribute "PN" "BL70"
						( Origin gPackager )
					)
					( objectStatus "U2D1.BL70" )
				)
				( pin "vss(589)"
					( attribute "PN" "BL68"
						( Origin gPackager )
					)
					( objectStatus "U2D1.BL68" )
				)
				( pin "vss(590)"
					( attribute "PN" "BL66"
						( Origin gPackager )
					)
					( objectStatus "U2D1.BL66" )
				)
				( pin "vss(591)"
					( attribute "PN" "BL64"
						( Origin gPackager )
					)
					( objectStatus "U2D1.BL64" )
				)
				( pin "vss(592)"
					( attribute "PN" "BL24"
						( Origin gPackager )
					)
					( objectStatus "U2D1.BL24" )
				)
				( pin "vss(593)"
					( attribute "PN" "BL22"
						( Origin gPackager )
					)
					( objectStatus "U2D1.BL22" )
				)
				( pin "vss(594)"
					( attribute "PN" "P61"
						( Origin gPackager )
					)
					( objectStatus "U2D1.P61" )
				)
				( pin "vss(595)"
					( attribute "PN" "BL12"
						( Origin gPackager )
					)
					( objectStatus "U2D1.BL12" )
				)
				( pin "vss(596)"
					( attribute "PN" "BL10"
						( Origin gPackager )
					)
					( objectStatus "U2D1.BL10" )
				)
				( pin "vss(597)"
					( attribute "PN" "BL6"
						( Origin gPackager )
					)
					( objectStatus "U2D1.BL6" )
				)
				( pin "vss(598)"
					( attribute "PN" "BK19"
						( Origin gPackager )
					)
					( objectStatus "U2D1.BK19" )
				)
				( pin "vss(599)"
					( attribute "PN" "BK11"
						( Origin gPackager )
					)
					( objectStatus "U2D1.BK11" )
				)
				( pin "vss(600)"
					( attribute "PN" "BK7"
						( Origin gPackager )
					)
					( objectStatus "U2D1.BK7" )
				)
				( pin "vss(601)"
					( attribute "PN" "BK3"
						( Origin gPackager )
					)
					( objectStatus "U2D1.BK3" )
				)
				( pin "vss(602)"
					( attribute "PN" "BJ6"
						( Origin gPackager )
					)
					( objectStatus "U2D1.BJ6" )
				)
				( pin "vss(603)"
					( attribute "PN" "BJ4"
						( Origin gPackager )
					)
					( objectStatus "U2D1.BJ4" )
				)
				( pin "vss(604)"
					( attribute "PN" "BH21"
						( Origin gPackager )
					)
					( objectStatus "U2D1.BH21" )
				)
				( pin "vss(605)"
					( attribute "PN" "BH15"
						( Origin gPackager )
					)
					( objectStatus "U2D1.BH15" )
				)
				( pin "vss(606)"
					( attribute "PN" "BH11"
						( Origin gPackager )
					)
					( objectStatus "U2D1.BH11" )
				)
				( pin "vss(607)"
					( attribute "PN" "BH9"
						( Origin gPackager )
					)
					( objectStatus "U2D1.BH9" )
				)
				( pin "vss(608)"
					( attribute "PN" "BH7"
						( Origin gPackager )
					)
					( objectStatus "U2D1.BH7" )
				)
				( pin "vss(609)"
					( attribute "PN" "BG82"
						( Origin gPackager )
					)
					( objectStatus "U2D1.BG82" )
				)
				( pin "vss(610)"
					( attribute "PN" "BG80"
						( Origin gPackager )
					)
					( objectStatus "U2D1.BG80" )
				)
				( pin "vss(611)"
					( attribute "PN" "BG78"
						( Origin gPackager )
					)
					( objectStatus "U2D1.BG78" )
				)
				( pin "vss(612)"
					( attribute "PN" "BG76"
						( Origin gPackager )
					)
					( objectStatus "U2D1.BG76" )
				)
				( pin "vss(613)"
					( attribute "PN" "BG74"
						( Origin gPackager )
					)
					( objectStatus "U2D1.BG74" )
				)
			)
			( gate "@baseboard_fab2_lib.baseboard_fab2(sch_1):page75_i18"
				( attribute "CDS_LIB" "chpset_lib"
					( Origin gPackager )
				)
				( attribute "CDS_LOCATION" "U2D1"
					( Origin gPackager )
				)
				( attribute "CDS_SEC" "28"
					( Origin gPackager )
				)
				( attribute "LOCATION" "U2D1"
					( Origin gFrontEnd )
				)
				( attribute "MATERIAL" "IC"
					( Origin gFrontEnd )
				)
				( attribute "PACK_TYPE" "BGA1"
					( Origin gFrontEnd )
				)
				( attribute "PART_NUMBER" "TBD"
					( Origin gFrontEnd )
				)
				( attribute "PHYS_PAGE" "75"
					( Origin gFrontEnd )
				)
				( attribute "ROT" "0"
					( Origin gFrontEnd )
				)
				( attribute "SEC" "28"
					( Origin gFrontEnd )
				)
				( attribute "SEC_TYPE" "BGA1"
					( Origin gFrontEnd )
				)
				( attribute "VER" "28"
					( Origin gFrontEnd )
				)
				( attribute "XY" "(-4925,2525)"
					( Origin gFrontEnd )
				)
				( attribute "CHIPS_PART_NAME" "SKX_EXT_B"
					( Origin gPackager )
				)
				( attribute "CDS_PART_NAME" "SKX_EXT_B_BGA1-IC,TBD"
					( Origin gPackager )
				)
				( objectStatus "U2D1" )
				( pin "vss(294)"
					( attribute "PN" "DA46"
						( Origin gPackager )
					)
					( objectStatus "U2D1.DA46" )
				)
				( pin "vss(295)"
					( attribute "PN" "DA44"
						( Origin gPackager )
					)
					( objectStatus "U2D1.DA44" )
				)
				( pin "vss(296)"
					( attribute "PN" "DA38"
						( Origin gPackager )
					)
					( objectStatus "U2D1.DA38" )
				)
				( pin "vss(297)"
					( attribute "PN" "DA36"
						( Origin gPackager )
					)
					( objectStatus "U2D1.DA36" )
				)
				( pin "vss(298)"
					( attribute "PN" "DA34"
						( Origin gPackager )
					)
					( objectStatus "U2D1.DA34" )
				)
				( pin "vss(299)"
					( attribute "PN" "DA32"
						( Origin gPackager )
					)
					( objectStatus "U2D1.DA32" )
				)
				( pin "vss(300)"
					( attribute "PN" "DA30"
						( Origin gPackager )
					)
					( objectStatus "U2D1.DA30" )
				)
				( pin "vss(301)"
					( attribute "PN" "DA28"
						( Origin gPackager )
					)
					( objectStatus "U2D1.DA28" )
				)
				( pin "vss(302)"
					( attribute "PN" "DA26"
						( Origin gPackager )
					)
					( objectStatus "U2D1.DA26" )
				)
				( pin "vss(303)"
					( attribute "PN" "DA18"
						( Origin gPackager )
					)
					( objectStatus "U2D1.DA18" )
				)
				( pin "vss(304)"
					( attribute "PN" "H53"
						( Origin gPackager )
					)
					( objectStatus "U2D1.H53" )
				)
				( pin "vss(305)"
					( attribute "PN" "DA6"
						( Origin gPackager )
					)
					( objectStatus "U2D1.DA6" )
				)
				( pin "vss(306)"
					( attribute "PN" "CY85"
						( Origin gPackager )
					)
					( objectStatus "U2D1.CY85" )
				)
				( pin "vss(307)"
					( attribute "PN" "CY83"
						( Origin gPackager )
					)
					( objectStatus "U2D1.CY83" )
				)
				( pin "vss(308)"
					( attribute "PN" "CY77"
						( Origin gPackager )
					)
					( objectStatus "U2D1.CY77" )
				)
				( pin "vss(309)"
					( attribute "PN" "CY75"
						( Origin gPackager )
					)
					( objectStatus "U2D1.CY75" )
				)
				( pin "vss(310)"
					( attribute "PN" "CY69"
						( Origin gPackager )
					)
					( objectStatus "U2D1.CY69" )
				)
				( pin "vss(311)"
					( attribute "PN" "CY65"
						( Origin gPackager )
					)
					( objectStatus "U2D1.CY65" )
				)
				( pin "vss(312)"
					( attribute "PN" "CY61"
						( Origin gPackager )
					)
					( objectStatus "U2D1.CY61" )
				)
				( pin "vss(313)"
					( attribute "PN" "CY59"
						( Origin gPackager )
					)
					( objectStatus "U2D1.CY59" )
				)
				( pin "vss(314)"
					( attribute "PN" "CY51"
						( Origin gPackager )
					)
					( objectStatus "U2D1.CY51" )
				)
				( pin "vss(315)"
					( attribute "PN" "CY45"
						( Origin gPackager )
					)
					( objectStatus "U2D1.CY45" )
				)
				( pin "vss(316)"
					( attribute "PN" "CY41"
						( Origin gPackager )
					)
					( objectStatus "U2D1.CY41" )
				)
				( pin "vss(317)"
					( attribute "PN" "CY21"
						( Origin gPackager )
					)
					( objectStatus "U2D1.CY21" )
				)
				( pin "vss(318)"
					( attribute "PN" "CY15"
						( Origin gPackager )
					)
					( objectStatus "U2D1.CY15" )
				)
				( pin "vss(319)"
					( attribute "PN" "CY13"
						( Origin gPackager )
					)
					( objectStatus "U2D1.CY13" )
				)
				( pin "vss(320)"
					( attribute "PN" "CY9"
						( Origin gPackager )
					)
					( objectStatus "U2D1.CY9" )
				)
				( pin "vss(321)"
					( attribute "PN" "CY1"
						( Origin gPackager )
					)
					( objectStatus "U2D1.CY1" )
				)
				( pin "vss(322)"
					( attribute "PN" "CW82"
						( Origin gPackager )
					)
					( objectStatus "U2D1.CW82" )
				)
				( pin "vss(323)"
					( attribute "PN" "CW78"
						( Origin gPackager )
					)
					( objectStatus "U2D1.CW78" )
				)
				( pin "vss(324)"
					( attribute "PN" "CW74"
						( Origin gPackager )
					)
					( objectStatus "U2D1.CW74" )
				)
				( pin "vss(325)"
					( attribute "PN" "CW68"
						( Origin gPackager )
					)
					( objectStatus "U2D1.CW68" )
				)
				( pin "vss(326)"
					( attribute "PN" "CW66"
						( Origin gPackager )
					)
					( objectStatus "U2D1.CW66" )
				)
				( pin "vss(327)"
					( attribute "PN" "CW64"
						( Origin gPackager )
					)
					( objectStatus "U2D1.CW64" )
				)
				( pin "vss(328)"
					( attribute "PN" "CW54"
						( Origin gPackager )
					)
					( objectStatus "U2D1.CW54" )
				)
				( pin "vss(329)"
					( attribute "PN" "CW52"
						( Origin gPackager )
					)
					( objectStatus "U2D1.CW52" )
				)
				( pin "vss(330)"
					( attribute "PN" "CW42"
						( Origin gPackager )
					)
					( objectStatus "U2D1.CW42" )
				)
				( pin "vss(331)"
					( attribute "PN" "CW40"
						( Origin gPackager )
					)
					( objectStatus "U2D1.CW40" )
				)
				( pin "vss(332)"
					( attribute "PN" "CW38"
						( Origin gPackager )
					)
					( objectStatus "U2D1.CW38" )
				)
				( pin "vss(333)"
					( attribute "PN" "CW32"
						( Origin gPackager )
					)
					( objectStatus "U2D1.CW32" )
				)
				( pin "vss(334)"
					( attribute "PN" "CW26"
						( Origin gPackager )
					)
					( objectStatus "U2D1.CW26" )
				)
				( pin "vss(335)"
					( attribute "PN" "CW12"
						( Origin gPackager )
					)
					( objectStatus "U2D1.CW12" )
				)
				( pin "vss(336)"
					( attribute "PN" "CV83"
						( Origin gPackager )
					)
					( objectStatus "U2D1.CV83" )
				)
				( pin "vss(337)"
					( attribute "PN" "CV81"
						( Origin gPackager )
					)
					( objectStatus "U2D1.CV81" )
				)
				( pin "vss(338)"
					( attribute "PN" "CV79"
						( Origin gPackager )
					)
					( objectStatus "U2D1.CV79" )
				)
				( pin "vss(339)"
					( attribute "PN" "CV73"
						( Origin gPackager )
					)
					( objectStatus "U2D1.CV73" )
				)
				( pin "vss(340)"
					( attribute "PN" "CV67"
						( Origin gPackager )
					)
					( objectStatus "U2D1.CV67" )
				)
				( pin "vss(341)"
					( attribute "PN" "CV63"
						( Origin gPackager )
					)
					( objectStatus "U2D1.CV63" )
				)
				( pin "vss(342)"
					( attribute "PN" "CV55"
						( Origin gPackager )
					)
					( objectStatus "U2D1.CV55" )
				)
				( pin "vss(343)"
					( attribute "PN" "CV53"
						( Origin gPackager )
					)
					( objectStatus "U2D1.CV53" )
				)
				( pin "vss(344)"
					( attribute "PN" "CV41"
						( Origin gPackager )
					)
					( objectStatus "U2D1.CV41" )
				)
				( pin "vss(345)"
					( attribute "PN" "CV39"
						( Origin gPackager )
					)
					( objectStatus "U2D1.CV39" )
				)
				( pin "vss(346)"
					( attribute "PN" "CV37"
						( Origin gPackager )
					)
					( objectStatus "U2D1.CV37" )
				)
				( pin "vss(347)"
					( attribute "PN" "CV33"
						( Origin gPackager )
					)
					( objectStatus "U2D1.CV33" )
				)
				( pin "vss(348)"
					( attribute "PN" "CV31"
						( Origin gPackager )
					)
					( objectStatus "U2D1.CV31" )
				)
				( pin "vss(349)"
					( attribute "PN" "CV27"
						( Origin gPackager )
					)
					( objectStatus "U2D1.CV27" )
				)
				( pin "vss(350)"
					( attribute "PN" "CV25"
						( Origin gPackager )
					)
					( objectStatus "U2D1.CV25" )
				)
				( pin "vss(351)"
					( attribute "PN" "CV17"
						( Origin gPackager )
					)
					( objectStatus "U2D1.CV17" )
				)
				( pin "vss(352)"
					( attribute "PN" "H55"
						( Origin gPackager )
					)
					( objectStatus "U2D1.H55" )
				)
				( pin "vss(353)"
					( attribute "PN" "CV1"
						( Origin gPackager )
					)
					( objectStatus "U2D1.CV1" )
				)
				( pin "vss(354)"
					( attribute "PN" "CU86"
						( Origin gPackager )
					)
					( objectStatus "U2D1.CU86" )
				)
				( pin "vss(355)"
					( attribute "PN" "CU82"
						( Origin gPackager )
					)
					( objectStatus "U2D1.CU82" )
				)
				( pin "vss(356)"
					( attribute "PN" "CU80"
						( Origin gPackager )
					)
					( objectStatus "U2D1.CU80" )
				)
				( pin "vss(357)"
					( attribute "PN" "CU78"
						( Origin gPackager )
					)
					( objectStatus "U2D1.CU78" )
				)
				( pin "vss(358)"
					( attribute "PN" "CU76"
						( Origin gPackager )
					)
					( objectStatus "U2D1.CU76" )
				)
				( pin "vss(359)"
					( attribute "PN" "CU68"
						( Origin gPackager )
					)
					( objectStatus "U2D1.CU68" )
				)
				( pin "vss(360)"
					( attribute "PN" "CU62"
						( Origin gPackager )
					)
					( objectStatus "U2D1.CU62" )
				)
				( pin "vss(361)"
					( attribute "PN" "CU56"
						( Origin gPackager )
					)
					( objectStatus "U2D1.CU56" )
				)
				( pin "vss(362)"
					( attribute "PN" "CU36"
						( Origin gPackager )
					)
					( objectStatus "U2D1.CU36" )
				)
				( pin "vss(363)"
					( attribute "PN" "CU34"
						( Origin gPackager )
					)
					( objectStatus "U2D1.CU34" )
				)
				( pin "vss(364)"
					( attribute "PN" "CU30"
						( Origin gPackager )
					)
					( objectStatus "U2D1.CU30" )
				)
				( pin "vss(365)"
					( attribute "PN" "CU28"
						( Origin gPackager )
					)
					( objectStatus "U2D1.CU28" )
				)
				( pin "vss(366)"
					( attribute "PN" "CU22"
						( Origin gPackager )
					)
					( objectStatus "U2D1.CU22" )
				)
				( pin "vss(367)"
					( attribute "PN" "CU4"
						( Origin gPackager )
					)
					( objectStatus "U2D1.CU4" )
				)
				( pin "vss(368)"
					( attribute "PN" "CT85"
						( Origin gPackager )
					)
					( objectStatus "U2D1.CT85" )
				)
				( pin "vss(369)"
					( attribute "PN" "CT83"
						( Origin gPackager )
					)
					( objectStatus "U2D1.CT83" )
				)
				( pin "vss(370)"
					( attribute "PN" "CT79"
						( Origin gPackager )
					)
					( objectStatus "U2D1.CT79" )
				)
				( pin "vss(371)"
					( attribute "PN" "CT73"
						( Origin gPackager )
					)
					( objectStatus "U2D1.CT73" )
				)
				( pin "vss(372)"
					( attribute "PN" "CT57"
						( Origin gPackager )
					)
					( objectStatus "U2D1.CT57" )
				)
				( pin "vss(373)"
					( attribute "PN" "CT35"
						( Origin gPackager )
					)
					( objectStatus "U2D1.CT35" )
				)
				( pin "vss(374)"
					( attribute "PN" "CT33"
						( Origin gPackager )
					)
					( objectStatus "U2D1.CT33" )
				)
				( pin "vss(375)"
					( attribute "PN" "CT29"
						( Origin gPackager )
					)
					( objectStatus "U2D1.CT29" )
				)
				( pin "vss(376)"
					( attribute "PN" "CT27"
						( Origin gPackager )
					)
					( objectStatus "U2D1.CT27" )
				)
				( pin "vss(377)"
					( attribute "PN" "CT19"
						( Origin gPackager )
					)
					( objectStatus "U2D1.CT19" )
				)
				( pin "vss(378)"
					( attribute "PN" "CT13"
						( Origin gPackager )
					)
					( objectStatus "U2D1.CT13" )
				)
				( pin "vss(379)"
					( attribute "PN" "H57"
						( Origin gPackager )
					)
					( objectStatus "U2D1.H57" )
				)
				( pin "vss(380)"
					( attribute "PN" "CR86"
						( Origin gPackager )
					)
					( objectStatus "U2D1.CR86" )
				)
				( pin "vss(381)"
					( attribute "PN" "CR78"
						( Origin gPackager )
					)
					( objectStatus "U2D1.CR78" )
				)
				( pin "vss(382)"
					( attribute "PN" "CR68"
						( Origin gPackager )
					)
					( objectStatus "U2D1.CR68" )
				)
				( pin "vss(383)"
					( attribute "PN" "CR66"
						( Origin gPackager )
					)
					( objectStatus "U2D1.CR66" )
				)
				( pin "vss(384)"
					( attribute "PN" "CR64"
						( Origin gPackager )
					)
					( objectStatus "U2D1.CR64" )
				)
				( pin "vss(385)"
					( attribute "PN" "CR62"
						( Origin gPackager )
					)
					( objectStatus "U2D1.CR62" )
				)
				( pin "vss(386)"
					( attribute "PN" "CR58"
						( Origin gPackager )
					)
					( objectStatus "U2D1.CR58" )
				)
				( pin "vss(387)"
					( attribute "PN" "CR32"
						( Origin gPackager )
					)
					( objectStatus "U2D1.CR32" )
				)
				( pin "vss(388)"
					( attribute "PN" "CR24"
						( Origin gPackager )
					)
					( objectStatus "U2D1.CR24" )
				)
				( pin "vss(389)"
					( attribute "PN" "CR22"
						( Origin gPackager )
					)
					( objectStatus "U2D1.CR22" )
				)
				( pin "vss(390)"
					( attribute "PN" "CR10"
						( Origin gPackager )
					)
					( objectStatus "U2D1.CR10" )
				)
				( pin "vss(391)"
					( attribute "PN" "CR6"
						( Origin gPackager )
					)
					( objectStatus "U2D1.CR6" )
				)
				( pin "vss(392)"
					( attribute "PN" "CP83"
						( Origin gPackager )
					)
					( objectStatus "U2D1.CP83" )
				)
				( pin "vss(393)"
					( attribute "PN" "CP81"
						( Origin gPackager )
					)
					( objectStatus "U2D1.CP81" )
				)
				( pin "vss(394)"
					( attribute "PN" "CP75"
						( Origin gPackager )
					)
					( objectStatus "U2D1.CP75" )
				)
				( pin "vss(395)"
					( attribute "PN" "CP73"
						( Origin gPackager )
					)
					( objectStatus "U2D1.CP73" )
				)
				( pin "vss(396)"
					( attribute "PN" "CP69"
						( Origin gPackager )
					)
					( objectStatus "U2D1.CP69" )
				)
				( pin "vss(397)"
					( attribute "PN" "CP59"
						( Origin gPackager )
					)
					( objectStatus "U2D1.CP59" )
				)
				( pin "vss(398)"
					( attribute "PN" "CP25"
						( Origin gPackager )
					)
					( objectStatus "U2D1.CP25" )
				)
				( pin "vss(399)"
					( attribute "PN" "H59"
						( Origin gPackager )
					)
					( objectStatus "U2D1.H59" )
				)
				( pin "vss(400)"
					( attribute "PN" "CP1"
						( Origin gPackager )
					)
					( objectStatus "U2D1.CP1" )
				)
				( pin "vss(401)"
					( attribute "PN" "CN78"
						( Origin gPackager )
					)
					( objectStatus "U2D1.CN78" )
				)
				( pin "vss(402)"
					( attribute "PN" "CN68"
						( Origin gPackager )
					)
					( objectStatus "U2D1.CN68" )
				)
				( pin "vss(403)"
					( attribute "PN" "CN62"
						( Origin gPackager )
					)
					( objectStatus "U2D1.CN62" )
				)
				( pin "vss(404)"
					( attribute "PN" "CN60"
						( Origin gPackager )
					)
					( objectStatus "U2D1.CN60" )
				)
				( pin "vss(405)"
					( attribute "PN" "CN32"
						( Origin gPackager )
					)
					( objectStatus "U2D1.CN32" )
				)
				( pin "vss(406)"
					( attribute "PN" "CN26"
						( Origin gPackager )
					)
					( objectStatus "U2D1.CN26" )
				)
				( pin "vss(407)"
					( attribute "PN" "H61"
						( Origin gPackager )
					)
					( objectStatus "U2D1.H61" )
				)
				( pin "vss(408)"
					( attribute "PN" "CN12"
						( Origin gPackager )
					)
					( objectStatus "U2D1.CN12" )
				)
				( pin "vss(409)"
					( attribute "PN" "CN2"
						( Origin gPackager )
					)
					( objectStatus "U2D1.CN2" )
				)
				( pin "vss(410)"
					( attribute "PN" "CM85"
						( Origin gPackager )
					)
					( objectStatus "U2D1.CM85" )
				)
				( pin "vss(411)"
					( attribute "PN" "CM83"
						( Origin gPackager )
					)
					( objectStatus "U2D1.CM83" )
				)
				( pin "vss(412)"
					( attribute "PN" "CM77"
						( Origin gPackager )
					)
					( objectStatus "U2D1.CM77" )
				)
				( pin "vss(413)"
					( attribute "PN" "CM73"
						( Origin gPackager )
					)
					( objectStatus "U2D1.CM73" )
				)
				( pin "vss(414)"
					( attribute "PN" "CM67"
						( Origin gPackager )
					)
					( objectStatus "U2D1.CM67" )
				)
				( pin "vss(415)"
					( attribute "PN" "CM63"
						( Origin gPackager )
					)
					( objectStatus "U2D1.CM63" )
				)
				( pin "vss(416)"
					( attribute "PN" "CM61"
						( Origin gPackager )
					)
					( objectStatus "U2D1.CM61" )
				)
				( pin "vss(417)"
					( attribute "PN" "CM31"
						( Origin gPackager )
					)
					( objectStatus "U2D1.CM31" )
				)
				( pin "vss(418)"
					( attribute "PN" "CM5"
						( Origin gPackager )
					)
					( objectStatus "U2D1.CM5" )
				)
				( pin "vss(419)"
					( attribute "PN" "CM29"
						( Origin gPackager )
					)
					( objectStatus "U2D1.CM29" )
				)
				( pin "vss(420)"
					( attribute "PN" "CM19"
						( Origin gPackager )
					)
					( objectStatus "U2D1.CM19" )
				)
				( pin "vss(421)"
					( attribute "PN" "CL80"
						( Origin gPackager )
					)
					( objectStatus "U2D1.CL80" )
				)
				( pin "vss(422)"
					( attribute "PN" "CL78"
						( Origin gPackager )
					)
					( objectStatus "U2D1.CL78" )
				)
				( pin "vss(423)"
					( attribute "PN" "CL76"
						( Origin gPackager )
					)
					( objectStatus "U2D1.CL76" )
				)
				( pin "vss(424)"
					( attribute "PN" "CL74"
						( Origin gPackager )
					)
					( objectStatus "U2D1.CL74" )
				)
				( pin "vss(425)"
					( attribute "PN" "CL66"
						( Origin gPackager )
					)
					( objectStatus "U2D1.CL66" )
				)
				( pin "vss(426)"
					( attribute "PN" "CL64"
						( Origin gPackager )
					)
					( objectStatus "U2D1.CL64" )
				)
				( pin "vss(427)"
					( attribute "PN" "CL62"
						( Origin gPackager )
					)
					( objectStatus "U2D1.CL62" )
				)
				( pin "vss(428)"
					( attribute "PN" "H63"
						( Origin gPackager )
					)
					( objectStatus "U2D1.H63" )
				)
				( pin "vss(429)"
					( attribute "PN" "P45"
						( Origin gPackager )
					)
					( objectStatus "U2D1.P45" )
				)
				( pin "vss(430)"
					( attribute "PN" "CL18"
						( Origin gPackager )
					)
					( objectStatus "U2D1.CL18" )
				)
				( pin "vss(431)"
					( attribute "PN" "CL14"
						( Origin gPackager )
					)
					( objectStatus "U2D1.CL14" )
				)
				( pin "vss(432)"
					( attribute "PN" "CL8"
						( Origin gPackager )
					)
					( objectStatus "U2D1.CL8" )
				)
				( pin "vss(433)"
					( attribute "PN" "CK85"
						( Origin gPackager )
					)
					( objectStatus "U2D1.CK85" )
				)
				( pin "vss(434)"
					( attribute "PN" "CK83"
						( Origin gPackager )
					)
					( objectStatus "U2D1.CK83" )
				)
				( pin "vss(435)"
					( attribute "PN" "CK75"
						( Origin gPackager )
					)
					( objectStatus "U2D1.CK75" )
				)
				( pin "vss(436)"
					( attribute "PN" "CK73"
						( Origin gPackager )
					)
					( objectStatus "U2D1.CK73" )
				)
				( pin "vss(437)"
					( attribute "PN" "CK71"
						( Origin gPackager )
					)
					( objectStatus "U2D1.CK71" )
				)
				( pin "vss(438)"
					( attribute "PN" "CK69"
						( Origin gPackager )
					)
					( objectStatus "U2D1.CK69" )
				)
				( pin "vss(439)"
					( attribute "PN" "CK67"
						( Origin gPackager )
					)
					( objectStatus "U2D1.CK67" )
				)
				( pin "vss(440)"
					( attribute "PN" "CK65"
						( Origin gPackager )
					)
					( objectStatus "U2D1.CK65" )
				)
				( pin "vss(441)"
					( attribute "PN" "CK63"
						( Origin gPackager )
					)
					( objectStatus "U2D1.CK63" )
				)
				( pin "vss(442)"
					( attribute "PN" "CK27"
						( Origin gPackager )
					)
					( objectStatus "U2D1.CK27" )
				)
				( pin "vss(443)"
					( attribute "PN" "CK21"
						( Origin gPackager )
					)
					( objectStatus "U2D1.CK21" )
				)
				( pin "vss(444)"
					( attribute "PN" "CK15"
						( Origin gPackager )
					)
					( objectStatus "U2D1.CK15" )
				)
				( pin "vss(445)"
					( attribute "PN" "CK11"
						( Origin gPackager )
					)
					( objectStatus "U2D1.CK11" )
				)
				( pin "vss(446)"
					( attribute "PN" "CJ86"
						( Origin gPackager )
					)
					( objectStatus "U2D1.CJ86" )
				)
				( pin "vss(447)"
					( attribute "PN" "CJ84"
						( Origin gPackager )
					)
					( objectStatus "U2D1.CJ84" )
				)
				( pin "vss(448)"
					( attribute "PN" "CJ82"
						( Origin gPackager )
					)
					( objectStatus "U2D1.CJ82" )
				)
				( pin "vss(449)"
					( attribute "PN" "CJ78"
						( Origin gPackager )
					)
					( objectStatus "U2D1.CJ78" )
				)
				( pin "vss(450)"
					( attribute "PN" "CJ76"
						( Origin gPackager )
					)
					( objectStatus "U2D1.CJ76" )
				)
				( pin "vss(451)"
					( attribute "PN" "CJ74"
						( Origin gPackager )
					)
					( objectStatus "U2D1.CJ74" )
				)
				( pin "vss(452)"
					( attribute "PN" "CJ62"
						( Origin gPackager )
					)
					( objectStatus "U2D1.CJ62" )
				)
				( pin "vss(453)"
					( attribute "PN" "P47"
						( Origin gPackager )
					)
					( objectStatus "U2D1.P47" )
				)
			)
			( gate "@baseboard_fab2_lib.baseboard_fab2(sch_1):page75_i19"
				( attribute "CDS_LIB" "chpset_lib"
					( Origin gPackager )
				)
				( attribute "CDS_LOCATION" "U2D1"
					( Origin gPackager )
				)
				( attribute "CDS_SEC" "29"
					( Origin gPackager )
				)
				( attribute "LOCATION" "U2D1"
					( Origin gFrontEnd )
				)
				( attribute "MATERIAL" "IC"
					( Origin gFrontEnd )
				)
				( attribute "PACK_TYPE" "BGA1"
					( Origin gFrontEnd )
				)
				( attribute "PART_NUMBER" "TBD"
					( Origin gFrontEnd )
				)
				( attribute "PHYS_PAGE" "75"
					( Origin gFrontEnd )
				)
				( attribute "ROT" "0"
					( Origin gFrontEnd )
				)
				( attribute "SEC" "29"
					( Origin gFrontEnd )
				)
				( attribute "SEC_TYPE" "BGA1"
					( Origin gFrontEnd )
				)
				( attribute "VER" "29"
					( Origin gFrontEnd )
				)
				( attribute "XY" "(-3050,2525)"
					( Origin gFrontEnd )
				)
				( attribute "CHIPS_PART_NAME" "SKX_EXT_B"
					( Origin gPackager )
				)
				( attribute "CDS_PART_NAME" "SKX_EXT_B_BGA1-IC,TBD"
					( Origin gPackager )
				)
				( objectStatus "U2D1" )
				( pin "vss(134)"
					( attribute "PN" "DN72"
						( Origin gPackager )
					)
					( objectStatus "U2D1.DN72" )
				)
				( pin "vss(135)"
					( attribute "PN" "DN68"
						( Origin gPackager )
					)
					( objectStatus "U2D1.DN68" )
				)
				( pin "vss(136)"
					( attribute "PN" "DN38"
						( Origin gPackager )
					)
					( objectStatus "U2D1.DN38" )
				)
				( pin "vss(137)"
					( attribute "PN" "DN32"
						( Origin gPackager )
					)
					( objectStatus "U2D1.DN32" )
				)
				( pin "vss(138)"
					( attribute "PN" "DN26"
						( Origin gPackager )
					)
					( objectStatus "U2D1.DN26" )
				)
				( pin "vss(139)"
					( attribute "PN" "DN22"
						( Origin gPackager )
					)
					( objectStatus "U2D1.DN22" )
				)
				( pin "vss(140)"
					( attribute "PN" "DN12"
						( Origin gPackager )
					)
					( objectStatus "U2D1.DN12" )
				)
				( pin "vss(141)"
					( attribute "PN" "BH17"
						( Origin gPackager )
					)
					( objectStatus "U2D1.BH17" )
				)
				( pin "vss(142)"
					( attribute "PN" "DN2"
						( Origin gPackager )
					)
					( objectStatus "U2D1.DN2" )
				)
				( pin "vss(143)"
					( attribute "PN" "DM83"
						( Origin gPackager )
					)
					( objectStatus "U2D1.DM83" )
				)
				( pin "vss(144)"
					( attribute "PN" "DM77"
						( Origin gPackager )
					)
					( objectStatus "U2D1.DM77" )
				)
				( pin "vss(145)"
					( attribute "PN" "DM73"
						( Origin gPackager )
					)
					( objectStatus "U2D1.DM73" )
				)
				( pin "vss(146)"
					( attribute "PN" "DM65"
						( Origin gPackager )
					)
					( objectStatus "U2D1.DM65" )
				)
				( pin "vss(147)"
					( attribute "PN" "DM39"
						( Origin gPackager )
					)
					( objectStatus "U2D1.DM39" )
				)
				( pin "vss(148)"
					( attribute "PN" "DM37"
						( Origin gPackager )
					)
					( objectStatus "U2D1.DM37" )
				)
				( pin "vss(149)"
					( attribute "PN" "DM33"
						( Origin gPackager )
					)
					( objectStatus "U2D1.DM33" )
				)
				( pin "vss(150)"
					( attribute "PN" "DM31"
						( Origin gPackager )
					)
					( objectStatus "U2D1.DM31" )
				)
				( pin "vss(151)"
					( attribute "PN" "DM27"
						( Origin gPackager )
					)
					( objectStatus "U2D1.DM27" )
				)
				( pin "vss(152)"
					( attribute "PN" "DM25"
						( Origin gPackager )
					)
					( objectStatus "U2D1.DM25" )
				)
				( pin "vss(153)"
					( attribute "PN" "H45"
						( Origin gPackager )
					)
					( objectStatus "U2D1.H45" )
				)
				( pin "vss(154)"
					( attribute "PN" "DM15"
						( Origin gPackager )
					)
					( objectStatus "U2D1.DM15" )
				)
				( pin "vss(155)"
					( attribute "PN" "DL80"
						( Origin gPackager )
					)
					( objectStatus "U2D1.DL80" )
				)
				( pin "vss(156)"
					( attribute "PN" "DL78"
						( Origin gPackager )
					)
					( objectStatus "U2D1.DL78" )
				)
				( pin "vss(157)"
					( attribute "PN" "DL76"
						( Origin gPackager )
					)
					( objectStatus "U2D1.DL76" )
				)
				( pin "vss(158)"
					( attribute "PN" "DL74"
						( Origin gPackager )
					)
					( objectStatus "U2D1.DL74" )
				)
				( pin "vss(159)"
					( attribute "PN" "DL70"
						( Origin gPackager )
					)
					( objectStatus "U2D1.DL70" )
				)
				( pin "vss(160)"
					( attribute "PN" "DL68"
						( Origin gPackager )
					)
					( objectStatus "U2D1.DL68" )
				)
				( pin "vss(161)"
					( attribute "PN" "DL40"
						( Origin gPackager )
					)
					( objectStatus "U2D1.DL40" )
				)
				( pin "vss(162)"
					( attribute "PN" "DL36"
						( Origin gPackager )
					)
					( objectStatus "U2D1.DL36" )
				)
				( pin "vss(163)"
					( attribute "PN" "DL34"
						( Origin gPackager )
					)
					( objectStatus "U2D1.DL34" )
				)
				( pin "vss(164)"
					( attribute "PN" "DL30"
						( Origin gPackager )
					)
					( objectStatus "U2D1.DL30" )
				)
				( pin "vss(165)"
					( attribute "PN" "DL28"
						( Origin gPackager )
					)
					( objectStatus "U2D1.DL28" )
				)
				( pin "vss(166)"
					( attribute "PN" "DL24"
						( Origin gPackager )
					)
					( objectStatus "U2D1.DL24" )
				)
				( pin "vss(167)"
					( attribute "PN" "DL22"
						( Origin gPackager )
					)
					( objectStatus "U2D1.DL22" )
				)
				( pin "vss(168)"
					( attribute "PN" "DL4"
						( Origin gPackager )
					)
					( objectStatus "U2D1.DL4" )
				)
				( pin "vss(169)"
					( attribute "PN" "DL18"
						( Origin gPackager )
					)
					( objectStatus "U2D1.DL18" )
				)
				( pin "vss(170)"
					( attribute "PN" "DL16"
						( Origin gPackager )
					)
					( objectStatus "U2D1.DL16" )
				)
				( pin "vss(171)"
					( attribute "PN" "DK85"
						( Origin gPackager )
					)
					( objectStatus "U2D1.DK85" )
				)
				( pin "vss(172)"
					( attribute "PN" "DK83"
						( Origin gPackager )
					)
					( objectStatus "U2D1.DK83" )
				)
				( pin "vss(173)"
					( attribute "PN" "DK77"
						( Origin gPackager )
					)
					( objectStatus "U2D1.DK77" )
				)
				( pin "vss(174)"
					( attribute "PN" "DK75"
						( Origin gPackager )
					)
					( objectStatus "U2D1.DK75" )
				)
				( pin "vss(175)"
					( attribute "PN" "DK73"
						( Origin gPackager )
					)
					( objectStatus "U2D1.DK73" )
				)
				( pin "vss(176)"
					( attribute "PN" "DK41"
						( Origin gPackager )
					)
					( objectStatus "U2D1.DK41" )
				)
				( pin "vss(177)"
					( attribute "PN" "DK39"
						( Origin gPackager )
					)
					( objectStatus "U2D1.DK39" )
				)
				( pin "vss(178)"
					( attribute "PN" "DK35"
						( Origin gPackager )
					)
					( objectStatus "U2D1.DK35" )
				)
				( pin "vss(179)"
					( attribute "PN" "DK29"
						( Origin gPackager )
					)
					( objectStatus "U2D1.DK29" )
				)
				( pin "vss(180)"
					( attribute "PN" "DK23"
						( Origin gPackager )
					)
					( objectStatus "U2D1.DK23" )
				)
				( pin "vss(181)"
					( attribute "PN" "DK7"
						( Origin gPackager )
					)
					( objectStatus "U2D1.DK7" )
				)
				( pin "vss(182)"
					( attribute "PN" "DJ84"
						( Origin gPackager )
					)
					( objectStatus "U2D1.DJ84" )
				)
				( pin "vss(183)"
					( attribute "PN" "DJ82"
						( Origin gPackager )
					)
					( objectStatus "U2D1.DJ82" )
				)
				( pin "vss(184)"
					( attribute "PN" "DJ78"
						( Origin gPackager )
					)
					( objectStatus "U2D1.DJ78" )
				)
				( pin "vss(185)"
					( attribute "PN" "DJ74"
						( Origin gPackager )
					)
					( objectStatus "U2D1.DJ74" )
				)
				( pin "vss(186)"
					( attribute "PN" "DJ68"
						( Origin gPackager )
					)
					( objectStatus "U2D1.DJ68" )
				)
				( pin "vss(187)"
					( attribute "PN" "DJ42"
						( Origin gPackager )
					)
					( objectStatus "U2D1.DJ42" )
				)
				( pin "vss(188)"
					( attribute "PN" "DJ38"
						( Origin gPackager )
					)
					( objectStatus "U2D1.DJ38" )
				)
				( pin "vss(189)"
					( attribute "PN" "DJ22"
						( Origin gPackager )
					)
					( objectStatus "U2D1.DJ22" )
				)
				( pin "vss(190)"
					( attribute "PN" "H47"
						( Origin gPackager )
					)
					( objectStatus "U2D1.H47" )
				)
				( pin "vss(191)"
					( attribute "PN" "DJ10"
						( Origin gPackager )
					)
					( objectStatus "U2D1.DJ10" )
				)
				( pin "vss(192)"
					( attribute "PN" "DJ2"
						( Origin gPackager )
					)
					( objectStatus "U2D1.DJ2" )
				)
				( pin "vss(193)"
					( attribute "PN" "DH83"
						( Origin gPackager )
					)
					( objectStatus "U2D1.DH83" )
				)
				( pin "vss(194)"
					( attribute "PN" "DH81"
						( Origin gPackager )
					)
					( objectStatus "U2D1.DH81" )
				)
				( pin "vss(195)"
					( attribute "PN" "DH79"
						( Origin gPackager )
					)
					( objectStatus "U2D1.DH79" )
				)
				( pin "vss(196)"
					( attribute "PN" "DH73"
						( Origin gPackager )
					)
					( objectStatus "U2D1.DH73" )
				)
				( pin "vss(197)"
					( attribute "PN" "DH71"
						( Origin gPackager )
					)
					( objectStatus "U2D1.DH71" )
				)
				( pin "vss(198)"
					( attribute "PN" "DH67"
						( Origin gPackager )
					)
					( objectStatus "U2D1.DH67" )
				)
				( pin "vss(199)"
					( attribute "PN" "DH41"
						( Origin gPackager )
					)
					( objectStatus "U2D1.DH41" )
				)
				( pin "vss(200)"
					( attribute "PN" "DH37"
						( Origin gPackager )
					)
					( objectStatus "U2D1.DH37" )
				)
				( pin "vss(201)"
					( attribute "PN" "DH35"
						( Origin gPackager )
					)
					( objectStatus "U2D1.DH35" )
				)
				( pin "vss(202)"
					( attribute "PN" "DH33"
						( Origin gPackager )
					)
					( objectStatus "U2D1.DH33" )
				)
				( pin "vss(203)"
					( attribute "PN" "DH31"
						( Origin gPackager )
					)
					( objectStatus "U2D1.DH31" )
				)
				( pin "vss(204)"
					( attribute "PN" "DH29"
						( Origin gPackager )
					)
					( objectStatus "U2D1.DH29" )
				)
				( pin "vss(205)"
					( attribute "PN" "DH27"
						( Origin gPackager )
					)
					( objectStatus "U2D1.DH27" )
				)
				( pin "vss(206)"
					( attribute "PN" "DH25"
						( Origin gPackager )
					)
					( objectStatus "U2D1.DH25" )
				)
				( pin "vss(207)"
					( attribute "PN" "DH23"
						( Origin gPackager )
					)
					( objectStatus "U2D1.DH23" )
				)
				( pin "vss(208)"
					( attribute "PN" "DH15"
						( Origin gPackager )
					)
					( objectStatus "U2D1.DH15" )
				)
				( pin "vss(209)"
					( attribute "PN" "DH13"
						( Origin gPackager )
					)
					( objectStatus "U2D1.DH13" )
				)
				( pin "vss(210)"
					( attribute "PN" "DG82"
						( Origin gPackager )
					)
					( objectStatus "U2D1.DG82" )
				)
				( pin "vss(211)"
					( attribute "PN" "DG80"
						( Origin gPackager )
					)
					( objectStatus "U2D1.DG80" )
				)
				( pin "vss(212)"
					( attribute "PN" "DG78"
						( Origin gPackager )
					)
					( objectStatus "U2D1.DG78" )
				)
				( pin "vss(213)"
					( attribute "PN" "DG76"
						( Origin gPackager )
					)
					( objectStatus "U2D1.DG76" )
				)
				( pin "vss(214)"
					( attribute "PN" "DG68"
						( Origin gPackager )
					)
					( objectStatus "U2D1.DG68" )
				)
				( pin "vss(215)"
					( attribute "PN" "DG66"
						( Origin gPackager )
					)
					( objectStatus "U2D1.DG66" )
				)
				( pin "vss(216)"
					( attribute "PN" "DG24"
						( Origin gPackager )
					)
					( objectStatus "U2D1.DG24" )
				)
				( pin "vss(217)"
					( attribute "PN" "DG16"
						( Origin gPackager )
					)
					( objectStatus "U2D1.DG16" )
				)
				( pin "vss(218)"
					( attribute "PN" "DG14"
						( Origin gPackager )
					)
					( objectStatus "U2D1.DG14" )
				)
				( pin "vss(219)"
					( attribute "PN" "H49"
						( Origin gPackager )
					)
					( objectStatus "U2D1.H49" )
				)
				( pin "vss(220)"
					( attribute "PN" "DG2"
						( Origin gPackager )
					)
					( objectStatus "U2D1.DG2" )
				)
				( pin "vss(221)"
					( attribute "PN" "DF85"
						( Origin gPackager )
					)
					( objectStatus "U2D1.DF85" )
				)
				( pin "vss(222)"
					( attribute "PN" "DF83"
						( Origin gPackager )
					)
					( objectStatus "U2D1.DF83" )
				)
				( pin "vss(223)"
					( attribute "PN" "DF79"
						( Origin gPackager )
					)
					( objectStatus "U2D1.DF79" )
				)
				( pin "vss(224)"
					( attribute "PN" "DF73"
						( Origin gPackager )
					)
					( objectStatus "U2D1.DF73" )
				)
				( pin "vss(225)"
					( attribute "PN" "DF69"
						( Origin gPackager )
					)
					( objectStatus "U2D1.DF69" )
				)
				( pin "vss(226)"
					( attribute "PN" "DF65"
						( Origin gPackager )
					)
					( objectStatus "U2D1.DF65" )
				)
				( pin "vss(227)"
					( attribute "PN" "DF41"
						( Origin gPackager )
					)
					( objectStatus "U2D1.DF41" )
				)
				( pin "vss(228)"
					( attribute "PN" "DF39"
						( Origin gPackager )
					)
					( objectStatus "U2D1.DF39" )
				)
				( pin "vss(229)"
					( attribute "PN" "DF37"
						( Origin gPackager )
					)
					( objectStatus "U2D1.DF37" )
				)
				( pin "vss(230)"
					( attribute "PN" "DF35"
						( Origin gPackager )
					)
					( objectStatus "U2D1.DF35" )
				)
				( pin "vss(231)"
					( attribute "PN" "DF29"
						( Origin gPackager )
					)
					( objectStatus "U2D1.DF29" )
				)
				( pin "vss(232)"
					( attribute "PN" "DF19"
						( Origin gPackager )
					)
					( objectStatus "U2D1.DF19" )
				)
				( pin "vss(233)"
					( attribute "PN" "H51"
						( Origin gPackager )
					)
					( objectStatus "U2D1.H51" )
				)
				( pin "vss(234)"
					( attribute "PN" "DF7"
						( Origin gPackager )
					)
					( objectStatus "U2D1.DF7" )
				)
				( pin "vss(235)"
					( attribute "PN" "DF5"
						( Origin gPackager )
					)
					( objectStatus "U2D1.DF5" )
				)
				( pin "vss(236)"
					( attribute "PN" "DE78"
						( Origin gPackager )
					)
					( objectStatus "U2D1.DE78" )
				)
				( pin "vss(237)"
					( attribute "PN" "DE72"
						( Origin gPackager )
					)
					( objectStatus "U2D1.DE72" )
				)
				( pin "vss(238)"
					( attribute "PN" "DE70"
						( Origin gPackager )
					)
					( objectStatus "U2D1.DE70" )
				)
				( pin "vss(239)"
					( attribute "PN" "DE64"
						( Origin gPackager )
					)
					( objectStatus "U2D1.DE64" )
				)
				( pin "vss(240)"
					( attribute "PN" "DE36"
						( Origin gPackager )
					)
					( objectStatus "U2D1.DE36" )
				)
				( pin "vss(241)"
					( attribute "PN" "DE34"
						( Origin gPackager )
					)
					( objectStatus "U2D1.DE34" )
				)
				( pin "vss(242)"
					( attribute "PN" "DE30"
						( Origin gPackager )
					)
					( objectStatus "U2D1.DE30" )
				)
				( pin "vss(243)"
					( attribute "PN" "DE28"
						( Origin gPackager )
					)
					( objectStatus "U2D1.DE28" )
				)
				( pin "vss(244)"
					( attribute "PN" "DE24"
						( Origin gPackager )
					)
					( objectStatus "U2D1.DE24" )
				)
				( pin "vss(245)"
					( attribute "PN" "DE20"
						( Origin gPackager )
					)
					( objectStatus "U2D1.DE20" )
				)
				( pin "vss(246)"
					( attribute "PN" "DE18"
						( Origin gPackager )
					)
					( objectStatus "U2D1.DE18" )
				)
				( pin "vss(247)"
					( attribute "PN" "DE8"
						( Origin gPackager )
					)
					( objectStatus "U2D1.DE8" )
				)
				( pin "vss(248)"
					( attribute "PN" "DE6"
						( Origin gPackager )
					)
					( objectStatus "U2D1.DE6" )
				)
				( pin "vss(249)"
					( attribute "PN" "DD83"
						( Origin gPackager )
					)
					( objectStatus "U2D1.DD83" )
				)
				( pin "vss(250)"
					( attribute "PN" "DD81"
						( Origin gPackager )
					)
					( objectStatus "U2D1.DD81" )
				)
				( pin "vss(251)"
					( attribute "PN" "DD75"
						( Origin gPackager )
					)
					( objectStatus "U2D1.DD75" )
				)
				( pin "vss(252)"
					( attribute "PN" "DD73"
						( Origin gPackager )
					)
					( objectStatus "U2D1.DD73" )
				)
				( pin "vss(253)"
					( attribute "PN" "DD71"
						( Origin gPackager )
					)
					( objectStatus "U2D1.DD71" )
				)
				( pin "vss(254)"
					( attribute "PN" "DD37"
						( Origin gPackager )
					)
					( objectStatus "U2D1.DD37" )
				)
				( pin "vss(255)"
					( attribute "PN" "DD33"
						( Origin gPackager )
					)
					( objectStatus "U2D1.DD33" )
				)
				( pin "vss(256)"
					( attribute "PN" "DD31"
						( Origin gPackager )
					)
					( objectStatus "U2D1.DD31" )
				)
				( pin "vss(257)"
					( attribute "PN" "DD27"
						( Origin gPackager )
					)
					( objectStatus "U2D1.DD27" )
				)
				( pin "vss(258)"
					( attribute "PN" "DD23"
						( Origin gPackager )
					)
					( objectStatus "U2D1.DD23" )
				)
				( pin "vss(259)"
					( attribute "PN" "DD11"
						( Origin gPackager )
					)
					( objectStatus "U2D1.DD11" )
				)
				( pin "vss(260)"
					( attribute "PN" "DC86"
						( Origin gPackager )
					)
					( objectStatus "U2D1.DC86" )
				)
				( pin "vss(261)"
					( attribute "PN" "DC84"
						( Origin gPackager )
					)
					( objectStatus "U2D1.DC84" )
				)
				( pin "vss(262)"
					( attribute "PN" "DC78"
						( Origin gPackager )
					)
					( objectStatus "U2D1.DC78" )
				)
				( pin "vss(263)"
					( attribute "PN" "DC70"
						( Origin gPackager )
					)
					( objectStatus "U2D1.DC70" )
				)
				( pin "vss(264)"
					( attribute "PN" "DC68"
						( Origin gPackager )
					)
					( objectStatus "U2D1.DC68" )
				)
				( pin "vss(265)"
					( attribute "PN" "DC66"
						( Origin gPackager )
					)
					( objectStatus "U2D1.DC66" )
				)
				( pin "vss(266)"
					( attribute "PN" "DC64"
						( Origin gPackager )
					)
					( objectStatus "U2D1.DC64" )
				)
				( pin "vss(267)"
					( attribute "PN" "DC42"
						( Origin gPackager )
					)
					( objectStatus "U2D1.DC42" )
				)
				( pin "vss(268)"
					( attribute "PN" "DC38"
						( Origin gPackager )
					)
					( objectStatus "U2D1.DC38" )
				)
				( pin "vss(269)"
					( attribute "PN" "DC32"
						( Origin gPackager )
					)
					( objectStatus "U2D1.DC32" )
				)
				( pin "vss(270)"
					( attribute "PN" "DC26"
						( Origin gPackager )
					)
					( objectStatus "U2D1.DC26" )
				)
				( pin "vss(271)"
					( attribute "PN" "DC24"
						( Origin gPackager )
					)
					( objectStatus "U2D1.DC24" )
				)
				( pin "vss(272)"
					( attribute "PN" "DC14"
						( Origin gPackager )
					)
					( objectStatus "U2D1.DC14" )
				)
				( pin "vss(273)"
					( attribute "PN" "DB85"
						( Origin gPackager )
					)
					( objectStatus "U2D1.DB85" )
				)
				( pin "vss(274)"
					( attribute "PN" "DB83"
						( Origin gPackager )
					)
					( objectStatus "U2D1.DB83" )
				)
				( pin "vss(275)"
					( attribute "PN" "DB77"
						( Origin gPackager )
					)
					( objectStatus "U2D1.DB77" )
				)
				( pin "vss(276)"
					( attribute "PN" "DB73"
						( Origin gPackager )
					)
					( objectStatus "U2D1.DB73" )
				)
				( pin "vss(277)"
					( attribute "PN" "DB49"
						( Origin gPackager )
					)
					( objectStatus "U2D1.DB49" )
				)
				( pin "vss(278)"
					( attribute "PN" "DB47"
						( Origin gPackager )
					)
					( objectStatus "U2D1.DB47" )
				)
				( pin "vss(279)"
					( attribute "PN" "DB41"
						( Origin gPackager )
					)
					( objectStatus "U2D1.DB41" )
				)
				( pin "vss(280)"
					( attribute "PN" "DB39"
						( Origin gPackager )
					)
					( objectStatus "U2D1.DB39" )
				)
				( pin "vss(281)"
					( attribute "PN" "DB25"
						( Origin gPackager )
					)
					( objectStatus "U2D1.DB25" )
				)
				( pin "vss(282)"
					( attribute "PN" "DB23"
						( Origin gPackager )
					)
					( objectStatus "U2D1.DB23" )
				)
				( pin "vss(283)"
					( attribute "PN" "DB17"
						( Origin gPackager )
					)
					( objectStatus "U2D1.DB17" )
				)
				( pin "vss(284)"
					( attribute "PN" "DB13"
						( Origin gPackager )
					)
					( objectStatus "U2D1.DB13" )
				)
				( pin "vss(285)"
					( attribute "PN" "DB3"
						( Origin gPackager )
					)
					( objectStatus "U2D1.DB3" )
				)
				( pin "vss(286)"
					( attribute "PN" "DA80"
						( Origin gPackager )
					)
					( objectStatus "U2D1.DA80" )
				)
				( pin "vss(287)"
					( attribute "PN" "DA78"
						( Origin gPackager )
					)
					( objectStatus "U2D1.DA78" )
				)
				( pin "vss(288)"
					( attribute "PN" "DA76"
						( Origin gPackager )
					)
					( objectStatus "U2D1.DA76" )
				)
				( pin "vss(289)"
					( attribute "PN" "DA74"
						( Origin gPackager )
					)
					( objectStatus "U2D1.DA74" )
				)
				( pin "vss(290)"
					( attribute "PN" "DA70"
						( Origin gPackager )
					)
					( objectStatus "U2D1.DA70" )
				)
				( pin "vss(291)"
					( attribute "PN" "DA64"
						( Origin gPackager )
					)
					( objectStatus "U2D1.DA64" )
				)
				( pin "vss(292)"
					( attribute "PN" "DA50"
						( Origin gPackager )
					)
					( objectStatus "U2D1.DA50" )
				)
				( pin "vss(293)"
					( attribute "PN" "DA48"
						( Origin gPackager )
					)
					( objectStatus "U2D1.DA48" )
				)
			)
			( gate "@baseboard_fab2_lib.baseboard_fab2(sch_1):page75_i20"
				( attribute "CDS_LIB" "chpset_lib"
					( Origin gPackager )
				)
				( attribute "CDS_LOCATION" "U2D1"
					( Origin gPackager )
				)
				( attribute "CDS_SEC" "30"
					( Origin gPackager )
				)
				( attribute "LOCATION" "U2D1"
					( Origin gFrontEnd )
				)
				( attribute "MATERIAL" "IC"
					( Origin gFrontEnd )
				)
				( attribute "PACK_TYPE" "BGA1"
					( Origin gFrontEnd )
				)
				( attribute "PART_NUMBER" "TBD"
					( Origin gFrontEnd )
				)
				( attribute "PHYS_PAGE" "75"
					( Origin gFrontEnd )
				)
				( attribute "ROT" "0"
					( Origin gFrontEnd )
				)
				( attribute "SEC" "30"
					( Origin gFrontEnd )
				)
				( attribute "SEC_TYPE" "BGA1"
					( Origin gFrontEnd )
				)
				( attribute "VER" "30"
					( Origin gFrontEnd )
				)
				( attribute "XY" "(-1225,2550)"
					( Origin gFrontEnd )
				)
				( attribute "CHIPS_PART_NAME" "SKX_EXT_B"
					( Origin gPackager )
				)
				( attribute "CDS_PART_NAME" "SKX_EXT_B_BGA1-IC,TBD"
					( Origin gPackager )
				)
				( objectStatus "U2D1" )
				( pin "vss(0)"
					( attribute "PN" "EF79"
						( Origin gPackager )
					)
					( objectStatus "U2D1.EF79" )
				)
				( pin "vss(1)"
					( attribute "PN" "EF75"
						( Origin gPackager )
					)
					( objectStatus "U2D1.EF75" )
				)
				( pin "vss(2)"
					( attribute "PN" "EF71"
						( Origin gPackager )
					)
					( objectStatus "U2D1.EF71" )
				)
				( pin "vss(3)"
					( attribute "PN" "EE78"
						( Origin gPackager )
					)
					( objectStatus "U2D1.EE78" )
				)
				( pin "vss(4)"
					( attribute "PN" "EE76"
						( Origin gPackager )
					)
					( objectStatus "U2D1.EE76" )
				)
				( pin "vss(5)"
					( attribute "PN" "EE70"
						( Origin gPackager )
					)
					( objectStatus "U2D1.EE70" )
				)
				( pin "vss(6)"
					( attribute "PN" "EE36"
						( Origin gPackager )
					)
					( objectStatus "U2D1.EE36" )
				)
				( pin "vss(7)"
					( attribute "PN" "EE34"
						( Origin gPackager )
					)
					( objectStatus "U2D1.EE34" )
				)
				( pin "vss(8)"
					( attribute "PN" "EE30"
						( Origin gPackager )
					)
					( objectStatus "U2D1.EE30" )
				)
				( pin "vss(9)"
					( attribute "PN" "EE28"
						( Origin gPackager )
					)
					( objectStatus "U2D1.EE28" )
				)
				( pin "vss(10)"
					( attribute "PN" "EE24"
						( Origin gPackager )
					)
					( objectStatus "U2D1.EE24" )
				)
				( pin "vss(11)"
					( attribute "PN" "ED77"
						( Origin gPackager )
					)
					( objectStatus "U2D1.ED77" )
				)
				( pin "vss(12)"
					( attribute "PN" "ED35"
						( Origin gPackager )
					)
					( objectStatus "U2D1.ED35" )
				)
				( pin "vss(13)"
					( attribute "PN" "ED29"
						( Origin gPackager )
					)
					( objectStatus "U2D1.ED29" )
				)
				( pin "vss(14)"
					( attribute "PN" "ED23"
						( Origin gPackager )
					)
					( objectStatus "U2D1.ED23" )
				)
				( pin "vss(15)"
					( attribute "PN" "ED15"
						( Origin gPackager )
					)
					( objectStatus "U2D1.ED15" )
				)
				( pin "vss(16)"
					( attribute "PN" "ED11"
						( Origin gPackager )
					)
					( objectStatus "U2D1.ED11" )
				)
				( pin "vss(17)"
					( attribute "PN" "EC76"
						( Origin gPackager )
					)
					( objectStatus "U2D1.EC76" )
				)
				( pin "vss(18)"
					( attribute "PN" "EC74"
						( Origin gPackager )
					)
					( objectStatus "U2D1.EC74" )
				)
				( pin "vss(19)"
					( attribute "PN" "EC72"
						( Origin gPackager )
					)
					( objectStatus "U2D1.EC72" )
				)
				( pin "vss(20)"
					( attribute "PN" "EC70"
						( Origin gPackager )
					)
					( objectStatus "U2D1.EC70" )
				)
				( pin "vss(21)"
					( attribute "PN" "EC10"
						( Origin gPackager )
					)
					( objectStatus "U2D1.EC10" )
				)
				( pin "vss(22)"
					( attribute "PN" "EB69"
						( Origin gPackager )
					)
					( objectStatus "U2D1.EB69" )
				)
				( pin "vss(23)"
					( attribute "PN" "EB65"
						( Origin gPackager )
					)
					( objectStatus "U2D1.EB65" )
				)
				( pin "vss(24)"
					( attribute "PN" "EB41"
						( Origin gPackager )
					)
					( objectStatus "U2D1.EB41" )
				)
				( pin "vss(25)"
					( attribute "PN" "EB39"
						( Origin gPackager )
					)
					( objectStatus "U2D1.EB39" )
				)
				( pin "vss(26)"
					( attribute "PN" "EB37"
						( Origin gPackager )
					)
					( objectStatus "U2D1.EB37" )
				)
				( pin "vss(27)"
					( attribute "PN" "EB35"
						( Origin gPackager )
					)
					( objectStatus "U2D1.EB35" )
				)
				( pin "vss(28)"
					( attribute "PN" "EB33"
						( Origin gPackager )
					)
					( objectStatus "U2D1.EB33" )
				)
				( pin "vss(29)"
					( attribute "PN" "EB31"
						( Origin gPackager )
					)
					( objectStatus "U2D1.EB31" )
				)
				( pin "vss(30)"
					( attribute "PN" "EB29"
						( Origin gPackager )
					)
					( objectStatus "U2D1.EB29" )
				)
				( pin "vss(31)"
					( attribute "PN" "EB27"
						( Origin gPackager )
					)
					( objectStatus "U2D1.EB27" )
				)
				( pin "vss(32)"
					( attribute "PN" "EB25"
						( Origin gPackager )
					)
					( objectStatus "U2D1.EB25" )
				)
				( pin "vss(33)"
					( attribute "PN" "EB23"
						( Origin gPackager )
					)
					( objectStatus "U2D1.EB23" )
				)
				( pin "vss(34)"
					( attribute "PN" "BR18"
						( Origin gPackager )
					)
					( objectStatus "U2D1.BR18" )
				)
				( pin "vss(35)"
					( attribute "PN" "EB13"
						( Origin gPackager )
					)
					( objectStatus "U2D1.EB13" )
				)
				( pin "vss(36)"
					( attribute "PN" "EA82"
						( Origin gPackager )
					)
					( objectStatus "U2D1.EA82" )
				)
				( pin "vss(37)"
					( attribute "PN" "EA80"
						( Origin gPackager )
					)
					( objectStatus "U2D1.EA80" )
				)
				( pin "vss(38)"
					( attribute "PN" "EA78"
						( Origin gPackager )
					)
					( objectStatus "U2D1.EA78" )
				)
				( pin "vss(39)"
					( attribute "PN" "EA76"
						( Origin gPackager )
					)
					( objectStatus "U2D1.EA76" )
				)
				( pin "vss(40)"
					( attribute "PN" "EA70"
						( Origin gPackager )
					)
					( objectStatus "U2D1.EA70" )
				)
				( pin "vss(41)"
					( attribute "PN" "EA64"
						( Origin gPackager )
					)
					( objectStatus "U2D1.EA64" )
				)
				( pin "vss(42)"
					( attribute "PN" "EA42"
						( Origin gPackager )
					)
					( objectStatus "U2D1.EA42" )
				)
				( pin "vss(43)"
					( attribute "PN" "EA22"
						( Origin gPackager )
					)
					( objectStatus "U2D1.EA22" )
				)
				( pin "vss(44)"
					( attribute "PN" "EA20"
						( Origin gPackager )
					)
					( objectStatus "U2D1.EA20" )
				)
				( pin "vss(45)"
					( attribute "PN" "EA16"
						( Origin gPackager )
					)
					( objectStatus "U2D1.EA16" )
				)
				( pin "vss(46)"
					( attribute "PN" "J16"
						( Origin gPackager )
					)
					( objectStatus "U2D1.J16" )
				)
				( pin "vss(47)"
					( attribute "PN" "EA6"
						( Origin gPackager )
					)
					( objectStatus "U2D1.EA6" )
				)
				( pin "vss(48)"
					( attribute "PN" "DY75"
						( Origin gPackager )
					)
					( objectStatus "U2D1.DY75" )
				)
				( pin "vss(49)"
					( attribute "PN" "DY71"
						( Origin gPackager )
					)
					( objectStatus "U2D1.DY71" )
				)
				( pin "vss(50)"
					( attribute "PN" "DY41"
						( Origin gPackager )
					)
					( objectStatus "U2D1.DY41" )
				)
				( pin "vss(51)"
					( attribute "PN" "DY35"
						( Origin gPackager )
					)
					( objectStatus "U2D1.DY35" )
				)
				( pin "vss(52)"
					( attribute "PN" "DY29"
						( Origin gPackager )
					)
					( objectStatus "U2D1.DY29" )
				)
				( pin "vss(53)"
					( attribute "PN" "DY23"
						( Origin gPackager )
					)
					( objectStatus "U2D1.DY23" )
				)
				( pin "vss(54)"
					( attribute "PN" "DY19"
						( Origin gPackager )
					)
					( objectStatus "U2D1.DY19" )
				)
				( pin "vss(55)"
					( attribute "PN" "DY5"
						( Origin gPackager )
					)
					( objectStatus "U2D1.DY5" )
				)
				( pin "vss(56)"
					( attribute "PN" "DW84"
						( Origin gPackager )
					)
					( objectStatus "U2D1.DW84" )
				)
				( pin "vss(57)"
					( attribute "PN" "DW82"
						( Origin gPackager )
					)
					( objectStatus "U2D1.DW82" )
				)
				( pin "vss(58)"
					( attribute "PN" "DW8"
						( Origin gPackager )
					)
					( objectStatus "U2D1.DW8" )
				)
				( pin "vss(59)"
					( attribute "PN" "DW76"
						( Origin gPackager )
					)
					( objectStatus "U2D1.DW76" )
				)
				( pin "vss(60)"
					( attribute "PN" "DW74"
						( Origin gPackager )
					)
					( objectStatus "U2D1.DW74" )
				)
				( pin "vss(61)"
					( attribute "PN" "DW72"
						( Origin gPackager )
					)
					( objectStatus "U2D1.DW72" )
				)
				( pin "vss(62)"
					( attribute "PN" "DW70"
						( Origin gPackager )
					)
					( objectStatus "U2D1.DW70" )
				)
				( pin "vss(63)"
					( attribute "PN" "DW68"
						( Origin gPackager )
					)
					( objectStatus "U2D1.DW68" )
				)
				( pin "vss(64)"
					( attribute "PN" "DW66"
						( Origin gPackager )
					)
					( objectStatus "U2D1.DW66" )
				)
				( pin "vss(65)"
					( attribute "PN" "DW64"
						( Origin gPackager )
					)
					( objectStatus "U2D1.DW64" )
				)
				( pin "vss(66)"
					( attribute "PN" "DW40"
						( Origin gPackager )
					)
					( objectStatus "U2D1.DW40" )
				)
				( pin "vss(67)"
					( attribute "PN" "DW36"
						( Origin gPackager )
					)
					( objectStatus "U2D1.DW36" )
				)
				( pin "vss(68)"
					( attribute "PN" "DW34"
						( Origin gPackager )
					)
					( objectStatus "U2D1.DW34" )
				)
				( pin "vss(69)"
					( attribute "PN" "DW30"
						( Origin gPackager )
					)
					( objectStatus "U2D1.DW30" )
				)
				( pin "vss(70)"
					( attribute "PN" "DW28"
						( Origin gPackager )
					)
					( objectStatus "U2D1.DW28" )
				)
				( pin "vss(71)"
					( attribute "PN" "DW24"
						( Origin gPackager )
					)
					( objectStatus "U2D1.DW24" )
				)
				( pin "vss(72)"
					( attribute "PN" "DW20"
						( Origin gPackager )
					)
					( objectStatus "U2D1.DW20" )
				)
				( pin "vss(73)"
					( attribute "PN" "DW12"
						( Origin gPackager )
					)
					( objectStatus "U2D1.DW12" )
				)
				( pin "vss(74)"
					( attribute "PN" "DV81"
						( Origin gPackager )
					)
					( objectStatus "U2D1.DV81" )
				)
				( pin "vss(75)"
					( attribute "PN" "DV77"
						( Origin gPackager )
					)
					( objectStatus "U2D1.DV77" )
				)
				( pin "vss(76)"
					( attribute "PN" "DV73"
						( Origin gPackager )
					)
					( objectStatus "U2D1.DV73" )
				)
				( pin "vss(77)"
					( attribute "PN" "DV39"
						( Origin gPackager )
					)
					( objectStatus "U2D1.DV39" )
				)
				( pin "vss(78)"
					( attribute "PN" "DV37"
						( Origin gPackager )
					)
					( objectStatus "U2D1.DV37" )
				)
				( pin "vss(79)"
					( attribute "PN" "DV33"
						( Origin gPackager )
					)
					( objectStatus "U2D1.DV33" )
				)
				( pin "vss(80)"
					( attribute "PN" "DV31"
						( Origin gPackager )
					)
					( objectStatus "U2D1.DV31" )
				)
				( pin "vss(81)"
					( attribute "PN" "DV27"
						( Origin gPackager )
					)
					( objectStatus "U2D1.DV27" )
				)
				( pin "vss(82)"
					( attribute "PN" "DV25"
						( Origin gPackager )
					)
					( objectStatus "U2D1.DV25" )
				)
				( pin "vss(83)"
					( attribute "PN" "DV21"
						( Origin gPackager )
					)
					( objectStatus "U2D1.DV21" )
				)
				( pin "vss(84)"
					( attribute "PN" "DU84"
						( Origin gPackager )
					)
					( objectStatus "U2D1.DU84" )
				)
				( pin "vss(85)"
					( attribute "PN" "DU82"
						( Origin gPackager )
					)
					( objectStatus "U2D1.DU82" )
				)
				( pin "vss(86)"
					( attribute "PN" "DU80"
						( Origin gPackager )
					)
					( objectStatus "U2D1.DU80" )
				)
				( pin "vss(87)"
					( attribute "PN" "DU78"
						( Origin gPackager )
					)
					( objectStatus "U2D1.DU78" )
				)
				( pin "vss(88)"
					( attribute "PN" "DU72"
						( Origin gPackager )
					)
					( objectStatus "U2D1.DU72" )
				)
				( pin "vss(89)"
					( attribute "PN" "DU70"
						( Origin gPackager )
					)
					( objectStatus "U2D1.DU70" )
				)
				( pin "vss(90)"
					( attribute "PN" "DU38"
						( Origin gPackager )
					)
					( objectStatus "U2D1.DU38" )
				)
				( pin "vss(91)"
					( attribute "PN" "DU32"
						( Origin gPackager )
					)
					( objectStatus "U2D1.DU32" )
				)
				( pin "vss(92)"
					( attribute "PN" "DU26"
						( Origin gPackager )
					)
					( objectStatus "U2D1.DU26" )
				)
				( pin "vss(93)"
					( attribute "PN" "DU22"
						( Origin gPackager )
					)
					( objectStatus "U2D1.DU22" )
				)
				( pin "vss(94)"
					( attribute "PN" "CN14"
						( Origin gPackager )
					)
					( objectStatus "U2D1.CN14" )
				)
				( pin "vss(95)"
					( attribute "PN" "DU14"
						( Origin gPackager )
					)
					( objectStatus "U2D1.DU14" )
				)
				( pin "vss(96)"
					( attribute "PN" "DU10"
						( Origin gPackager )
					)
					( objectStatus "U2D1.DU10" )
				)
				( pin "vss(97)"
					( attribute "PN" "DT85"
						( Origin gPackager )
					)
					( objectStatus "U2D1.DT85" )
				)
				( pin "vss(98)"
					( attribute "PN" "DT83"
						( Origin gPackager )
					)
					( objectStatus "U2D1.DT83" )
				)
				( pin "vss(99)"
					( attribute "PN" "DT79"
						( Origin gPackager )
					)
					( objectStatus "U2D1.DT79" )
				)
				( pin "vss(100)"
					( attribute "PN" "DT69"
						( Origin gPackager )
					)
					( objectStatus "U2D1.DT69" )
				)
				( pin "vss(101)"
					( attribute "PN" "DT65"
						( Origin gPackager )
					)
					( objectStatus "U2D1.DT65" )
				)
				( pin "vss(102)"
					( attribute "PN" "DH21"
						( Origin gPackager )
					)
					( objectStatus "U2D1.DH21" )
				)
				( pin "vss(103)"
					( attribute "PN" "DT17"
						( Origin gPackager )
					)
					( objectStatus "U2D1.DT17" )
				)
				( pin "vss(104)"
					( attribute "PN" "DT3"
						( Origin gPackager )
					)
					( objectStatus "U2D1.DT3" )
				)
				( pin "vss(105)"
					( attribute "PN" "DR78"
						( Origin gPackager )
					)
					( objectStatus "U2D1.DR78" )
				)
				( pin "vss(106)"
					( attribute "PN" "DR76"
						( Origin gPackager )
					)
					( objectStatus "U2D1.DR76" )
				)
				( pin "vss(107)"
					( attribute "PN" "DR74"
						( Origin gPackager )
					)
					( objectStatus "U2D1.DR74" )
				)
				( pin "vss(108)"
					( attribute "PN" "DR72"
						( Origin gPackager )
					)
					( objectStatus "U2D1.DR72" )
				)
				( pin "vss(109)"
					( attribute "PN" "DR70"
						( Origin gPackager )
					)
					( objectStatus "U2D1.DR70" )
				)
				( pin "vss(110)"
					( attribute "PN" "DR68"
						( Origin gPackager )
					)
					( objectStatus "U2D1.DR68" )
				)
				( pin "vss(111)"
					( attribute "PN" "DR66"
						( Origin gPackager )
					)
					( objectStatus "U2D1.DR66" )
				)
				( pin "vss(112)"
					( attribute "PN" "DR42"
						( Origin gPackager )
					)
					( objectStatus "U2D1.DR42" )
				)
				( pin "vss(113)"
					( attribute "PN" "DR40"
						( Origin gPackager )
					)
					( objectStatus "U2D1.DR40" )
				)
				( pin "vss(114)"
					( attribute "PN" "DR38"
						( Origin gPackager )
					)
					( objectStatus "U2D1.DR38" )
				)
				( pin "vss(115)"
					( attribute "PN" "DR36"
						( Origin gPackager )
					)
					( objectStatus "U2D1.DR36" )
				)
				( pin "vss(116)"
					( attribute "PN" "DR34"
						( Origin gPackager )
					)
					( objectStatus "U2D1.DR34" )
				)
				( pin "vss(117)"
					( attribute "PN" "DR32"
						( Origin gPackager )
					)
					( objectStatus "U2D1.DR32" )
				)
				( pin "vss(118)"
					( attribute "PN" "DR30"
						( Origin gPackager )
					)
					( objectStatus "U2D1.DR30" )
				)
				( pin "vss(119)"
					( attribute "PN" "DR28"
						( Origin gPackager )
					)
					( objectStatus "U2D1.DR28" )
				)
				( pin "vss(120)"
					( attribute "PN" "DR26"
						( Origin gPackager )
					)
					( objectStatus "U2D1.DR26" )
				)
				( pin "vss(121)"
					( attribute "PN" "DR24"
						( Origin gPackager )
					)
					( objectStatus "U2D1.DR24" )
				)
				( pin "vss(122)"
					( attribute "PN" "DR22"
						( Origin gPackager )
					)
					( objectStatus "U2D1.DR22" )
				)
				( pin "vss(123)"
					( attribute "PN" "DR20"
						( Origin gPackager )
					)
					( objectStatus "U2D1.DR20" )
				)
				( pin "vss(124)"
					( attribute "PN" "CL22"
						( Origin gPackager )
					)
					( objectStatus "U2D1.CL22" )
				)
				( pin "vss(125)"
					( attribute "PN" "CA20"
						( Origin gPackager )
					)
					( objectStatus "U2D1.CA20" )
				)
				( pin "vss(126)"
					( attribute "PN" "DR6"
						( Origin gPackager )
					)
					( objectStatus "U2D1.DR6" )
				)
				( pin "vss(127)"
					( attribute "PN" "BR26"
						( Origin gPackager )
					)
					( objectStatus "U2D1.BR26" )
				)
				( pin "vss(128)"
					( attribute "PN" "DP83"
						( Origin gPackager )
					)
					( objectStatus "U2D1.DP83" )
				)
				( pin "vss(129)"
					( attribute "PN" "DP81"
						( Origin gPackager )
					)
					( objectStatus "U2D1.DP81" )
				)
				( pin "vss(130)"
					( attribute "PN" "DP71"
						( Origin gPackager )
					)
					( objectStatus "U2D1.DP71" )
				)
				( pin "vss(131)"
					( attribute "PN" "DP69"
						( Origin gPackager )
					)
					( objectStatus "U2D1.DP69" )
				)
				( pin "vss(132)"
					( attribute "PN" "DP67"
						( Origin gPackager )
					)
					( objectStatus "U2D1.DP67" )
				)
				( pin "vss(133)"
					( attribute "PN" "DN78"
						( Origin gPackager )
					)
					( objectStatus "U2D1.DN78" )
				)
			)
			( gate "@baseboard_fab2_lib.baseboard_fab2(sch_1):page76_i1"
				( attribute "BOM_COST" "PROC"
					( Origin gFrontEnd )
				)
				( attribute "CDS_LIB" "dev_discrete"
					( Origin gPackager )
				)
				( attribute "CDS_LOCATION" "C3D21"
					( Origin gPackager )
				)
				( attribute "CDS_SEC" "1"
					( Origin gPackager )
				)
				( attribute "LOCATION" "C3D21"
					( Origin gFrontEnd )
				)
				( attribute "MATERIAL" "X6S"
					( Origin gFrontEnd )
				)
				( attribute "PACK_TYPE" "0603V"
					( Origin gFrontEnd )
				)
				( attribute "PART_NUMBER" "E15431-004"
					( Origin gFrontEnd )
				)
				( attribute "PHYS_PAGE" "76"
					( Origin gFrontEnd )
				)
				( attribute "ROOM" "PVCCIN_CPU1_DECAP_VR"
					( Origin gFrontEnd )
				)
				( attribute "ROT" "0"
					( Origin gFrontEnd )
				)
				( attribute "SEC" "1"
					( Origin gPackager )
				)
				( attribute "TOLERANCE" "20%"
					( Origin gFrontEnd )
				)
				( attribute "VALUE" "22.0UF"
					( Origin gFrontEnd )
				)
				( attribute "VER" "1"
					( Origin gFrontEnd )
				)
				( attribute "VOLTAGE" "4V"
					( Units "uVoltage" "V" 1.000000)
					( Origin gFrontEnd )
				)
				( attribute "XY" "(-1275,4450)"
					( Origin gFrontEnd )
				)
				( attribute "CHIPS_PART_NAME" "CAP_A"
					( Origin gPackager )
				)
				( attribute "CDS_PART_NAME" "CAP_A_0603V-22.0UF,4V,20%,X6S,A"
					( Origin gPackager )
				)
				( objectStatus "C3D21" )
				( pin "a"
					( attribute "PN" "1"
						( Origin gPackager )
					)
					( objectStatus "C3D21.1" )
				)
				( pin "b"
					( attribute "PN" "2"
						( Origin gPackager )
					)
					( objectStatus "C3D21.2" )
				)
			)
			( gate "@baseboard_fab2_lib.baseboard_fab2(sch_1):page76_i3"
				( attribute "BOM_COST" "PROC"
					( Origin gFrontEnd )
				)
				( attribute "CDS_LIB" "dev_discrete"
					( Origin gPackager )
				)
				( attribute "CDS_LOCATION" "C3D5"
					( Origin gPackager )
				)
				( attribute "CDS_SEC" "1"
					( Origin gPackager )
				)
				( attribute "LOCATION" "C3D5"
					( Origin gFrontEnd )
				)
				( attribute "MATERIAL" "X6S"
					( Origin gFrontEnd )
				)
				( attribute "PACK_TYPE" "0603V"
					( Origin gFrontEnd )
				)
				( attribute "PART_NUMBER" "E15431-004"
					( Origin gFrontEnd )
				)
				( attribute "PHYS_PAGE" "76"
					( Origin gFrontEnd )
				)
				( attribute "ROOM" "PVCCIN_CPU1_DECAP_VR"
					( Origin gFrontEnd )
				)
				( attribute "ROT" "0"
					( Origin gFrontEnd )
				)
				( attribute "SEC" "1"
					( Origin gPackager )
				)
				( attribute "TOLERANCE" "20%"
					( Origin gFrontEnd )
				)
				( attribute "VALUE" "22.0UF"
					( Origin gFrontEnd )
				)
				( attribute "VER" "1"
					( Origin gFrontEnd )
				)
				( attribute "VOLTAGE" "4V"
					( Units "uVoltage" "V" 1.000000)
					( Origin gFrontEnd )
				)
				( attribute "XY" "(-1600,4450)"
					( Origin gFrontEnd )
				)
				( attribute "CHIPS_PART_NAME" "CAP_A"
					( Origin gPackager )
				)
				( attribute "CDS_PART_NAME" "CAP_A_0603V-22.0UF,4V,20%,X6S,A"
					( Origin gPackager )
				)
				( objectStatus "C3D5" )
				( pin "a"
					( attribute "PN" "1"
						( Origin gPackager )
					)
					( objectStatus "C3D5.1" )
				)
				( pin "b"
					( attribute "PN" "2"
						( Origin gPackager )
					)
					( objectStatus "C3D5.2" )
				)
			)
			( gate "@baseboard_fab2_lib.baseboard_fab2(sch_1):page76_i4"
				( attribute "BOM_COST" "PROC"
					( Origin gFrontEnd )
				)
				( attribute "CDS_LIB" "dev_discrete"
					( Origin gPackager )
				)
				( attribute "CDS_LOCATION" "C3D12"
					( Origin gPackager )
				)
				( attribute "CDS_SEC" "1"
					( Origin gPackager )
				)
				( attribute "LOCATION" "C3D12"
					( Origin gFrontEnd )
				)
				( attribute "MATERIAL" "X6S"
					( Origin gFrontEnd )
				)
				( attribute "PACK_TYPE" "0603V"
					( Origin gFrontEnd )
				)
				( attribute "PART_NUMBER" "E15431-004"
					( Origin gFrontEnd )
				)
				( attribute "PHYS_PAGE" "76"
					( Origin gFrontEnd )
				)
				( attribute "ROOM" "PVCCIN_CPU1_DECAP_VR"
					( Origin gFrontEnd )
				)
				( attribute "ROT" "0"
					( Origin gFrontEnd )
				)
				( attribute "SEC" "1"
					( Origin gPackager )
				)
				( attribute "TOLERANCE" "20%"
					( Origin gFrontEnd )
				)
				( attribute "VALUE" "22.0UF"
					( Origin gFrontEnd )
				)
				( attribute "VER" "1"
					( Origin gFrontEnd )
				)
				( attribute "VOLTAGE" "4V"
					( Units "uVoltage" "V" 1.000000)
					( Origin gFrontEnd )
				)
				( attribute "XY" "(-1875,4450)"
					( Origin gFrontEnd )
				)
				( attribute "CHIPS_PART_NAME" "CAP_A"
					( Origin gPackager )
				)
				( attribute "CDS_PART_NAME" "CAP_A_0603V-22.0UF,4V,20%,X6S,A"
					( Origin gPackager )
				)
				( objectStatus "C3D12" )
				( pin "a"
					( attribute "PN" "1"
						( Origin gPackager )
					)
					( objectStatus "C3D12.1" )
				)
				( pin "b"
					( attribute "PN" "2"
						( Origin gPackager )
					)
					( objectStatus "C3D12.2" )
				)
			)
			( gate "@baseboard_fab2_lib.baseboard_fab2(sch_1):page76_i5"
				( attribute "BOM_COST" "PROC"
					( Origin gFrontEnd )
				)
				( attribute "CDS_LIB" "dev_discrete"
					( Origin gPackager )
				)
				( attribute "CDS_LOCATION" "C3D4"
					( Origin gPackager )
				)
				( attribute "CDS_SEC" "1"
					( Origin gPackager )
				)
				( attribute "LOCATION" "C3D4"
					( Origin gFrontEnd )
				)
				( attribute "MATERIAL" "X6S"
					( Origin gFrontEnd )
				)
				( attribute "PACK_TYPE" "0603V"
					( Origin gFrontEnd )
				)
				( attribute "PART_NUMBER" "E15431-004"
					( Origin gFrontEnd )
				)
				( attribute "PHYS_PAGE" "76"
					( Origin gFrontEnd )
				)
				( attribute "ROOM" "PVCCIN_CPU1_DECAP_VR"
					( Origin gFrontEnd )
				)
				( attribute "ROT" "0"
					( Origin gFrontEnd )
				)
				( attribute "SEC" "1"
					( Origin gPackager )
				)
				( attribute "TOLERANCE" "20%"
					( Origin gFrontEnd )
				)
				( attribute "VALUE" "22.0UF"
					( Origin gFrontEnd )
				)
				( attribute "VER" "1"
					( Origin gFrontEnd )
				)
				( attribute "VOLTAGE" "4V"
					( Units "uVoltage" "V" 1.000000)
					( Origin gFrontEnd )
				)
				( attribute "XY" "(-2175,4450)"
					( Origin gFrontEnd )
				)
				( attribute "CHIPS_PART_NAME" "CAP_A"
					( Origin gPackager )
				)
				( attribute "CDS_PART_NAME" "CAP_A_0603V-22.0UF,4V,20%,X6S,A"
					( Origin gPackager )
				)
				( objectStatus "C3D4" )
				( pin "a"
					( attribute "PN" "1"
						( Origin gPackager )
					)
					( objectStatus "C3D4.1" )
				)
				( pin "b"
					( attribute "PN" "2"
						( Origin gPackager )
					)
					( objectStatus "C3D4.2" )
				)
			)
			( gate "@baseboard_fab2_lib.baseboard_fab2(sch_1):page76_i7"
				( attribute "BOM_COST" "PROC"
					( Origin gFrontEnd )
				)
				( attribute "CDS_LIB" "dev_discrete"
					( Origin gPackager )
				)
				( attribute "CDS_LOCATION" "C3D11"
					( Origin gPackager )
				)
				( attribute "CDS_SEC" "1"
					( Origin gPackager )
				)
				( attribute "LOCATION" "C3D11"
					( Origin gFrontEnd )
				)
				( attribute "MATERIAL" "X6S"
					( Origin gFrontEnd )
				)
				( attribute "PACK_TYPE" "0603V"
					( Origin gFrontEnd )
				)
				( attribute "PART_NUMBER" "E15431-004"
					( Origin gFrontEnd )
				)
				( attribute "PHYS_PAGE" "76"
					( Origin gFrontEnd )
				)
				( attribute "ROOM" "PVCCIN_CPU1_DECAP_VR"
					( Origin gFrontEnd )
				)
				( attribute "ROT" "0"
					( Origin gFrontEnd )
				)
				( attribute "SEC" "1"
					( Origin gPackager )
				)
				( attribute "TOLERANCE" "20%"
					( Origin gFrontEnd )
				)
				( attribute "VALUE" "22.0UF"
					( Origin gFrontEnd )
				)
				( attribute "VER" "1"
					( Origin gFrontEnd )
				)
				( attribute "VOLTAGE" "4V"
					( Units "uVoltage" "V" 1.000000)
					( Origin gFrontEnd )
				)
				( attribute "XY" "(-2450,4450)"
					( Origin gFrontEnd )
				)
				( attribute "CHIPS_PART_NAME" "CAP_A"
					( Origin gPackager )
				)
				( attribute "CDS_PART_NAME" "CAP_A_0603V-22.0UF,4V,20%,X6S,A"
					( Origin gPackager )
				)
				( objectStatus "C3D11" )
				( pin "a"
					( attribute "PN" "1"
						( Origin gPackager )
					)
					( objectStatus "C3D11.1" )
				)
				( pin "b"
					( attribute "PN" "2"
						( Origin gPackager )
					)
					( objectStatus "C3D11.2" )
				)
			)
			( gate "@baseboard_fab2_lib.baseboard_fab2(sch_1):page76_i8"
				( attribute "BOM_COST" "PROC"
					( Origin gFrontEnd )
				)
				( attribute "CDS_LIB" "dev_discrete"
					( Origin gPackager )
				)
				( attribute "CDS_LOCATION" "C3D13"
					( Origin gPackager )
				)
				( attribute "CDS_SEC" "1"
					( Origin gPackager )
				)
				( attribute "LOCATION" "C3D13"
					( Origin gFrontEnd )
				)
				( attribute "MATERIAL" "X6S"
					( Origin gFrontEnd )
				)
				( attribute "PACK_TYPE" "0603V"
					( Origin gFrontEnd )
				)
				( attribute "PART_NUMBER" "E15431-004"
					( Origin gFrontEnd )
				)
				( attribute "PHYS_PAGE" "76"
					( Origin gFrontEnd )
				)
				( attribute "ROOM" "PVCCIN_CPU1_DECAP_VR"
					( Origin gFrontEnd )
				)
				( attribute "ROT" "0"
					( Origin gFrontEnd )
				)
				( attribute "SEC" "1"
					( Origin gPackager )
				)
				( attribute "TOLERANCE" "20%"
					( Origin gFrontEnd )
				)
				( attribute "VALUE" "22.0UF"
					( Origin gFrontEnd )
				)
				( attribute "VER" "1"
					( Origin gFrontEnd )
				)
				( attribute "VOLTAGE" "4V"
					( Units "uVoltage" "V" 1.000000)
					( Origin gFrontEnd )
				)
				( attribute "XY" "(-2975,4450)"
					( Origin gFrontEnd )
				)
				( attribute "CHIPS_PART_NAME" "CAP_A"
					( Origin gPackager )
				)
				( attribute "CDS_PART_NAME" "CAP_A_0603V-22.0UF,4V,20%,X6S,A"
					( Origin gPackager )
				)
				( objectStatus "C3D13" )
				( pin "a"
					( attribute "PN" "1"
						( Origin gPackager )
					)
					( objectStatus "C3D13.1" )
				)
				( pin "b"
					( attribute "PN" "2"
						( Origin gPackager )
					)
					( objectStatus "C3D13.2" )
				)
			)
			( gate "@baseboard_fab2_lib.baseboard_fab2(sch_1):page76_i10"
				( attribute "BOM_COST" "PROC"
					( Origin gFrontEnd )
				)
				( attribute "CDS_LIB" "dev_discrete"
					( Origin gPackager )
				)
				( attribute "CDS_LOCATION" "C2D40"
					( Origin gPackager )
				)
				( attribute "CDS_SEC" "1"
					( Origin gPackager )
				)
				( attribute "LOCATION" "C2D40"
					( Origin gFrontEnd )
				)
				( attribute "MATERIAL" "X6S"
					( Origin gFrontEnd )
				)
				( attribute "PACK_TYPE" "0603V"
					( Origin gFrontEnd )
				)
				( attribute "PART_NUMBER" "E15431-004"
					( Origin gFrontEnd )
				)
				( attribute "PHYS_PAGE" "76"
					( Origin gFrontEnd )
				)
				( attribute "ROOM" "PVCCIN_CPU1_DECAP_VR"
					( Origin gFrontEnd )
				)
				( attribute "ROT" "0"
					( Origin gFrontEnd )
				)
				( attribute "SEC" "1"
					( Origin gPackager )
				)
				( attribute "TOLERANCE" "20%"
					( Origin gFrontEnd )
				)
				( attribute "VALUE" "22.0UF"
					( Origin gFrontEnd )
				)
				( attribute "VER" "1"
					( Origin gFrontEnd )
				)
				( attribute "VOLTAGE" "4V"
					( Units "uVoltage" "V" 1.000000)
					( Origin gFrontEnd )
				)
				( attribute "XY" "(-3250,4425)"
					( Origin gFrontEnd )
				)
				( attribute "CHIPS_PART_NAME" "CAP_A"
					( Origin gPackager )
				)
				( attribute "CDS_PART_NAME" "CAP_A_0603V-22.0UF,4V,20%,X6S,A"
					( Origin gPackager )
				)
				( objectStatus "C2D40" )
				( pin "a"
					( attribute "PN" "1"
						( Origin gPackager )
					)
					( objectStatus "C2D40.1" )
				)
				( pin "b"
					( attribute "PN" "2"
						( Origin gPackager )
					)
					( objectStatus "C2D40.2" )
				)
			)
			( gate "@baseboard_fab2_lib.baseboard_fab2(sch_1):page76_i15"
				( attribute "BOM_COST" "PROC"
					( Origin gFrontEnd )
				)
				( attribute "CDS_LIB" "dev_discrete"
					( Origin gPackager )
				)
				( attribute "CDS_LOCATION" "C3D9"
					( Origin gPackager )
				)
				( attribute "CDS_SEC" "1"
					( Origin gPackager )
				)
				( attribute "LOCATION" "C3D9"
					( Origin gFrontEnd )
				)
				( attribute "MATERIAL" "X6S"
					( Origin gFrontEnd )
				)
				( attribute "PACK_TYPE" "0603V"
					( Origin gFrontEnd )
				)
				( attribute "PART_NUMBER" "E15431-004"
					( Origin gFrontEnd )
				)
				( attribute "PHYS_PAGE" "76"
					( Origin gFrontEnd )
				)
				( attribute "ROOM" "PVCCIN_CPU1_DECAP_VR"
					( Origin gFrontEnd )
				)
				( attribute "ROT" "0"
					( Origin gFrontEnd )
				)
				( attribute "SEC" "1"
					( Origin gPackager )
				)
				( attribute "TOLERANCE" "20%"
					( Origin gFrontEnd )
				)
				( attribute "VALUE" "22.0UF"
					( Origin gFrontEnd )
				)
				( attribute "VER" "1"
					( Origin gFrontEnd )
				)
				( attribute "VOLTAGE" "4V"
					( Units "uVoltage" "V" 1.000000)
					( Origin gFrontEnd )
				)
				( attribute "XY" "(-2450,3750)"
					( Origin gFrontEnd )
				)
				( attribute "CHIPS_PART_NAME" "CAP_A"
					( Origin gPackager )
				)
				( attribute "CDS_PART_NAME" "CAP_A_0603V-22.0UF,4V,20%,X6S,A"
					( Origin gPackager )
				)
				( objectStatus "C3D9" )
				( pin "a"
					( attribute "PN" "1"
						( Origin gPackager )
					)
					( objectStatus "C3D9.1" )
				)
				( pin "b"
					( attribute "PN" "2"
						( Origin gPackager )
					)
					( objectStatus "C3D9.2" )
				)
			)
			( gate "@baseboard_fab2_lib.baseboard_fab2(sch_1):page76_i18"
				( attribute "BOM_COST" "PROC"
					( Origin gFrontEnd )
				)
				( attribute "CDS_LIB" "dev_discrete"
					( Origin gPackager )
				)
				( attribute "CDS_LOCATION" "C3D8"
					( Origin gPackager )
				)
				( attribute "CDS_SEC" "1"
					( Origin gPackager )
				)
				( attribute "LOCATION" "C3D8"
					( Origin gFrontEnd )
				)
				( attribute "MATERIAL" "X6S"
					( Origin gFrontEnd )
				)
				( attribute "PACK_TYPE" "0603V"
					( Origin gFrontEnd )
				)
				( attribute "PART_NUMBER" "E15431-004"
					( Origin gFrontEnd )
				)
				( attribute "PHYS_PAGE" "76"
					( Origin gFrontEnd )
				)
				( attribute "ROOM" "PVCCIN_CPU1_DECAP_VR"
					( Origin gFrontEnd )
				)
				( attribute "ROT" "0"
					( Origin gFrontEnd )
				)
				( attribute "SEC" "1"
					( Origin gPackager )
				)
				( attribute "TOLERANCE" "20%"
					( Origin gFrontEnd )
				)
				( attribute "VALUE" "22.0UF"
					( Origin gFrontEnd )
				)
				( attribute "VER" "1"
					( Origin gFrontEnd )
				)
				( attribute "VOLTAGE" "4V"
					( Units "uVoltage" "V" 1.000000)
					( Origin gFrontEnd )
				)
				( attribute "XY" "(-2750,3775)"
					( Origin gFrontEnd )
				)
				( attribute "CHIPS_PART_NAME" "CAP_A"
					( Origin gPackager )
				)
				( attribute "CDS_PART_NAME" "CAP_A_0603V-22.0UF,4V,20%,X6S,A"
					( Origin gPackager )
				)
				( objectStatus "C3D8" )
				( pin "a"
					( attribute "PN" "1"
						( Origin gPackager )
					)
					( objectStatus "C3D8.1" )
				)
				( pin "b"
					( attribute "PN" "2"
						( Origin gPackager )
					)
					( objectStatus "C3D8.2" )
				)
			)
			( gate "@baseboard_fab2_lib.baseboard_fab2(sch_1):page76_i23"
				( attribute "BOM_COST" "PROC"
					( Origin gFrontEnd )
				)
				( attribute "CDS_LIB" "mstr_discrete"
					( Origin gPackager )
				)
				( attribute "CDS_LOCATION" "C7P6"
					( Origin gPackager )
				)
				( attribute "CDS_SEC" "1"
					( Origin gPackager )
				)
				( attribute "LOCATION" "C7P6"
					( Origin gFrontEnd )
				)
				( attribute "MATERIAL" "X6S"
					( Origin gFrontEnd )
				)
				( attribute "PACK_TYPE" "0805"
					( Origin gFrontEnd )
				)
				( attribute "PART_NUMBER" "C95333-006"
					( Origin gFrontEnd )
				)
				( attribute "PHYS_PAGE" "76"
					( Origin gFrontEnd )
				)
				( attribute "ROOM" "PVCCIN_CPU1_DECAP_VR"
					( Origin gFrontEnd )
				)
				( attribute "ROT" "0"
					( Origin gFrontEnd )
				)
				( attribute "SEC" "1"
					( Origin gPackager )
				)
				( attribute "TOLERANCE" "20%"
					( Origin gFrontEnd )
				)
				( attribute "VALUE" "47UF"
					( Origin gFrontEnd )
				)
				( attribute "VER" "1"
					( Origin gFrontEnd )
				)
				( attribute "VOLTAGE" "4V"
					( Units "uVoltage" "V" 1.000000)
					( Origin gFrontEnd )
				)
				( attribute "XY" "(-1750,2125)"
					( Origin gFrontEnd )
				)
				( attribute "CHIPS_PART_NAME" "CAP"
					( Origin gPackager )
				)
				( attribute "CDS_PART_NAME" "CAP_0805-47UF,4V,20%,X6S,C9533A"
					( Origin gPackager )
				)
				( objectStatus "C7P6" )
				( pin "a"
					( attribute "PN" "1"
						( Origin gPackager )
					)
					( objectStatus "C7P6.1" )
				)
				( pin "b"
					( attribute "PN" "2"
						( Origin gPackager )
					)
					( objectStatus "C7P6.2" )
				)
			)
			( gate "@baseboard_fab2_lib.baseboard_fab2(sch_1):page76_i25"
				( attribute "BOM_COST" "PROC"
					( Origin gFrontEnd )
				)
				( attribute "CDS_LIB" "mstr_discrete"
					( Origin gPackager )
				)
				( attribute "CDS_LOCATION" "C7P13"
					( Origin gPackager )
				)
				( attribute "CDS_SEC" "1"
					( Origin gPackager )
				)
				( attribute "LOCATION" "C7P13"
					( Origin gFrontEnd )
				)
				( attribute "MATERIAL" "X6S"
					( Origin gFrontEnd )
				)
				( attribute "PACK_TYPE" "0805"
					( Origin gFrontEnd )
				)
				( attribute "PART_NUMBER" "C95333-006"
					( Origin gFrontEnd )
				)
				( attribute "PHYS_PAGE" "76"
					( Origin gFrontEnd )
				)
				( attribute "ROOM" "PVCCIN_CPU1_DECAP_VR"
					( Origin gFrontEnd )
				)
				( attribute "ROT" "0"
					( Origin gFrontEnd )
				)
				( attribute "SEC" "1"
					( Origin gPackager )
				)
				( attribute "TOLERANCE" "20%"
					( Origin gFrontEnd )
				)
				( attribute "VALUE" "47UF"
					( Origin gFrontEnd )
				)
				( attribute "VER" "1"
					( Origin gFrontEnd )
				)
				( attribute "VOLTAGE" "4V"
					( Units "uVoltage" "V" 1.000000)
					( Origin gFrontEnd )
				)
				( attribute "XY" "(-2025,2150)"
					( Origin gFrontEnd )
				)
				( attribute "CHIPS_PART_NAME" "CAP"
					( Origin gPackager )
				)
				( attribute "CDS_PART_NAME" "CAP_0805-47UF,4V,20%,X6S,C9533A"
					( Origin gPackager )
				)
				( objectStatus "C7P13" )
				( pin "a"
					( attribute "PN" "1"
						( Origin gPackager )
					)
					( objectStatus "C7P13.1" )
				)
				( pin "b"
					( attribute "PN" "2"
						( Origin gPackager )
					)
					( objectStatus "C7P13.2" )
				)
			)
			( gate "@baseboard_fab2_lib.baseboard_fab2(sch_1):page76_i26"
				( attribute "BOM_COST" "PROC"
					( Origin gFrontEnd )
				)
				( attribute "CDS_LIB" "mstr_discrete"
					( Origin gPackager )
				)
				( attribute "CDS_LOCATION" "C7P10"
					( Origin gPackager )
				)
				( attribute "CDS_SEC" "1"
					( Origin gPackager )
				)
				( attribute "LOCATION" "C7P10"
					( Origin gFrontEnd )
				)
				( attribute "MATERIAL" "X6S"
					( Origin gFrontEnd )
				)
				( attribute "PACK_TYPE" "0805"
					( Origin gFrontEnd )
				)
				( attribute "PART_NUMBER" "C95333-006"
					( Origin gFrontEnd )
				)
				( attribute "PHYS_PAGE" "76"
					( Origin gFrontEnd )
				)
				( attribute "ROOM" "PVCCIN_CPU1_DECAP_VR"
					( Origin gFrontEnd )
				)
				( attribute "ROT" "0"
					( Origin gFrontEnd )
				)
				( attribute "SEC" "1"
					( Origin gPackager )
				)
				( attribute "TOLERANCE" "20%"
					( Origin gFrontEnd )
				)
				( attribute "VALUE" "47UF"
					( Origin gFrontEnd )
				)
				( attribute "VER" "1"
					( Origin gFrontEnd )
				)
				( attribute "VOLTAGE" "4V"
					( Units "uVoltage" "V" 1.000000)
					( Origin gFrontEnd )
				)
				( attribute "XY" "(-2325,2150)"
					( Origin gFrontEnd )
				)
				( attribute "CHIPS_PART_NAME" "CAP"
					( Origin gPackager )
				)
				( attribute "CDS_PART_NAME" "CAP_0805-47UF,4V,20%,X6S,C9533A"
					( Origin gPackager )
				)
				( objectStatus "C7P10" )
				( pin "a"
					( attribute "PN" "1"
						( Origin gPackager )
					)
					( objectStatus "C7P10.1" )
				)
				( pin "b"
					( attribute "PN" "2"
						( Origin gPackager )
					)
					( objectStatus "C7P10.2" )
				)
			)
			( gate "@baseboard_fab2_lib.baseboard_fab2(sch_1):page76_i27"
				( attribute "BOM_COST" "PROC"
					( Origin gFrontEnd )
				)
				( attribute "CDS_LIB" "mstr_discrete"
					( Origin gPackager )
				)
				( attribute "CDS_LOCATION" "C7P7"
					( Origin gPackager )
				)
				( attribute "CDS_SEC" "1"
					( Origin gPackager )
				)
				( attribute "LOCATION" "C7P7"
					( Origin gFrontEnd )
				)
				( attribute "MATERIAL" "X6S"
					( Origin gFrontEnd )
				)
				( attribute "PACK_TYPE" "0805"
					( Origin gFrontEnd )
				)
				( attribute "PART_NUMBER" "C95333-006"
					( Origin gFrontEnd )
				)
				( attribute "PHYS_PAGE" "76"
					( Origin gFrontEnd )
				)
				( attribute "ROOM" "PVCCIN_CPU1_DECAP_VR"
					( Origin gFrontEnd )
				)
				( attribute "ROT" "0"
					( Origin gFrontEnd )
				)
				( attribute "SEC" "1"
					( Origin gPackager )
				)
				( attribute "TOLERANCE" "20%"
					( Origin gFrontEnd )
				)
				( attribute "VALUE" "47UF"
					( Origin gFrontEnd )
				)
				( attribute "VER" "1"
					( Origin gFrontEnd )
				)
				( attribute "VOLTAGE" "4V"
					( Units "uVoltage" "V" 1.000000)
					( Origin gFrontEnd )
				)
				( attribute "XY" "(-2625,2150)"
					( Origin gFrontEnd )
				)
				( attribute "CHIPS_PART_NAME" "CAP"
					( Origin gPackager )
				)
				( attribute "CDS_PART_NAME" "CAP_0805-47UF,4V,20%,X6S,C9533A"
					( Origin gPackager )
				)
				( objectStatus "C7P7" )
				( pin "a"
					( attribute "PN" "1"
						( Origin gPackager )
					)
					( objectStatus "C7P7.1" )
				)
				( pin "b"
					( attribute "PN" "2"
						( Origin gPackager )
					)
					( objectStatus "C7P7.2" )
				)
			)
			( gate "@baseboard_fab2_lib.baseboard_fab2(sch_1):page76_i28"
				( attribute "BOM_COST" "PROC"
					( Origin gFrontEnd )
				)
				( attribute "CDS_LIB" "mstr_discrete"
					( Origin gPackager )
				)
				( attribute "CDS_LOCATION" "C8P22"
					( Origin gPackager )
				)
				( attribute "CDS_SEC" "1"
					( Origin gPackager )
				)
				( attribute "LOCATION" "C8P22"
					( Origin gFrontEnd )
				)
				( attribute "MATERIAL" "X6S"
					( Origin gFrontEnd )
				)
				( attribute "PACK_TYPE" "0805"
					( Origin gFrontEnd )
				)
				( attribute "PART_NUMBER" "C95333-006"
					( Origin gFrontEnd )
				)
				( attribute "PHYS_PAGE" "76"
					( Origin gFrontEnd )
				)
				( attribute "ROOM" "PVCCIN_CPU1_DECAP_VR"
					( Origin gFrontEnd )
				)
				( attribute "ROT" "0"
					( Origin gFrontEnd )
				)
				( attribute "SEC" "1"
					( Origin gPackager )
				)
				( attribute "TOLERANCE" "20%"
					( Origin gFrontEnd )
				)
				( attribute "VALUE" "47UF"
					( Origin gFrontEnd )
				)
				( attribute "VER" "1"
					( Origin gFrontEnd )
				)
				( attribute "VOLTAGE" "4V"
					( Units "uVoltage" "V" 1.000000)
					( Origin gFrontEnd )
				)
				( attribute "XY" "(-2925,2150)"
					( Origin gFrontEnd )
				)
				( attribute "CHIPS_PART_NAME" "CAP"
					( Origin gPackager )
				)
				( attribute "CDS_PART_NAME" "CAP_0805-47UF,4V,20%,X6S,C9533A"
					( Origin gPackager )
				)
				( objectStatus "C8P22" )
				( pin "a"
					( attribute "PN" "1"
						( Origin gPackager )
					)
					( objectStatus "C8P22.1" )
				)
				( pin "b"
					( attribute "PN" "2"
						( Origin gPackager )
					)
					( objectStatus "C8P22.2" )
				)
			)
			( gate "@baseboard_fab2_lib.baseboard_fab2(sch_1):page76_i29"
				( attribute "BOM_COST" "PROC"
					( Origin gFrontEnd )
				)
				( attribute "CDS_LIB" "mstr_discrete"
					( Origin gPackager )
				)
				( attribute "CDS_LOCATION" "C7P17"
					( Origin gPackager )
				)
				( attribute "CDS_SEC" "1"
					( Origin gPackager )
				)
				( attribute "LOCATION" "C7P17"
					( Origin gFrontEnd )
				)
				( attribute "MATERIAL" "X6S"
					( Origin gFrontEnd )
				)
				( attribute "PACK_TYPE" "0805"
					( Origin gFrontEnd )
				)
				( attribute "PART_NUMBER" "C95333-006"
					( Origin gFrontEnd )
				)
				( attribute "PHYS_PAGE" "76"
					( Origin gFrontEnd )
				)
				( attribute "ROOM" "PVCCIN_CPU1_DECAP_VR"
					( Origin gFrontEnd )
				)
				( attribute "ROT" "0"
					( Origin gFrontEnd )
				)
				( attribute "SEC" "1"
					( Origin gPackager )
				)
				( attribute "TOLERANCE" "20%"
					( Origin gFrontEnd )
				)
				( attribute "VALUE" "47UF"
					( Origin gFrontEnd )
				)
				( attribute "VER" "1"
					( Origin gFrontEnd )
				)
				( attribute "VOLTAGE" "4V"
					( Units "uVoltage" "V" 1.000000)
					( Origin gFrontEnd )
				)
				( attribute "XY" "(-2625,925)"
					( Origin gFrontEnd )
				)
				( attribute "CHIPS_PART_NAME" "CAP"
					( Origin gPackager )
				)
				( attribute "CDS_PART_NAME" "CAP_0805-47UF,4V,20%,X6S,C9533A"
					( Origin gPackager )
				)
				( objectStatus "C7P17" )
				( pin "a"
					( attribute "PN" "1"
						( Origin gPackager )
					)
					( objectStatus "C7P17.1" )
				)
				( pin "b"
					( attribute "PN" "2"
						( Origin gPackager )
					)
					( objectStatus "C7P17.2" )
				)
			)
			( gate "@baseboard_fab2_lib.baseboard_fab2(sch_1):page76_i33"
				( attribute "BOM_COST" "PROC"
					( Origin gFrontEnd )
				)
				( attribute "CDS_LIB" "mstr_discrete"
					( Origin gPackager )
				)
				( attribute "CDS_LOCATION" "C2D8"
					( Origin gPackager )
				)
				( attribute "CDS_SEC" "1"
					( Origin gPackager )
				)
				( attribute "LOCATION" "C2D8"
					( Origin gFrontEnd )
				)
				( attribute "MATERIAL" "X6S"
					( Origin gFrontEnd )
				)
				( attribute "PACK_TYPE" "0603LF"
					( Origin gFrontEnd )
				)
				( attribute "PART_NUMBER" "E15431-001"
					( Origin gFrontEnd )
				)
				( attribute "PHYS_PAGE" "76"
					( Origin gFrontEnd )
				)
				( attribute "ROOM" "PVCCIN_CPU1_DECAP_VR"
					( Origin gFrontEnd )
				)
				( attribute "ROT" "0"
					( Origin gFrontEnd )
				)
				( attribute "SEC" "1"
					( Origin gPackager )
				)
				( attribute "TOLERANCE" "20%"
					( Origin gFrontEnd )
				)
				( attribute "VALUE" "10UF"
					( Origin gFrontEnd )
				)
				( attribute "VER" "1"
					( Origin gFrontEnd )
				)
				( attribute "VOLTAGE" "4V"
					( Units "uVoltage" "V" 1.000000)
					( Origin gFrontEnd )
				)
				( attribute "XY" "(-2750,3050)"
					( Origin gFrontEnd )
				)
				( attribute "CHIPS_PART_NAME" "CAP"
					( Origin gPackager )
				)
				( attribute "CDS_PART_NAME" "CAP_0603LF-10UF,4V,20%,X6S,E15A"
					( Origin gPackager )
				)
				( objectStatus "C2D8" )
				( pin "a"
					( attribute "PN" "1"
						( Origin gPackager )
					)
					( objectStatus "C2D8.1" )
				)
				( pin "b"
					( attribute "PN" "2"
						( Origin gPackager )
					)
					( objectStatus "C2D8.2" )
				)
			)
			( gate "@baseboard_fab2_lib.baseboard_fab2(sch_1):page76_i37"
				( attribute "BOM_COST" "PROC"
					( Origin gFrontEnd )
				)
				( attribute "CDS_LIB" "mstr_discrete"
					( Origin gPackager )
				)
				( attribute "CDS_LOCATION" "C2D10"
					( Origin gPackager )
				)
				( attribute "CDS_SEC" "1"
					( Origin gPackager )
				)
				( attribute "LOCATION" "C2D10"
					( Origin gFrontEnd )
				)
				( attribute "MATERIAL" "X6S"
					( Origin gFrontEnd )
				)
				( attribute "PACK_TYPE" "0603LF"
					( Origin gFrontEnd )
				)
				( attribute "PART_NUMBER" "E15431-001"
					( Origin gFrontEnd )
				)
				( attribute "PHYS_PAGE" "76"
					( Origin gFrontEnd )
				)
				( attribute "ROOM" "PVCCIN_CPU1_DECAP_VR"
					( Origin gFrontEnd )
				)
				( attribute "ROT" "0"
					( Origin gFrontEnd )
				)
				( attribute "SEC" "1"
					( Origin gPackager )
				)
				( attribute "TOLERANCE" "20%"
					( Origin gFrontEnd )
				)
				( attribute "VALUE" "10UF"
					( Origin gFrontEnd )
				)
				( attribute "VER" "1"
					( Origin gFrontEnd )
				)
				( attribute "VOLTAGE" "4V"
					( Units "uVoltage" "V" 1.000000)
					( Origin gFrontEnd )
				)
				( attribute "XY" "(-3150,3050)"
					( Origin gFrontEnd )
				)
				( attribute "CHIPS_PART_NAME" "CAP"
					( Origin gPackager )
				)
				( attribute "CDS_PART_NAME" "CAP_0603LF-10UF,4V,20%,X6S,E15A"
					( Origin gPackager )
				)
				( objectStatus "C2D10" )
				( pin "a"
					( attribute "PN" "1"
						( Origin gPackager )
					)
					( objectStatus "C2D10.1" )
				)
				( pin "b"
					( attribute "PN" "2"
						( Origin gPackager )
					)
					( objectStatus "C2D10.2" )
				)
			)
			( gate "@baseboard_fab2_lib.baseboard_fab2(sch_1):page76_i42"
				( attribute "BOM_COST" "PROC"
					( Origin gFrontEnd )
				)
				( attribute "CDS_LIB" "mstr_discrete"
					( Origin gPackager )
				)
				( attribute "CDS_LOCATION" "C2D11"
					( Origin gPackager )
				)
				( attribute "CDS_SEC" "1"
					( Origin gPackager )
				)
				( attribute "LOCATION" "C2D11"
					( Origin gFrontEnd )
				)
				( attribute "MATERIAL" "X6S"
					( Origin gFrontEnd )
				)
				( attribute "PACK_TYPE" "0603LF"
					( Origin gFrontEnd )
				)
				( attribute "PART_NUMBER" "E15431-001"
					( Origin gFrontEnd )
				)
				( attribute "PHYS_PAGE" "76"
					( Origin gFrontEnd )
				)
				( attribute "ROOM" "PVCCIN_CPU1_DECAP_VR"
					( Origin gFrontEnd )
				)
				( attribute "ROT" "0"
					( Origin gFrontEnd )
				)
				( attribute "SEC" "1"
					( Origin gPackager )
				)
				( attribute "TOLERANCE" "20%"
					( Origin gFrontEnd )
				)
				( attribute "VALUE" "10UF"
					( Origin gFrontEnd )
				)
				( attribute "VER" "1"
					( Origin gFrontEnd )
				)
				( attribute "VOLTAGE" "4V"
					( Units "uVoltage" "V" 1.000000)
					( Origin gFrontEnd )
				)
				( attribute "XY" "(-3525,3075)"
					( Origin gFrontEnd )
				)
				( attribute "CHIPS_PART_NAME" "CAP"
					( Origin gPackager )
				)
				( attribute "CDS_PART_NAME" "CAP_0603LF-10UF,4V,20%,X6S,E15A"
					( Origin gPackager )
				)
				( objectStatus "C2D11" )
				( pin "a"
					( attribute "PN" "1"
						( Origin gPackager )
					)
					( objectStatus "C2D11.1" )
				)
				( pin "b"
					( attribute "PN" "2"
						( Origin gPackager )
					)
					( objectStatus "C2D11.2" )
				)
			)
			( gate "@baseboard_fab2_lib.baseboard_fab2(sch_1):page76_i43"
				( attribute "BOM_COST" "PROC"
					( Origin gFrontEnd )
				)
				( attribute "CDS_LIB" "mstr_discrete"
					( Origin gPackager )
				)
				( attribute "CDS_LOCATION" "C2D9"
					( Origin gPackager )
				)
				( attribute "CDS_SEC" "1"
					( Origin gPackager )
				)
				( attribute "LOCATION" "C2D9"
					( Origin gFrontEnd )
				)
				( attribute "MATERIAL" "X6S"
					( Origin gFrontEnd )
				)
				( attribute "PACK_TYPE" "0603LF"
					( Origin gFrontEnd )
				)
				( attribute "PART_NUMBER" "E15431-001"
					( Origin gFrontEnd )
				)
				( attribute "PHYS_PAGE" "76"
					( Origin gFrontEnd )
				)
				( attribute "ROOM" "PVCCIN_CPU1_DECAP_VR"
					( Origin gFrontEnd )
				)
				( attribute "ROT" "0"
					( Origin gFrontEnd )
				)
				( attribute "SEC" "1"
					( Origin gPackager )
				)
				( attribute "TOLERANCE" "20%"
					( Origin gFrontEnd )
				)
				( attribute "VALUE" "10UF"
					( Origin gFrontEnd )
				)
				( attribute "VER" "1"
					( Origin gFrontEnd )
				)
				( attribute "VOLTAGE" "4V"
					( Units "uVoltage" "V" 1.000000)
					( Origin gFrontEnd )
				)
				( attribute "XY" "(-3925,3050)"
					( Origin gFrontEnd )
				)
				( attribute "CHIPS_PART_NAME" "CAP"
					( Origin gPackager )
				)
				( attribute "CDS_PART_NAME" "CAP_0603LF-10UF,4V,20%,X6S,E15A"
					( Origin gPackager )
				)
				( objectStatus "C2D9" )
				( pin "a"
					( attribute "PN" "1"
						( Origin gPackager )
					)
					( objectStatus "C2D9.1" )
				)
				( pin "b"
					( attribute "PN" "2"
						( Origin gPackager )
					)
					( objectStatus "C2D9.2" )
				)
			)
			( gate "@baseboard_fab2_lib.baseboard_fab2(sch_1):page76_i45"
				( attribute "BOM_COST" "PROC"
					( Origin gFrontEnd )
				)
				( attribute "CDS_LIB" "mstr_discrete"
					( Origin gPackager )
				)
				( attribute "CDS_LOCATION" "C7P15"
					( Origin gPackager )
				)
				( attribute "CDS_SEC" "1"
					( Origin gPackager )
				)
				( attribute "LOCATION" "C7P15"
					( Origin gFrontEnd )
				)
				( attribute "MATERIAL" "X6S"
					( Origin gFrontEnd )
				)
				( attribute "PACK_TYPE" "0805"
					( Origin gFrontEnd )
				)
				( attribute "PART_NUMBER" "C95333-006"
					( Origin gFrontEnd )
				)
				( attribute "PHYS_PAGE" "76"
					( Origin gFrontEnd )
				)
				( attribute "ROOM" "PVCCIN_CPU1_DECAP_VR"
					( Origin gFrontEnd )
				)
				( attribute "ROT" "0"
					( Origin gFrontEnd )
				)
				( attribute "SEC" "1"
					( Origin gPackager )
				)
				( attribute "TOLERANCE" "20%"
					( Origin gFrontEnd )
				)
				( attribute "VALUE" "47UF"
					( Origin gFrontEnd )
				)
				( attribute "VER" "1"
					( Origin gFrontEnd )
				)
				( attribute "VOLTAGE" "4V"
					( Units "uVoltage" "V" 1.000000)
					( Origin gFrontEnd )
				)
				( attribute "XY" "(-3725,2150)"
					( Origin gFrontEnd )
				)
				( attribute "CHIPS_PART_NAME" "CAP"
					( Origin gPackager )
				)
				( attribute "CDS_PART_NAME" "CAP_0805-47UF,4V,20%,X6S,C9533A"
					( Origin gPackager )
				)
				( objectStatus "C7P15" )
				( pin "a"
					( attribute "PN" "1"
						( Origin gPackager )
					)
					( objectStatus "C7P15.1" )
				)
				( pin "b"
					( attribute "PN" "2"
						( Origin gPackager )
					)
					( objectStatus "C7P15.2" )
				)
			)
			( gate "@baseboard_fab2_lib.baseboard_fab2(sch_1):page76_i48"
				( attribute "BOM_COST" "PROC"
					( Origin gFrontEnd )
				)
				( attribute "CDS_LIB" "mstr_discrete"
					( Origin gPackager )
				)
				( attribute "CDS_LOCATION" "C8P23"
					( Origin gPackager )
				)
				( attribute "CDS_SEC" "1"
					( Origin gPackager )
				)
				( attribute "LOCATION" "C8P23"
					( Origin gFrontEnd )
				)
				( attribute "MATERIAL" "X6S"
					( Origin gFrontEnd )
				)
				( attribute "PACK_TYPE" "0805"
					( Origin gFrontEnd )
				)
				( attribute "PART_NUMBER" "C95333-006"
					( Origin gFrontEnd )
				)
				( attribute "PHYS_PAGE" "76"
					( Origin gFrontEnd )
				)
				( attribute "ROOM" "PVCCIN_CPU1_DECAP_VR"
					( Origin gFrontEnd )
				)
				( attribute "ROT" "0"
					( Origin gFrontEnd )
				)
				( attribute "SEC" "1"
					( Origin gPackager )
				)
				( attribute "TOLERANCE" "20%"
					( Origin gFrontEnd )
				)
				( attribute "VALUE" "47UF"
					( Origin gFrontEnd )
				)
				( attribute "VER" "1"
					( Origin gFrontEnd )
				)
				( attribute "VOLTAGE" "4V"
					( Units "uVoltage" "V" 1.000000)
					( Origin gFrontEnd )
				)
				( attribute "XY" "(-4000,2150)"
					( Origin gFrontEnd )
				)
				( attribute "CHIPS_PART_NAME" "CAP"
					( Origin gPackager )
				)
				( attribute "CDS_PART_NAME" "CAP_0805-47UF,4V,20%,X6S,C9533A"
					( Origin gPackager )
				)
				( objectStatus "C8P23" )
				( pin "a"
					( attribute "PN" "1"
						( Origin gPackager )
					)
					( objectStatus "C8P23.1" )
				)
				( pin "b"
					( attribute "PN" "2"
						( Origin gPackager )
					)
					( objectStatus "C8P23.2" )
				)
			)
			( gate "@baseboard_fab2_lib.baseboard_fab2(sch_1):page76_i49"
				( attribute "BOM_COST" "PROC"
					( Origin gFrontEnd )
				)
				( attribute "CDS_LIB" "mstr_discrete"
					( Origin gPackager )
				)
				( attribute "CDS_LOCATION" "C7P14"
					( Origin gPackager )
				)
				( attribute "CDS_SEC" "1"
					( Origin gPackager )
				)
				( attribute "LOCATION" "C7P14"
					( Origin gFrontEnd )
				)
				( attribute "MATERIAL" "X6S"
					( Origin gFrontEnd )
				)
				( attribute "PACK_TYPE" "0805"
					( Origin gFrontEnd )
				)
				( attribute "PART_NUMBER" "C95333-006"
					( Origin gFrontEnd )
				)
				( attribute "PHYS_PAGE" "76"
					( Origin gFrontEnd )
				)
				( attribute "ROOM" "PVCCIN_CPU1_DECAP_VR"
					( Origin gFrontEnd )
				)
				( attribute "ROT" "0"
					( Origin gFrontEnd )
				)
				( attribute "SEC" "1"
					( Origin gPackager )
				)
				( attribute "TOLERANCE" "20%"
					( Origin gFrontEnd )
				)
				( attribute "VALUE" "47UF"
					( Origin gFrontEnd )
				)
				( attribute "VER" "1"
					( Origin gFrontEnd )
				)
				( attribute "VOLTAGE" "4V"
					( Units "uVoltage" "V" 1.000000)
					( Origin gFrontEnd )
				)
				( attribute "XY" "(-4275,2125)"
					( Origin gFrontEnd )
				)
				( attribute "CHIPS_PART_NAME" "CAP"
					( Origin gPackager )
				)
				( attribute "CDS_PART_NAME" "CAP_0805-47UF,4V,20%,X6S,C9533A"
					( Origin gPackager )
				)
				( objectStatus "C7P14" )
				( pin "a"
					( attribute "PN" "1"
						( Origin gPackager )
					)
					( objectStatus "C7P14.1" )
				)
				( pin "b"
					( attribute "PN" "2"
						( Origin gPackager )
					)
					( objectStatus "C7P14.2" )
				)
			)
			( gate "@baseboard_fab2_lib.baseboard_fab2(sch_1):page76_i50"
				( attribute "BOM_COST" "PROC"
					( Origin gFrontEnd )
				)
				( attribute "CDS_LIB" "mstr_discrete"
					( Origin gPackager )
				)
				( attribute "CDS_LOCATION" "C8P7"
					( Origin gPackager )
				)
				( attribute "CDS_SEC" "1"
					( Origin gPackager )
				)
				( attribute "LOCATION" "C8P7"
					( Origin gFrontEnd )
				)
				( attribute "MATERIAL" "X6S"
					( Origin gFrontEnd )
				)
				( attribute "PACK_TYPE" "0805LF"
					( Origin gFrontEnd )
				)
				( attribute "PART_NUMBER" "C95333-002"
					( Origin gFrontEnd )
				)
				( attribute "PHYS_PAGE" "76"
					( Origin gFrontEnd )
				)
				( attribute "ROOM" "PVCCIN_CPU1_DECAP_VR"
					( Origin gFrontEnd )
				)
				( attribute "ROT" "0"
					( Origin gFrontEnd )
				)
				( attribute "SEC" "1"
					( Origin gPackager )
				)
				( attribute "TOLERANCE" "20%"
					( Origin gFrontEnd )
				)
				( attribute "VALUE" "22UF"
					( Origin gFrontEnd )
				)
				( attribute "VER" "1"
					( Origin gFrontEnd )
				)
				( attribute "VOLTAGE" "4V"
					( Units "uVoltage" "V" 1.000000)
					( Origin gFrontEnd )
				)
				( attribute "XY" "(-3800,950)"
					( Origin gFrontEnd )
				)
				( attribute "CHIPS_PART_NAME" "CAP"
					( Origin gPackager )
				)
				( attribute "CDS_PART_NAME" "CAP_0805LF-22UF,4V,20%,X6S,C95A"
					( Origin gPackager )
				)
				( objectStatus "C8P7" )
				( pin "a"
					( attribute "PN" "1"
						( Origin gPackager )
					)
					( objectStatus "C8P7.1" )
				)
				( pin "b"
					( attribute "PN" "2"
						( Origin gPackager )
					)
					( objectStatus "C8P7.2" )
				)
			)
			( gate "@baseboard_fab2_lib.baseboard_fab2(sch_1):page76_i51"
				( attribute "BOM_COST" "PROC"
					( Origin gFrontEnd )
				)
				( attribute "CDS_LIB" "mstr_discrete"
					( Origin gPackager )
				)
				( attribute "CDS_LOCATION" "C7P18"
					( Origin gPackager )
				)
				( attribute "CDS_SEC" "1"
					( Origin gPackager )
				)
				( attribute "LOCATION" "C7P18"
					( Origin gFrontEnd )
				)
				( attribute "MATERIAL" "X6S"
					( Origin gFrontEnd )
				)
				( attribute "PACK_TYPE" "0805"
					( Origin gFrontEnd )
				)
				( attribute "PART_NUMBER" "C95333-006"
					( Origin gFrontEnd )
				)
				( attribute "PHYS_PAGE" "76"
					( Origin gFrontEnd )
				)
				( attribute "ROOM" "PVCCIN_CPU1_DECAP_VR"
					( Origin gFrontEnd )
				)
				( attribute "ROT" "0"
					( Origin gFrontEnd )
				)
				( attribute "SEC" "1"
					( Origin gPackager )
				)
				( attribute "TOLERANCE" "20%"
					( Origin gFrontEnd )
				)
				( attribute "VALUE" "47UF"
					( Origin gFrontEnd )
				)
				( attribute "VER" "1"
					( Origin gFrontEnd )
				)
				( attribute "VOLTAGE" "4V"
					( Units "uVoltage" "V" 1.000000)
					( Origin gFrontEnd )
				)
				( attribute "XY" "(-2950,925)"
					( Origin gFrontEnd )
				)
				( attribute "CHIPS_PART_NAME" "CAP"
					( Origin gPackager )
				)
				( attribute "CDS_PART_NAME" "CAP_0805-47UF,4V,20%,X6S,C9533A"
					( Origin gPackager )
				)
				( objectStatus "C7P18" )
				( pin "a"
					( attribute "PN" "1"
						( Origin gPackager )
					)
					( objectStatus "C7P18.1" )
				)
				( pin "b"
					( attribute "PN" "2"
						( Origin gPackager )
					)
					( objectStatus "C7P18.2" )
				)
			)
			( gate "@baseboard_fab2_lib.baseboard_fab2(sch_1):page76_i52"
				( attribute "BOM_COST" "PROC"
					( Origin gFrontEnd )
				)
				( attribute "CDS_LIB" "mstr_discrete"
					( Origin gPackager )
				)
				( attribute "CDS_LOCATION" "C7P3"
					( Origin gPackager )
				)
				( attribute "CDS_SEC" "1"
					( Origin gPackager )
				)
				( attribute "LOCATION" "C7P3"
					( Origin gFrontEnd )
				)
				( attribute "MATERIAL" "X6S"
					( Origin gFrontEnd )
				)
				( attribute "PACK_TYPE" "0805"
					( Origin gFrontEnd )
				)
				( attribute "PART_NUMBER" "C95333-006"
					( Origin gFrontEnd )
				)
				( attribute "PHYS_PAGE" "76"
					( Origin gFrontEnd )
				)
				( attribute "ROOM" "PVCCIN_CPU1_DECAP_VR"
					( Origin gFrontEnd )
				)
				( attribute "ROT" "0"
					( Origin gFrontEnd )
				)
				( attribute "SEC" "1"
					( Origin gPackager )
				)
				( attribute "TOLERANCE" "20%"
					( Origin gFrontEnd )
				)
				( attribute "VALUE" "47UF"
					( Origin gFrontEnd )
				)
				( attribute "VER" "1"
					( Origin gFrontEnd )
				)
				( attribute "VOLTAGE" "4V"
					( Units "uVoltage" "V" 1.000000)
					( Origin gFrontEnd )
				)
				( attribute "XY" "(-3300,925)"
					( Origin gFrontEnd )
				)
				( attribute "CHIPS_PART_NAME" "CAP"
					( Origin gPackager )
				)
				( attribute "CDS_PART_NAME" "CAP_0805-47UF,4V,20%,X6S,C9533A"
					( Origin gPackager )
				)
				( objectStatus "C7P3" )
				( pin "a"
					( attribute "PN" "1"
						( Origin gPackager )
					)
					( objectStatus "C7P3.1" )
				)
				( pin "b"
					( attribute "PN" "2"
						( Origin gPackager )
					)
					( objectStatus "C7P3.2" )
				)
			)
			( gate "@baseboard_fab2_lib.baseboard_fab2(sch_1):page76_i55"
				( attribute "BOM_COST" "PROC"
					( Origin gFrontEnd )
				)
				( attribute "CDS_LIB" "mstr_discrete"
					( Origin gPackager )
				)
				( attribute "CDS_LOCATION" "C8P6"
					( Origin gPackager )
				)
				( attribute "CDS_SEC" "1"
					( Origin gPackager )
				)
				( attribute "LOCATION" "C8P6"
					( Origin gFrontEnd )
				)
				( attribute "MATERIAL" "X6S"
					( Origin gFrontEnd )
				)
				( attribute "PACK_TYPE" "0805LF"
					( Origin gFrontEnd )
				)
				( attribute "PART_NUMBER" "C95333-002"
					( Origin gFrontEnd )
				)
				( attribute "PHYS_PAGE" "76"
					( Origin gFrontEnd )
				)
				( attribute "ROOM" "PVCCIN_CPU1_DECAP_VR"
					( Origin gFrontEnd )
				)
				( attribute "ROT" "0"
					( Origin gFrontEnd )
				)
				( attribute "SEC" "1"
					( Origin gPackager )
				)
				( attribute "TOLERANCE" "20%"
					( Origin gFrontEnd )
				)
				( attribute "VALUE" "22UF"
					( Origin gFrontEnd )
				)
				( attribute "VER" "1"
					( Origin gFrontEnd )
				)
				( attribute "VOLTAGE" "4V"
					( Units "uVoltage" "V" 1.000000)
					( Origin gFrontEnd )
				)
				( attribute "XY" "(-4125,950)"
					( Origin gFrontEnd )
				)
				( attribute "CHIPS_PART_NAME" "CAP"
					( Origin gPackager )
				)
				( attribute "CDS_PART_NAME" "CAP_0805LF-22UF,4V,20%,X6S,C95A"
					( Origin gPackager )
				)
				( objectStatus "C8P6" )
				( pin "a"
					( attribute "PN" "1"
						( Origin gPackager )
					)
					( objectStatus "C8P6.1" )
				)
				( pin "b"
					( attribute "PN" "2"
						( Origin gPackager )
					)
					( objectStatus "C8P6.2" )
				)
			)
			( gate "@baseboard_fab2_lib.baseboard_fab2(sch_1):page76_i58"
				( attribute "BOM_COST" "PROC"
					( Origin gFrontEnd )
				)
				( attribute "CDS_LIB" "mstr_discrete"
					( Origin gPackager )
				)
				( attribute "CDS_LOCATION" "C8P5"
					( Origin gPackager )
				)
				( attribute "CDS_SEC" "1"
					( Origin gPackager )
				)
				( attribute "LOCATION" "C8P5"
					( Origin gFrontEnd )
				)
				( attribute "MATERIAL" "X6S"
					( Origin gFrontEnd )
				)
				( attribute "PACK_TYPE" "0805LF"
					( Origin gFrontEnd )
				)
				( attribute "PART_NUMBER" "C95333-002"
					( Origin gFrontEnd )
				)
				( attribute "PHYS_PAGE" "76"
					( Origin gFrontEnd )
				)
				( attribute "ROOM" "PVCCIN_CPU1_DECAP_VR"
					( Origin gFrontEnd )
				)
				( attribute "ROT" "0"
					( Origin gFrontEnd )
				)
				( attribute "SEC" "1"
					( Origin gPackager )
				)
				( attribute "TOLERANCE" "20%"
					( Origin gFrontEnd )
				)
				( attribute "VALUE" "22UF"
					( Origin gFrontEnd )
				)
				( attribute "VER" "1"
					( Origin gFrontEnd )
				)
				( attribute "VOLTAGE" "4V"
					( Units "uVoltage" "V" 1.000000)
					( Origin gFrontEnd )
				)
				( attribute "XY" "(-4475,950)"
					( Origin gFrontEnd )
				)
				( attribute "CHIPS_PART_NAME" "CAP"
					( Origin gPackager )
				)
				( attribute "CDS_PART_NAME" "CAP_0805LF-22UF,4V,20%,X6S,C95A"
					( Origin gPackager )
				)
				( objectStatus "C8P5" )
				( pin "a"
					( attribute "PN" "1"
						( Origin gPackager )
					)
					( objectStatus "C8P5.1" )
				)
				( pin "b"
					( attribute "PN" "2"
						( Origin gPackager )
					)
					( objectStatus "C8P5.2" )
				)
			)
			( gate "@baseboard_fab2_lib.baseboard_fab2(sch_1):page76_i59"
				( attribute "BOM_COST" "PROC"
					( Origin gFrontEnd )
				)
				( attribute "CDS_LIB" "dev_discrete"
					( Origin gPackager )
				)
				( attribute "CDS_LOCATION" "C2D12"
					( Origin gPackager )
				)
				( attribute "CDS_SEC" "1"
					( Origin gPackager )
				)
				( attribute "LOCATION" "C2D12"
					( Origin gFrontEnd )
				)
				( attribute "MATERIAL" "X6S"
					( Origin gFrontEnd )
				)
				( attribute "PACK_TYPE" "0603V"
					( Origin gFrontEnd )
				)
				( attribute "PART_NUMBER" "E15431-004"
					( Origin gFrontEnd )
				)
				( attribute "PHYS_PAGE" "76"
					( Origin gFrontEnd )
				)
				( attribute "ROOM" "PVCCIN_CPU1_DECAP_VR"
					( Origin gFrontEnd )
				)
				( attribute "ROT" "0"
					( Origin gFrontEnd )
				)
				( attribute "SEC" "1"
					( Origin gPackager )
				)
				( attribute "TOLERANCE" "20%"
					( Origin gFrontEnd )
				)
				( attribute "VALUE" "22.0UF"
					( Origin gFrontEnd )
				)
				( attribute "VER" "1"
					( Origin gFrontEnd )
				)
				( attribute "VOLTAGE" "4V"
					( Units "uVoltage" "V" 1.000000)
					( Origin gFrontEnd )
				)
				( attribute "XY" "(-4625,4425)"
					( Origin gFrontEnd )
				)
				( attribute "CHIPS_PART_NAME" "CAP_A"
					( Origin gPackager )
				)
				( attribute "CDS_PART_NAME" "CAP_A_0603V-22.0UF,4V,20%,X6S,A"
					( Origin gPackager )
				)
				( objectStatus "C2D12" )
				( pin "a"
					( attribute "PN" "1"
						( Origin gPackager )
					)
					( objectStatus "C2D12.1" )
				)
				( pin "b"
					( attribute "PN" "2"
						( Origin gPackager )
					)
					( objectStatus "C2D12.2" )
				)
			)
			( gate "@baseboard_fab2_lib.baseboard_fab2(sch_1):page76_i61"
				( attribute "BOM_COST" "PROC"
					( Origin gFrontEnd )
				)
				( attribute "CDS_LIB" "dev_discrete"
					( Origin gPackager )
				)
				( attribute "CDS_LOCATION" "C2D22"
					( Origin gPackager )
				)
				( attribute "CDS_SEC" "1"
					( Origin gPackager )
				)
				( attribute "LOCATION" "C2D22"
					( Origin gFrontEnd )
				)
				( attribute "MATERIAL" "X6S"
					( Origin gFrontEnd )
				)
				( attribute "PACK_TYPE" "0603V"
					( Origin gFrontEnd )
				)
				( attribute "PART_NUMBER" "E15431-004"
					( Origin gFrontEnd )
				)
				( attribute "PHYS_PAGE" "76"
					( Origin gFrontEnd )
				)
				( attribute "ROOM" "PVCCIN_CPU1_DECAP_VR"
					( Origin gFrontEnd )
				)
				( attribute "ROT" "0"
					( Origin gFrontEnd )
				)
				( attribute "SEC" "1"
					( Origin gPackager )
				)
				( attribute "TOLERANCE" "20%"
					( Origin gFrontEnd )
				)
				( attribute "VALUE" "22.0UF"
					( Origin gFrontEnd )
				)
				( attribute "VER" "1"
					( Origin gFrontEnd )
				)
				( attribute "VOLTAGE" "4V"
					( Units "uVoltage" "V" 1.000000)
					( Origin gFrontEnd )
				)
				( attribute "XY" "(-4950,4450)"
					( Origin gFrontEnd )
				)
				( attribute "CHIPS_PART_NAME" "CAP_A"
					( Origin gPackager )
				)
				( attribute "CDS_PART_NAME" "CAP_A_0603V-22.0UF,4V,20%,X6S,A"
					( Origin gPackager )
				)
				( objectStatus "C2D22" )
				( pin "a"
					( attribute "PN" "1"
						( Origin gPackager )
					)
					( objectStatus "C2D22.1" )
				)
				( pin "b"
					( attribute "PN" "2"
						( Origin gPackager )
					)
					( objectStatus "C2D22.2" )
				)
			)
			( gate "@baseboard_fab2_lib.baseboard_fab2(sch_1):page76_i63"
				( attribute "BOM_COST" "PROC"
					( Origin gFrontEnd )
				)
				( attribute "CDS_LIB" "dev_discrete"
					( Origin gPackager )
				)
				( attribute "CDS_LOCATION" "C2D31"
					( Origin gPackager )
				)
				( attribute "CDS_SEC" "1"
					( Origin gPackager )
				)
				( attribute "LOCATION" "C2D31"
					( Origin gFrontEnd )
				)
				( attribute "MATERIAL" "X6S"
					( Origin gFrontEnd )
				)
				( attribute "PACK_TYPE" "0603V"
					( Origin gFrontEnd )
				)
				( attribute "PART_NUMBER" "E15431-004"
					( Origin gFrontEnd )
				)
				( attribute "PHYS_PAGE" "76"
					( Origin gFrontEnd )
				)
				( attribute "ROOM" "PVCCIN_CPU1_DECAP_VR"
					( Origin gFrontEnd )
				)
				( attribute "ROT" "0"
					( Origin gFrontEnd )
				)
				( attribute "SEC" "1"
					( Origin gPackager )
				)
				( attribute "TOLERANCE" "20%"
					( Origin gFrontEnd )
				)
				( attribute "VALUE" "22.0UF"
					( Origin gFrontEnd )
				)
				( attribute "VER" "1"
					( Origin gFrontEnd )
				)
				( attribute "VOLTAGE" "4V"
					( Units "uVoltage" "V" 1.000000)
					( Origin gFrontEnd )
				)
				( attribute "XY" "(-5575,4450)"
					( Origin gFrontEnd )
				)
				( attribute "CHIPS_PART_NAME" "CAP_A"
					( Origin gPackager )
				)
				( attribute "CDS_PART_NAME" "CAP_A_0603V-22.0UF,4V,20%,X6S,A"
					( Origin gPackager )
				)
				( objectStatus "C2D31" )
				( pin "a"
					( attribute "PN" "1"
						( Origin gPackager )
					)
					( objectStatus "C2D31.1" )
				)
				( pin "b"
					( attribute "PN" "2"
						( Origin gPackager )
					)
					( objectStatus "C2D31.2" )
				)
			)
			( gate "@baseboard_fab2_lib.baseboard_fab2(sch_1):page76_i65"
				( attribute "BOM_COST" "PROC"
					( Origin gFrontEnd )
				)
				( attribute "CDS_LIB" "dev_discrete"
					( Origin gPackager )
				)
				( attribute "CDS_LOCATION" "C2D21"
					( Origin gPackager )
				)
				( attribute "CDS_SEC" "1"
					( Origin gPackager )
				)
				( attribute "LOCATION" "C2D21"
					( Origin gFrontEnd )
				)
				( attribute "MATERIAL" "X6S"
					( Origin gFrontEnd )
				)
				( attribute "PACK_TYPE" "0603V"
					( Origin gFrontEnd )
				)
				( attribute "PART_NUMBER" "E15431-004"
					( Origin gFrontEnd )
				)
				( attribute "PHYS_PAGE" "76"
					( Origin gFrontEnd )
				)
				( attribute "ROOM" "PVCCIN_CPU1_DECAP_VR"
					( Origin gFrontEnd )
				)
				( attribute "ROT" "0"
					( Origin gFrontEnd )
				)
				( attribute "SEC" "1"
					( Origin gPackager )
				)
				( attribute "TOLERANCE" "20%"
					( Origin gFrontEnd )
				)
				( attribute "VALUE" "22.0UF"
					( Origin gFrontEnd )
				)
				( attribute "VER" "1"
					( Origin gFrontEnd )
				)
				( attribute "VOLTAGE" "4V"
					( Units "uVoltage" "V" 1.000000)
					( Origin gFrontEnd )
				)
				( attribute "XY" "(-5900,4450)"
					( Origin gFrontEnd )
				)
				( attribute "CHIPS_PART_NAME" "CAP_A"
					( Origin gPackager )
				)
				( attribute "CDS_PART_NAME" "CAP_A_0603V-22.0UF,4V,20%,X6S,A"
					( Origin gPackager )
				)
				( objectStatus "C2D21" )
				( pin "a"
					( attribute "PN" "1"
						( Origin gPackager )
					)
					( objectStatus "C2D21.1" )
				)
				( pin "b"
					( attribute "PN" "2"
						( Origin gPackager )
					)
					( objectStatus "C2D21.2" )
				)
			)
			( gate "@baseboard_fab2_lib.baseboard_fab2(sch_1):page76_i66"
				( attribute "BOM_COST" "PROC"
					( Origin gFrontEnd )
				)
				( attribute "CDS_LIB" "dev_discrete"
					( Origin gPackager )
				)
				( attribute "CDS_LOCATION" "C2D27"
					( Origin gPackager )
				)
				( attribute "CDS_SEC" "1"
					( Origin gPackager )
				)
				( attribute "LOCATION" "C2D27"
					( Origin gFrontEnd )
				)
				( attribute "MATERIAL" "X6S"
					( Origin gFrontEnd )
				)
				( attribute "PACK_TYPE" "0603V"
					( Origin gFrontEnd )
				)
				( attribute "PART_NUMBER" "E15431-004"
					( Origin gFrontEnd )
				)
				( attribute "PHYS_PAGE" "76"
					( Origin gFrontEnd )
				)
				( attribute "ROOM" "PVCCIN_CPU1_DECAP_VR"
					( Origin gFrontEnd )
				)
				( attribute "ROT" "0"
					( Origin gFrontEnd )
				)
				( attribute "SEC" "1"
					( Origin gPackager )
				)
				( attribute "TOLERANCE" "20%"
					( Origin gFrontEnd )
				)
				( attribute "VALUE" "22.0UF"
					( Origin gFrontEnd )
				)
				( attribute "VER" "1"
					( Origin gFrontEnd )
				)
				( attribute "VOLTAGE" "4V"
					( Units "uVoltage" "V" 1.000000)
					( Origin gFrontEnd )
				)
				( attribute "XY" "(-6350,4450)"
					( Origin gFrontEnd )
				)
				( attribute "CHIPS_PART_NAME" "CAP_A"
					( Origin gPackager )
				)
				( attribute "CDS_PART_NAME" "CAP_A_0603V-22.0UF,4V,20%,X6S,A"
					( Origin gPackager )
				)
				( objectStatus "C2D27" )
				( pin "a"
					( attribute "PN" "1"
						( Origin gPackager )
					)
					( objectStatus "C2D27.1" )
				)
				( pin "b"
					( attribute "PN" "2"
						( Origin gPackager )
					)
					( objectStatus "C2D27.2" )
				)
			)
			( gate "@baseboard_fab2_lib.baseboard_fab2(sch_1):page76_i69"
				( attribute "BOM_COST" "PROC"
					( Origin gFrontEnd )
				)
				( attribute "CDS_LIB" "dev_discrete"
					( Origin gPackager )
				)
				( attribute "CDS_LOCATION" "C3D2"
					( Origin gPackager )
				)
				( attribute "CDS_SEC" "1"
					( Origin gPackager )
				)
				( attribute "LOCATION" "C3D2"
					( Origin gFrontEnd )
				)
				( attribute "MATERIAL" "X6S"
					( Origin gFrontEnd )
				)
				( attribute "PACK_TYPE" "0603V"
					( Origin gFrontEnd )
				)
				( attribute "PART_NUMBER" "E15431-004"
					( Origin gFrontEnd )
				)
				( attribute "PHYS_PAGE" "76"
					( Origin gFrontEnd )
				)
				( attribute "ROOM" "PVCCIN_CPU1_DECAP_VR"
					( Origin gFrontEnd )
				)
				( attribute "ROT" "0"
					( Origin gFrontEnd )
				)
				( attribute "SEC" "1"
					( Origin gPackager )
				)
				( attribute "TOLERANCE" "20%"
					( Origin gFrontEnd )
				)
				( attribute "VALUE" "22.0UF"
					( Origin gFrontEnd )
				)
				( attribute "VER" "1"
					( Origin gFrontEnd )
				)
				( attribute "VOLTAGE" "4V"
					( Units "uVoltage" "V" 1.000000)
					( Origin gFrontEnd )
				)
				( attribute "XY" "(-7050,4450)"
					( Origin gFrontEnd )
				)
				( attribute "CHIPS_PART_NAME" "CAP_A"
					( Origin gPackager )
				)
				( attribute "CDS_PART_NAME" "CAP_A_0603V-22.0UF,4V,20%,X6S,A"
					( Origin gPackager )
				)
				( objectStatus "C3D2" )
				( pin "a"
					( attribute "PN" "1"
						( Origin gPackager )
					)
					( objectStatus "C3D2.1" )
				)
				( pin "b"
					( attribute "PN" "2"
						( Origin gPackager )
					)
					( objectStatus "C3D2.2" )
				)
			)
			( gate "@baseboard_fab2_lib.baseboard_fab2(sch_1):page76_i70"
				( attribute "BOM_COST" "PROC"
					( Origin gFrontEnd )
				)
				( attribute "CDS_LIB" "dev_discrete"
					( Origin gPackager )
				)
				( attribute "CDS_LOCATION" "C2D36"
					( Origin gPackager )
				)
				( attribute "CDS_SEC" "1"
					( Origin gPackager )
				)
				( attribute "LOCATION" "C2D36"
					( Origin gFrontEnd )
				)
				( attribute "MATERIAL" "X6S"
					( Origin gFrontEnd )
				)
				( attribute "PACK_TYPE" "0603V"
					( Origin gFrontEnd )
				)
				( attribute "PART_NUMBER" "E15431-004"
					( Origin gFrontEnd )
				)
				( attribute "PHYS_PAGE" "76"
					( Origin gFrontEnd )
				)
				( attribute "ROOM" "PVCCIN_CPU1_DECAP_VR"
					( Origin gFrontEnd )
				)
				( attribute "ROT" "0"
					( Origin gFrontEnd )
				)
				( attribute "SEC" "1"
					( Origin gPackager )
				)
				( attribute "TOLERANCE" "20%"
					( Origin gFrontEnd )
				)
				( attribute "VALUE" "22.0UF"
					( Origin gFrontEnd )
				)
				( attribute "VER" "1"
					( Origin gFrontEnd )
				)
				( attribute "VOLTAGE" "4V"
					( Units "uVoltage" "V" 1.000000)
					( Origin gFrontEnd )
				)
				( attribute "XY" "(-7375,4450)"
					( Origin gFrontEnd )
				)
				( attribute "CHIPS_PART_NAME" "CAP_A"
					( Origin gPackager )
				)
				( attribute "CDS_PART_NAME" "CAP_A_0603V-22.0UF,4V,20%,X6S,A"
					( Origin gPackager )
				)
				( objectStatus "C2D36" )
				( pin "a"
					( attribute "PN" "1"
						( Origin gPackager )
					)
					( objectStatus "C2D36.1" )
				)
				( pin "b"
					( attribute "PN" "2"
						( Origin gPackager )
					)
					( objectStatus "C2D36.2" )
				)
			)
			( gate "@baseboard_fab2_lib.baseboard_fab2(sch_1):page76_i73"
				( attribute "BOM_COST" "PROC"
					( Origin gFrontEnd )
				)
				( attribute "CDS_LIB" "dev_discrete"
					( Origin gPackager )
				)
				( attribute "CDS_LOCATION" "C2D13"
					( Origin gPackager )
				)
				( attribute "CDS_SEC" "1"
					( Origin gPackager )
				)
				( attribute "LOCATION" "C2D13"
					( Origin gFrontEnd )
				)
				( attribute "MATERIAL" "X6S"
					( Origin gFrontEnd )
				)
				( attribute "PACK_TYPE" "0603V"
					( Origin gFrontEnd )
				)
				( attribute "PART_NUMBER" "E15431-004"
					( Origin gFrontEnd )
				)
				( attribute "PHYS_PAGE" "76"
					( Origin gFrontEnd )
				)
				( attribute "ROOM" "PVCCIN_CPU1_DECAP_VR"
					( Origin gFrontEnd )
				)
				( attribute "ROT" "0"
					( Origin gFrontEnd )
				)
				( attribute "SEC" "1"
					( Origin gPackager )
				)
				( attribute "TOLERANCE" "20%"
					( Origin gFrontEnd )
				)
				( attribute "VALUE" "22.0UF"
					( Origin gFrontEnd )
				)
				( attribute "VER" "1"
					( Origin gFrontEnd )
				)
				( attribute "VOLTAGE" "4V"
					( Units "uVoltage" "V" 1.000000)
					( Origin gFrontEnd )
				)
				( attribute "XY" "(-4625,3750)"
					( Origin gFrontEnd )
				)
				( attribute "CHIPS_PART_NAME" "CAP_A"
					( Origin gPackager )
				)
				( attribute "CDS_PART_NAME" "CAP_A_0603V-22.0UF,4V,20%,X6S,A"
					( Origin gPackager )
				)
				( objectStatus "C2D13" )
				( pin "a"
					( attribute "PN" "1"
						( Origin gPackager )
					)
					( objectStatus "C2D13.1" )
				)
				( pin "b"
					( attribute "PN" "2"
						( Origin gPackager )
					)
					( objectStatus "C2D13.2" )
				)
			)
			( gate "@baseboard_fab2_lib.baseboard_fab2(sch_1):page76_i75"
				( attribute "BOM_COST" "PROC"
					( Origin gFrontEnd )
				)
				( attribute "CDS_LIB" "dev_discrete"
					( Origin gPackager )
				)
				( attribute "CDS_LOCATION" "C2D19"
					( Origin gPackager )
				)
				( attribute "CDS_SEC" "1"
					( Origin gPackager )
				)
				( attribute "LOCATION" "C2D19"
					( Origin gFrontEnd )
				)
				( attribute "MATERIAL" "X6S"
					( Origin gFrontEnd )
				)
				( attribute "PACK_TYPE" "0603V"
					( Origin gFrontEnd )
				)
				( attribute "PART_NUMBER" "E15431-004"
					( Origin gFrontEnd )
				)
				( attribute "PHYS_PAGE" "76"
					( Origin gFrontEnd )
				)
				( attribute "ROOM" "PVCCIN_CPU1_DECAP_VR"
					( Origin gFrontEnd )
				)
				( attribute "ROT" "0"
					( Origin gFrontEnd )
				)
				( attribute "SEC" "1"
					( Origin gPackager )
				)
				( attribute "TOLERANCE" "20%"
					( Origin gFrontEnd )
				)
				( attribute "VALUE" "22.0UF"
					( Origin gFrontEnd )
				)
				( attribute "VER" "1"
					( Origin gFrontEnd )
				)
				( attribute "VOLTAGE" "4V"
					( Units "uVoltage" "V" 1.000000)
					( Origin gFrontEnd )
				)
				( attribute "XY" "(-4900,3775)"
					( Origin gFrontEnd )
				)
				( attribute "CHIPS_PART_NAME" "CAP_A"
					( Origin gPackager )
				)
				( attribute "CDS_PART_NAME" "CAP_A_0603V-22.0UF,4V,20%,X6S,A"
					( Origin gPackager )
				)
				( objectStatus "C2D19" )
				( pin "a"
					( attribute "PN" "1"
						( Origin gPackager )
					)
					( objectStatus "C2D19.1" )
				)
				( pin "b"
					( attribute "PN" "2"
						( Origin gPackager )
					)
					( objectStatus "C2D19.2" )
				)
			)
			( gate "@baseboard_fab2_lib.baseboard_fab2(sch_1):page76_i76"
				( attribute "BOM_COST" "PROC"
					( Origin gFrontEnd )
				)
				( attribute "CDS_LIB" "dev_discrete"
					( Origin gPackager )
				)
				( attribute "CDS_LOCATION" "C2D14"
					( Origin gPackager )
				)
				( attribute "CDS_SEC" "1"
					( Origin gPackager )
				)
				( attribute "LOCATION" "C2D14"
					( Origin gFrontEnd )
				)
				( attribute "MATERIAL" "X6S"
					( Origin gFrontEnd )
				)
				( attribute "PACK_TYPE" "0603V"
					( Origin gFrontEnd )
				)
				( attribute "PART_NUMBER" "E15431-004"
					( Origin gFrontEnd )
				)
				( attribute "PHYS_PAGE" "76"
					( Origin gFrontEnd )
				)
				( attribute "ROOM" "PVCCIN_CPU1_DECAP_VR"
					( Origin gFrontEnd )
				)
				( attribute "ROT" "0"
					( Origin gFrontEnd )
				)
				( attribute "SEC" "1"
					( Origin gPackager )
				)
				( attribute "TOLERANCE" "20%"
					( Origin gFrontEnd )
				)
				( attribute "VALUE" "22.0UF"
					( Origin gFrontEnd )
				)
				( attribute "VER" "1"
					( Origin gFrontEnd )
				)
				( attribute "VOLTAGE" "4V"
					( Units "uVoltage" "V" 1.000000)
					( Origin gFrontEnd )
				)
				( attribute "XY" "(-4600,3150)"
					( Origin gFrontEnd )
				)
				( attribute "CHIPS_PART_NAME" "CAP_A"
					( Origin gPackager )
				)
				( attribute "CDS_PART_NAME" "CAP_A_0603V-22.0UF,4V,20%,X6S,A"
					( Origin gPackager )
				)
				( objectStatus "C2D14" )
				( pin "a"
					( attribute "PN" "1"
						( Origin gPackager )
					)
					( objectStatus "C2D14.1" )
				)
				( pin "b"
					( attribute "PN" "2"
						( Origin gPackager )
					)
					( objectStatus "C2D14.2" )
				)
			)
			( gate "@baseboard_fab2_lib.baseboard_fab2(sch_1):page76_i79"
				( attribute "BOM_COST" "PROC"
					( Origin gFrontEnd )
				)
				( attribute "CDS_LIB" "dev_discrete"
					( Origin gPackager )
				)
				( attribute "CDS_LOCATION" "C2D20"
					( Origin gPackager )
				)
				( attribute "CDS_SEC" "1"
					( Origin gPackager )
				)
				( attribute "LOCATION" "C2D20"
					( Origin gFrontEnd )
				)
				( attribute "MATERIAL" "X6S"
					( Origin gFrontEnd )
				)
				( attribute "PACK_TYPE" "0603V"
					( Origin gFrontEnd )
				)
				( attribute "PART_NUMBER" "E15431-004"
					( Origin gFrontEnd )
				)
				( attribute "PHYS_PAGE" "76"
					( Origin gFrontEnd )
				)
				( attribute "ROOM" "PVCCIN_CPU1_DECAP_VR"
					( Origin gFrontEnd )
				)
				( attribute "ROT" "0"
					( Origin gFrontEnd )
				)
				( attribute "SEC" "1"
					( Origin gPackager )
				)
				( attribute "TOLERANCE" "20%"
					( Origin gFrontEnd )
				)
				( attribute "VALUE" "22.0UF"
					( Origin gFrontEnd )
				)
				( attribute "VER" "1"
					( Origin gFrontEnd )
				)
				( attribute "VOLTAGE" "4V"
					( Units "uVoltage" "V" 1.000000)
					( Origin gFrontEnd )
				)
				( attribute "XY" "(-4875,3125)"
					( Origin gFrontEnd )
				)
				( attribute "CHIPS_PART_NAME" "CAP_A"
					( Origin gPackager )
				)
				( attribute "CDS_PART_NAME" "CAP_A_0603V-22.0UF,4V,20%,X6S,A"
					( Origin gPackager )
				)
				( objectStatus "C2D20" )
				( pin "a"
					( attribute "PN" "1"
						( Origin gPackager )
					)
					( objectStatus "C2D20.1" )
				)
				( pin "b"
					( attribute "PN" "2"
						( Origin gPackager )
					)
					( objectStatus "C2D20.2" )
				)
			)
			( gate "@baseboard_fab2_lib.baseboard_fab2(sch_1):page76_i80"
				( attribute "BOM_COST" "PROC"
					( Origin gFrontEnd )
				)
				( attribute "CDS_LIB" "dev_discrete"
					( Origin gPackager )
				)
				( attribute "CDS_LOCATION" "C2D24"
					( Origin gPackager )
				)
				( attribute "CDS_SEC" "1"
					( Origin gPackager )
				)
				( attribute "LOCATION" "C2D24"
					( Origin gFrontEnd )
				)
				( attribute "MATERIAL" "X6S"
					( Origin gFrontEnd )
				)
				( attribute "PACK_TYPE" "0603V"
					( Origin gFrontEnd )
				)
				( attribute "PART_NUMBER" "E15431-004"
					( Origin gFrontEnd )
				)
				( attribute "PHYS_PAGE" "76"
					( Origin gFrontEnd )
				)
				( attribute "ROOM" "PVCCIN_CPU1_DECAP_VR"
					( Origin gFrontEnd )
				)
				( attribute "ROT" "0"
					( Origin gFrontEnd )
				)
				( attribute "SEC" "1"
					( Origin gPackager )
				)
				( attribute "TOLERANCE" "20%"
					( Origin gFrontEnd )
				)
				( attribute "VALUE" "22.0UF"
					( Origin gFrontEnd )
				)
				( attribute "VER" "1"
					( Origin gFrontEnd )
				)
				( attribute "VOLTAGE" "4V"
					( Units "uVoltage" "V" 1.000000)
					( Origin gFrontEnd )
				)
				( attribute "XY" "(-5200,3150)"
					( Origin gFrontEnd )
				)
				( attribute "CHIPS_PART_NAME" "CAP_A"
					( Origin gPackager )
				)
				( attribute "CDS_PART_NAME" "CAP_A_0603V-22.0UF,4V,20%,X6S,A"
					( Origin gPackager )
				)
				( objectStatus "C2D24" )
				( pin "a"
					( attribute "PN" "1"
						( Origin gPackager )
					)
					( objectStatus "C2D24.1" )
				)
				( pin "b"
					( attribute "PN" "2"
						( Origin gPackager )
					)
					( objectStatus "C2D24.2" )
				)
			)
			( gate "@baseboard_fab2_lib.baseboard_fab2(sch_1):page76_i82"
				( attribute "BOM_COST" "PROC"
					( Origin gFrontEnd )
				)
				( attribute "CDS_LIB" "dev_discrete"
					( Origin gPackager )
				)
				( attribute "CDS_LOCATION" "C2D25"
					( Origin gPackager )
				)
				( attribute "CDS_SEC" "1"
					( Origin gPackager )
				)
				( attribute "LOCATION" "C2D25"
					( Origin gFrontEnd )
				)
				( attribute "MATERIAL" "X6S"
					( Origin gFrontEnd )
				)
				( attribute "PACK_TYPE" "0603V"
					( Origin gFrontEnd )
				)
				( attribute "PART_NUMBER" "E15431-004"
					( Origin gFrontEnd )
				)
				( attribute "PHYS_PAGE" "76"
					( Origin gFrontEnd )
				)
				( attribute "ROOM" "PVCCIN_CPU1_DECAP_VR"
					( Origin gFrontEnd )
				)
				( attribute "ROT" "0"
					( Origin gFrontEnd )
				)
				( attribute "SEC" "1"
					( Origin gPackager )
				)
				( attribute "TOLERANCE" "20%"
					( Origin gFrontEnd )
				)
				( attribute "VALUE" "22.0UF"
					( Origin gFrontEnd )
				)
				( attribute "VER" "1"
					( Origin gFrontEnd )
				)
				( attribute "VOLTAGE" "4V"
					( Units "uVoltage" "V" 1.000000)
					( Origin gFrontEnd )
				)
				( attribute "XY" "(-5225,3775)"
					( Origin gFrontEnd )
				)
				( attribute "CHIPS_PART_NAME" "CAP_A"
					( Origin gPackager )
				)
				( attribute "CDS_PART_NAME" "CAP_A_0603V-22.0UF,4V,20%,X6S,A"
					( Origin gPackager )
				)
				( objectStatus "C2D25" )
				( pin "a"
					( attribute "PN" "1"
						( Origin gPackager )
					)
					( objectStatus "C2D25.1" )
				)
				( pin "b"
					( attribute "PN" "2"
						( Origin gPackager )
					)
					( objectStatus "C2D25.2" )
				)
			)
			( gate "@baseboard_fab2_lib.baseboard_fab2(sch_1):page76_i83"
				( attribute "BOM_COST" "PROC"
					( Origin gFrontEnd )
				)
				( attribute "CDS_LIB" "dev_discrete"
					( Origin gPackager )
				)
				( attribute "CDS_LOCATION" "C2D30"
					( Origin gPackager )
				)
				( attribute "CDS_SEC" "1"
					( Origin gPackager )
				)
				( attribute "LOCATION" "C2D30"
					( Origin gFrontEnd )
				)
				( attribute "MATERIAL" "X6S"
					( Origin gFrontEnd )
				)
				( attribute "PACK_TYPE" "0603V"
					( Origin gFrontEnd )
				)
				( attribute "PART_NUMBER" "E15431-004"
					( Origin gFrontEnd )
				)
				( attribute "PHYS_PAGE" "76"
					( Origin gFrontEnd )
				)
				( attribute "ROOM" "PVCCIN_CPU1_DECAP_VR"
					( Origin gFrontEnd )
				)
				( attribute "ROT" "0"
					( Origin gFrontEnd )
				)
				( attribute "SEC" "1"
					( Origin gPackager )
				)
				( attribute "TOLERANCE" "20%"
					( Origin gFrontEnd )
				)
				( attribute "VALUE" "22.0UF"
					( Origin gFrontEnd )
				)
				( attribute "VER" "1"
					( Origin gFrontEnd )
				)
				( attribute "VOLTAGE" "4V"
					( Units "uVoltage" "V" 1.000000)
					( Origin gFrontEnd )
				)
				( attribute "XY" "(-5550,3775)"
					( Origin gFrontEnd )
				)
				( attribute "CHIPS_PART_NAME" "CAP_A"
					( Origin gPackager )
				)
				( attribute "CDS_PART_NAME" "CAP_A_0603V-22.0UF,4V,20%,X6S,A"
					( Origin gPackager )
				)
				( objectStatus "C2D30" )
				( pin "a"
					( attribute "PN" "1"
						( Origin gPackager )
					)
					( objectStatus "C2D30.1" )
				)
				( pin "b"
					( attribute "PN" "2"
						( Origin gPackager )
					)
					( objectStatus "C2D30.2" )
				)
			)
			( gate "@baseboard_fab2_lib.baseboard_fab2(sch_1):page76_i85"
				( attribute "BOM_COST" "PROC"
					( Origin gFrontEnd )
				)
				( attribute "CDS_LIB" "dev_discrete"
					( Origin gPackager )
				)
				( attribute "CDS_LOCATION" "C2D33"
					( Origin gPackager )
				)
				( attribute "CDS_SEC" "1"
					( Origin gPackager )
				)
				( attribute "LOCATION" "C2D33"
					( Origin gFrontEnd )
				)
				( attribute "MATERIAL" "X6S"
					( Origin gFrontEnd )
				)
				( attribute "PACK_TYPE" "0603V"
					( Origin gFrontEnd )
				)
				( attribute "PART_NUMBER" "E15431-004"
					( Origin gFrontEnd )
				)
				( attribute "PHYS_PAGE" "76"
					( Origin gFrontEnd )
				)
				( attribute "ROOM" "PVCCIN_CPU1_DECAP_VR"
					( Origin gFrontEnd )
				)
				( attribute "ROT" "0"
					( Origin gFrontEnd )
				)
				( attribute "SEC" "1"
					( Origin gPackager )
				)
				( attribute "TOLERANCE" "20%"
					( Origin gFrontEnd )
				)
				( attribute "VALUE" "22.0UF"
					( Origin gFrontEnd )
				)
				( attribute "VER" "1"
					( Origin gFrontEnd )
				)
				( attribute "VOLTAGE" "4V"
					( Units "uVoltage" "V" 1.000000)
					( Origin gFrontEnd )
				)
				( attribute "XY" "(-5875,3775)"
					( Origin gFrontEnd )
				)
				( attribute "CHIPS_PART_NAME" "CAP_A"
					( Origin gPackager )
				)
				( attribute "CDS_PART_NAME" "CAP_A_0603V-22.0UF,4V,20%,X6S,A"
					( Origin gPackager )
				)
				( objectStatus "C2D33" )
				( pin "a"
					( attribute "PN" "1"
						( Origin gPackager )
					)
					( objectStatus "C2D33.1" )
				)
				( pin "b"
					( attribute "PN" "2"
						( Origin gPackager )
					)
					( objectStatus "C2D33.2" )
				)
			)
			( gate "@baseboard_fab2_lib.baseboard_fab2(sch_1):page76_i88"
				( attribute "BOM_COST" "PROC"
					( Origin gFrontEnd )
				)
				( attribute "CDS_LIB" "mstr_discrete"
					( Origin gPackager )
				)
				( attribute "CDS_LOCATION" "C8P4"
					( Origin gPackager )
				)
				( attribute "CDS_SEC" "1"
					( Origin gPackager )
				)
				( attribute "LOCATION" "C8P4"
					( Origin gFrontEnd )
				)
				( attribute "MATERIAL" "X6S"
					( Origin gFrontEnd )
				)
				( attribute "PACK_TYPE" "0805"
					( Origin gFrontEnd )
				)
				( attribute "PART_NUMBER" "C95333-006"
					( Origin gFrontEnd )
				)
				( attribute "PHYS_PAGE" "76"
					( Origin gFrontEnd )
				)
				( attribute "ROOM" "PVCCIN_CPU1_DECAP_VR"
					( Origin gFrontEnd )
				)
				( attribute "ROT" "0"
					( Origin gFrontEnd )
				)
				( attribute "SEC" "1"
					( Origin gPackager )
				)
				( attribute "TOLERANCE" "20%"
					( Origin gFrontEnd )
				)
				( attribute "VALUE" "47UF"
					( Origin gFrontEnd )
				)
				( attribute "VER" "1"
					( Origin gFrontEnd )
				)
				( attribute "VOLTAGE" "4V"
					( Units "uVoltage" "V" 1.000000)
					( Origin gFrontEnd )
				)
				( attribute "XY" "(-5425,2200)"
					( Origin gFrontEnd )
				)
				( attribute "CHIPS_PART_NAME" "CAP"
					( Origin gPackager )
				)
				( attribute "CDS_PART_NAME" "CAP_0805-47UF,4V,20%,X6S,C9533A"
					( Origin gPackager )
				)
				( objectStatus "C8P4" )
				( pin "a"
					( attribute "PN" "1"
						( Origin gPackager )
					)
					( objectStatus "C8P4.1" )
				)
				( pin "b"
					( attribute "PN" "2"
						( Origin gPackager )
					)
					( objectStatus "C8P4.2" )
				)
			)
			( gate "@baseboard_fab2_lib.baseboard_fab2(sch_1):page76_i89"
				( attribute "BOM_COST" "PROC"
					( Origin gFrontEnd )
				)
				( attribute "CDS_LIB" "mstr_discrete"
					( Origin gPackager )
				)
				( attribute "CDS_LOCATION" "C8P20"
					( Origin gPackager )
				)
				( attribute "CDS_SEC" "1"
					( Origin gPackager )
				)
				( attribute "LOCATION" "C8P20"
					( Origin gFrontEnd )
				)
				( attribute "MATERIAL" "X6S"
					( Origin gFrontEnd )
				)
				( attribute "PACK_TYPE" "0805"
					( Origin gFrontEnd )
				)
				( attribute "PART_NUMBER" "C95333-006"
					( Origin gFrontEnd )
				)
				( attribute "PHYS_PAGE" "76"
					( Origin gFrontEnd )
				)
				( attribute "ROOM" "PVCCIN_CPU1_DECAP_VR"
					( Origin gFrontEnd )
				)
				( attribute "ROT" "0"
					( Origin gFrontEnd )
				)
				( attribute "SEC" "1"
					( Origin gPackager )
				)
				( attribute "TOLERANCE" "20%"
					( Origin gFrontEnd )
				)
				( attribute "VALUE" "47UF"
					( Origin gFrontEnd )
				)
				( attribute "VER" "1"
					( Origin gFrontEnd )
				)
				( attribute "VOLTAGE" "4V"
					( Units "uVoltage" "V" 1.000000)
					( Origin gFrontEnd )
				)
				( attribute "XY" "(-5700,2200)"
					( Origin gFrontEnd )
				)
				( attribute "CHIPS_PART_NAME" "CAP"
					( Origin gPackager )
				)
				( attribute "CDS_PART_NAME" "CAP_0805-47UF,4V,20%,X6S,C9533A"
					( Origin gPackager )
				)
				( objectStatus "C8P20" )
				( pin "a"
					( attribute "PN" "1"
						( Origin gPackager )
					)
					( objectStatus "C8P20.1" )
				)
				( pin "b"
					( attribute "PN" "2"
						( Origin gPackager )
					)
					( objectStatus "C8P20.2" )
				)
			)
			( gate "@baseboard_fab2_lib.baseboard_fab2(sch_1):page76_i90"
				( attribute "BOM_COST" "PROC"
					( Origin gFrontEnd )
				)
				( attribute "CDS_LIB" "dev_discrete"
					( Origin gPackager )
				)
				( attribute "CDS_LOCATION" "C2D32"
					( Origin gPackager )
				)
				( attribute "CDS_SEC" "1"
					( Origin gPackager )
				)
				( attribute "LOCATION" "C2D32"
					( Origin gFrontEnd )
				)
				( attribute "MATERIAL" "X6S"
					( Origin gFrontEnd )
				)
				( attribute "PACK_TYPE" "0603V"
					( Origin gFrontEnd )
				)
				( attribute "PART_NUMBER" "E15431-004"
					( Origin gFrontEnd )
				)
				( attribute "PHYS_PAGE" "76"
					( Origin gFrontEnd )
				)
				( attribute "ROOM" "PVCCIN_CPU1_DECAP_VR"
					( Origin gFrontEnd )
				)
				( attribute "ROT" "0"
					( Origin gFrontEnd )
				)
				( attribute "SEC" "1"
					( Origin gPackager )
				)
				( attribute "TOLERANCE" "20%"
					( Origin gFrontEnd )
				)
				( attribute "VALUE" "22.0UF"
					( Origin gFrontEnd )
				)
				( attribute "VER" "1"
					( Origin gFrontEnd )
				)
				( attribute "VOLTAGE" "4V"
					( Units "uVoltage" "V" 1.000000)
					( Origin gFrontEnd )
				)
				( attribute "XY" "(-5850,3150)"
					( Origin gFrontEnd )
				)
				( attribute "CHIPS_PART_NAME" "CAP_A"
					( Origin gPackager )
				)
				( attribute "CDS_PART_NAME" "CAP_A_0603V-22.0UF,4V,20%,X6S,A"
					( Origin gPackager )
				)
				( objectStatus "C2D32" )
				( pin "a"
					( attribute "PN" "1"
						( Origin gPackager )
					)
					( objectStatus "C2D32.1" )
				)
				( pin "b"
					( attribute "PN" "2"
						( Origin gPackager )
					)
					( objectStatus "C2D32.2" )
				)
			)
			( gate "@baseboard_fab2_lib.baseboard_fab2(sch_1):page76_i92"
				( attribute "BOM_COST" "PROC"
					( Origin gFrontEnd )
				)
				( attribute "CDS_LIB" "mstr_discrete"
					( Origin gPackager )
				)
				( attribute "CDS_LOCATION" "C8P18"
					( Origin gPackager )
				)
				( attribute "CDS_SEC" "1"
					( Origin gPackager )
				)
				( attribute "LOCATION" "C8P18"
					( Origin gFrontEnd )
				)
				( attribute "MATERIAL" "X6S"
					( Origin gFrontEnd )
				)
				( attribute "PACK_TYPE" "0805"
					( Origin gFrontEnd )
				)
				( attribute "PART_NUMBER" "C95333-006"
					( Origin gFrontEnd )
				)
				( attribute "PHYS_PAGE" "76"
					( Origin gFrontEnd )
				)
				( attribute "ROOM" "PVCCIN_CPU1_DECAP_VR"
					( Origin gFrontEnd )
				)
				( attribute "ROT" "0"
					( Origin gFrontEnd )
				)
				( attribute "SEC" "1"
					( Origin gPackager )
				)
				( attribute "TOLERANCE" "20%"
					( Origin gFrontEnd )
				)
				( attribute "VALUE" "47UF"
					( Origin gFrontEnd )
				)
				( attribute "VER" "1"
					( Origin gFrontEnd )
				)
				( attribute "VOLTAGE" "4V"
					( Units "uVoltage" "V" 1.000000)
					( Origin gFrontEnd )
				)
				( attribute "XY" "(-5975,2200)"
					( Origin gFrontEnd )
				)
				( attribute "CHIPS_PART_NAME" "CAP"
					( Origin gPackager )
				)
				( attribute "CDS_PART_NAME" "CAP_0805-47UF,4V,20%,X6S,C9533A"
					( Origin gPackager )
				)
				( objectStatus "C8P18" )
				( pin "a"
					( attribute "PN" "1"
						( Origin gPackager )
					)
					( objectStatus "C8P18.1" )
				)
				( pin "b"
					( attribute "PN" "2"
						( Origin gPackager )
					)
					( objectStatus "C8P18.2" )
				)
			)
			( gate "@baseboard_fab2_lib.baseboard_fab2(sch_1):page76_i100"
				( attribute "BOM_COST" "PROC"
					( Origin gFrontEnd )
				)
				( attribute "CDS_LIB" "mstr_discrete"
					( Origin gPackager )
				)
				( attribute "CDS_LOCATION" "C7P2"
					( Origin gPackager )
				)
				( attribute "CDS_SEC" "1"
					( Origin gPackager )
				)
				( attribute "LOCATION" "C7P2"
					( Origin gFrontEnd )
				)
				( attribute "MATERIAL" "X6S"
					( Origin gFrontEnd )
				)
				( attribute "PACK_TYPE" "0805"
					( Origin gFrontEnd )
				)
				( attribute "PART_NUMBER" "C95333-006"
					( Origin gFrontEnd )
				)
				( attribute "PHYS_PAGE" "76"
					( Origin gFrontEnd )
				)
				( attribute "ROOM" "PVCCIN_CPU1_DECAP_VR"
					( Origin gFrontEnd )
				)
				( attribute "ROT" "0"
					( Origin gFrontEnd )
				)
				( attribute "SEC" "1"
					( Origin gPackager )
				)
				( attribute "TOLERANCE" "20%"
					( Origin gFrontEnd )
				)
				( attribute "VALUE" "47UF"
					( Origin gFrontEnd )
				)
				( attribute "VER" "1"
					( Origin gFrontEnd )
				)
				( attribute "VOLTAGE" "4V"
					( Units "uVoltage" "V" 1.000000)
					( Origin gFrontEnd )
				)
				( attribute "XY" "(-5300,1550)"
					( Origin gFrontEnd )
				)
				( attribute "CHIPS_PART_NAME" "CAP"
					( Origin gPackager )
				)
				( attribute "CDS_PART_NAME" "CAP_0805-47UF,4V,20%,X6S,C9533A"
					( Origin gPackager )
				)
				( objectStatus "C7P2" )
				( pin "a"
					( attribute "PN" "1"
						( Origin gPackager )
					)
					( objectStatus "C7P2.1" )
				)
				( pin "b"
					( attribute "PN" "2"
						( Origin gPackager )
					)
					( objectStatus "C7P2.2" )
				)
			)
			( gate "@baseboard_fab2_lib.baseboard_fab2(sch_1):page76_i101"
				( attribute "BOM_COST" "PROC"
					( Origin gFrontEnd )
				)
				( attribute "CDS_LIB" "mstr_discrete"
					( Origin gPackager )
				)
				( attribute "CDS_LOCATION" "C8P3"
					( Origin gPackager )
				)
				( attribute "CDS_SEC" "1"
					( Origin gPackager )
				)
				( attribute "LOCATION" "C8P3"
					( Origin gFrontEnd )
				)
				( attribute "MATERIAL" "X6S"
					( Origin gFrontEnd )
				)
				( attribute "PACK_TYPE" "0805"
					( Origin gFrontEnd )
				)
				( attribute "PART_NUMBER" "C95333-006"
					( Origin gFrontEnd )
				)
				( attribute "PHYS_PAGE" "76"
					( Origin gFrontEnd )
				)
				( attribute "ROOM" "PVCCIN_CPU1_DECAP_VR"
					( Origin gFrontEnd )
				)
				( attribute "ROT" "0"
					( Origin gFrontEnd )
				)
				( attribute "SEC" "1"
					( Origin gPackager )
				)
				( attribute "TOLERANCE" "20%"
					( Origin gFrontEnd )
				)
				( attribute "VALUE" "47UF"
					( Origin gFrontEnd )
				)
				( attribute "VER" "1"
					( Origin gFrontEnd )
				)
				( attribute "VOLTAGE" "4V"
					( Units "uVoltage" "V" 1.000000)
					( Origin gFrontEnd )
				)
				( attribute "XY" "(-5625,1550)"
					( Origin gFrontEnd )
				)
				( attribute "CHIPS_PART_NAME" "CAP"
					( Origin gPackager )
				)
				( attribute "CDS_PART_NAME" "CAP_0805-47UF,4V,20%,X6S,C9533A"
					( Origin gPackager )
				)
				( objectStatus "C8P3" )
				( pin "a"
					( attribute "PN" "1"
						( Origin gPackager )
					)
					( objectStatus "C8P3.1" )
				)
				( pin "b"
					( attribute "PN" "2"
						( Origin gPackager )
					)
					( objectStatus "C8P3.2" )
				)
			)
			( gate "@baseboard_fab2_lib.baseboard_fab2(sch_1):page76_i103"
				( attribute "BOM_COST" "PROC"
					( Origin gFrontEnd )
				)
				( attribute "CDS_LIB" "mstr_discrete"
					( Origin gPackager )
				)
				( attribute "CDS_LOCATION" "C8P19"
					( Origin gPackager )
				)
				( attribute "CDS_SEC" "1"
					( Origin gPackager )
				)
				( attribute "LOCATION" "C8P19"
					( Origin gFrontEnd )
				)
				( attribute "MATERIAL" "X6S"
					( Origin gFrontEnd )
				)
				( attribute "PACK_TYPE" "0805"
					( Origin gFrontEnd )
				)
				( attribute "PART_NUMBER" "C95333-006"
					( Origin gFrontEnd )
				)
				( attribute "PHYS_PAGE" "76"
					( Origin gFrontEnd )
				)
				( attribute "ROOM" "PVCCIN_CPU1_DECAP_VR"
					( Origin gFrontEnd )
				)
				( attribute "ROT" "0"
					( Origin gFrontEnd )
				)
				( attribute "SEC" "1"
					( Origin gPackager )
				)
				( attribute "TOLERANCE" "20%"
					( Origin gFrontEnd )
				)
				( attribute "VALUE" "47UF"
					( Origin gFrontEnd )
				)
				( attribute "VER" "1"
					( Origin gFrontEnd )
				)
				( attribute "VOLTAGE" "4V"
					( Units "uVoltage" "V" 1.000000)
					( Origin gFrontEnd )
				)
				( attribute "XY" "(-5975,1550)"
					( Origin gFrontEnd )
				)
				( attribute "CHIPS_PART_NAME" "CAP"
					( Origin gPackager )
				)
				( attribute "CDS_PART_NAME" "CAP_0805-47UF,4V,20%,X6S,C9533A"
					( Origin gPackager )
				)
				( objectStatus "C8P19" )
				( pin "a"
					( attribute "PN" "1"
						( Origin gPackager )
					)
					( objectStatus "C8P19.1" )
				)
				( pin "b"
					( attribute "PN" "2"
						( Origin gPackager )
					)
					( objectStatus "C8P19.2" )
				)
			)
			( gate "@baseboard_fab2_lib.baseboard_fab2(sch_1):page76_i105"
				( attribute "BOM_COST" "PROC"
					( Origin gFrontEnd )
				)
				( attribute "CDS_LIB" "mstr_discrete"
					( Origin gPackager )
				)
				( attribute "CDS_LOCATION" "C7P1"
					( Origin gPackager )
				)
				( attribute "CDS_SEC" "1"
					( Origin gPackager )
				)
				( attribute "LOCATION" "C7P1"
					( Origin gFrontEnd )
				)
				( attribute "MATERIAL" "X6S"
					( Origin gFrontEnd )
				)
				( attribute "PACK_TYPE" "0805"
					( Origin gFrontEnd )
				)
				( attribute "PART_NUMBER" "C95333-006"
					( Origin gFrontEnd )
				)
				( attribute "PHYS_PAGE" "76"
					( Origin gFrontEnd )
				)
				( attribute "ROOM" "PVCCIN_CPU1_DECAP_VR"
					( Origin gFrontEnd )
				)
				( attribute "ROT" "0"
					( Origin gFrontEnd )
				)
				( attribute "SEC" "1"
					( Origin gPackager )
				)
				( attribute "TOLERANCE" "20%"
					( Origin gFrontEnd )
				)
				( attribute "VALUE" "47UF"
					( Origin gFrontEnd )
				)
				( attribute "VER" "1"
					( Origin gFrontEnd )
				)
				( attribute "VOLTAGE" "4V"
					( Units "uVoltage" "V" 1.000000)
					( Origin gFrontEnd )
				)
				( attribute "XY" "(-5275,875)"
					( Origin gFrontEnd )
				)
				( attribute "CHIPS_PART_NAME" "CAP"
					( Origin gPackager )
				)
				( attribute "CDS_PART_NAME" "CAP_0805-47UF,4V,20%,X6S,C9533A"
					( Origin gPackager )
				)
				( objectStatus "C7P1" )
				( pin "a"
					( attribute "PN" "1"
						( Origin gPackager )
					)
					( objectStatus "C7P1.1" )
				)
				( pin "b"
					( attribute "PN" "2"
						( Origin gPackager )
					)
					( objectStatus "C7P1.2" )
				)
			)
			( gate "@baseboard_fab2_lib.baseboard_fab2(sch_1):page76_i106"
				( attribute "BOM_COST" "PROC"
					( Origin gFrontEnd )
				)
				( attribute "CDS_LIB" "mstr_discrete"
					( Origin gPackager )
				)
				( attribute "CDS_LOCATION" "C8P34"
					( Origin gPackager )
				)
				( attribute "CDS_SEC" "1"
					( Origin gPackager )
				)
				( attribute "LOCATION" "C8P34"
					( Origin gFrontEnd )
				)
				( attribute "MATERIAL" "X6S"
					( Origin gFrontEnd )
				)
				( attribute "PACK_TYPE" "0805"
					( Origin gFrontEnd )
				)
				( attribute "PART_NUMBER" "C95333-006"
					( Origin gFrontEnd )
				)
				( attribute "PHYS_PAGE" "76"
					( Origin gFrontEnd )
				)
				( attribute "ROOM" "PVCCIN_CPU1_DECAP_VR"
					( Origin gFrontEnd )
				)
				( attribute "ROT" "0"
					( Origin gFrontEnd )
				)
				( attribute "SEC" "1"
					( Origin gPackager )
				)
				( attribute "TOLERANCE" "20%"
					( Origin gFrontEnd )
				)
				( attribute "VALUE" "47UF"
					( Origin gFrontEnd )
				)
				( attribute "VER" "1"
					( Origin gFrontEnd )
				)
				( attribute "VOLTAGE" "4V"
					( Units "uVoltage" "V" 1.000000)
					( Origin gFrontEnd )
				)
				( attribute "XY" "(-5600,875)"
					( Origin gFrontEnd )
				)
				( attribute "CHIPS_PART_NAME" "CAP"
					( Origin gPackager )
				)
				( attribute "CDS_PART_NAME" "CAP_0805-47UF,4V,20%,X6S,C9533A"
					( Origin gPackager )
				)
				( objectStatus "C8P34" )
				( pin "a"
					( attribute "PN" "1"
						( Origin gPackager )
					)
					( objectStatus "C8P34.1" )
				)
				( pin "b"
					( attribute "PN" "2"
						( Origin gPackager )
					)
					( objectStatus "C8P34.2" )
				)
			)
			( gate "@baseboard_fab2_lib.baseboard_fab2(sch_1):page76_i107"
				( attribute "BOM_COST" "PROC"
					( Origin gFrontEnd )
				)
				( attribute "CDS_LIB" "mstr_discrete"
					( Origin gPackager )
				)
				( attribute "CDS_LOCATION" "C8P12"
					( Origin gPackager )
				)
				( attribute "CDS_SEC" "1"
					( Origin gPackager )
				)
				( attribute "LOCATION" "C8P12"
					( Origin gFrontEnd )
				)
				( attribute "MATERIAL" "X6S"
					( Origin gFrontEnd )
				)
				( attribute "PACK_TYPE" "0805"
					( Origin gFrontEnd )
				)
				( attribute "PART_NUMBER" "C95333-006"
					( Origin gFrontEnd )
				)
				( attribute "PHYS_PAGE" "76"
					( Origin gFrontEnd )
				)
				( attribute "ROOM" "PVCCIN_CPU1_DECAP_VR"
					( Origin gFrontEnd )
				)
				( attribute "ROT" "0"
					( Origin gFrontEnd )
				)
				( attribute "SEC" "1"
					( Origin gPackager )
				)
				( attribute "TOLERANCE" "20%"
					( Origin gFrontEnd )
				)
				( attribute "VALUE" "47UF"
					( Origin gFrontEnd )
				)
				( attribute "VER" "1"
					( Origin gFrontEnd )
				)
				( attribute "VOLTAGE" "4V"
					( Units "uVoltage" "V" 1.000000)
					( Origin gFrontEnd )
				)
				( attribute "XY" "(-5950,875)"
					( Origin gFrontEnd )
				)
				( attribute "CHIPS_PART_NAME" "CAP"
					( Origin gPackager )
				)
				( attribute "CDS_PART_NAME" "CAP_0805-47UF,4V,20%,X6S,C9533A"
					( Origin gPackager )
				)
				( objectStatus "C8P12" )
				( pin "a"
					( attribute "PN" "1"
						( Origin gPackager )
					)
					( objectStatus "C8P12.1" )
				)
				( pin "b"
					( attribute "PN" "2"
						( Origin gPackager )
					)
					( objectStatus "C8P12.2" )
				)
			)
			( gate "@baseboard_fab2_lib.baseboard_fab2(sch_1):page76_i108"
				( attribute "BOM_COST" "PROC"
					( Origin gFrontEnd )
				)
				( attribute "CDS_LIB" "dev_discrete"
					( Origin gPackager )
				)
				( attribute "CDS_LOCATION" "C2D26"
					( Origin gPackager )
				)
				( attribute "CDS_SEC" "1"
					( Origin gPackager )
				)
				( attribute "LOCATION" "C2D26"
					( Origin gFrontEnd )
				)
				( attribute "MATERIAL" "X6S"
					( Origin gFrontEnd )
				)
				( attribute "PACK_TYPE" "0603V"
					( Origin gFrontEnd )
				)
				( attribute "PART_NUMBER" "E15431-004"
					( Origin gFrontEnd )
				)
				( attribute "PHYS_PAGE" "76"
					( Origin gFrontEnd )
				)
				( attribute "ROOM" "PVCCIN_CPU1_DECAP_VR"
					( Origin gFrontEnd )
				)
				( attribute "ROT" "0"
					( Origin gFrontEnd )
				)
				( attribute "SEC" "1"
					( Origin gPackager )
				)
				( attribute "TOLERANCE" "20%"
					( Origin gFrontEnd )
				)
				( attribute "VALUE" "22.0UF"
					( Origin gFrontEnd )
				)
				( attribute "VER" "1"
					( Origin gFrontEnd )
				)
				( attribute "VOLTAGE" "4V"
					( Units "uVoltage" "V" 1.000000)
					( Origin gFrontEnd )
				)
				( attribute "XY" "(-6300,3775)"
					( Origin gFrontEnd )
				)
				( attribute "CHIPS_PART_NAME" "CAP_A"
					( Origin gPackager )
				)
				( attribute "CDS_PART_NAME" "CAP_A_0603V-22.0UF,4V,20%,X6S,A"
					( Origin gPackager )
				)
				( objectStatus "C2D26" )
				( pin "a"
					( attribute "PN" "1"
						( Origin gPackager )
					)
					( objectStatus "C2D26.1" )
				)
				( pin "b"
					( attribute "PN" "2"
						( Origin gPackager )
					)
					( objectStatus "C2D26.2" )
				)
			)
			( gate "@baseboard_fab2_lib.baseboard_fab2(sch_1):page76_i111"
				( attribute "BOM_COST" "PROC"
					( Origin gFrontEnd )
				)
				( attribute "CDS_LIB" "dev_discrete"
					( Origin gPackager )
				)
				( attribute "CDS_LOCATION" "C3D1"
					( Origin gPackager )
				)
				( attribute "CDS_SEC" "1"
					( Origin gPackager )
				)
				( attribute "LOCATION" "C3D1"
					( Origin gFrontEnd )
				)
				( attribute "MATERIAL" "X6S"
					( Origin gFrontEnd )
				)
				( attribute "PACK_TYPE" "0603V"
					( Origin gFrontEnd )
				)
				( attribute "PART_NUMBER" "E15431-004"
					( Origin gFrontEnd )
				)
				( attribute "PHYS_PAGE" "76"
					( Origin gFrontEnd )
				)
				( attribute "ROOM" "PVCCIN_CPU1_DECAP_VR"
					( Origin gFrontEnd )
				)
				( attribute "ROT" "0"
					( Origin gFrontEnd )
				)
				( attribute "SEC" "1"
					( Origin gPackager )
				)
				( attribute "TOLERANCE" "20%"
					( Origin gFrontEnd )
				)
				( attribute "VALUE" "22.0UF"
					( Origin gFrontEnd )
				)
				( attribute "VER" "1"
					( Origin gFrontEnd )
				)
				( attribute "VOLTAGE" "4V"
					( Units "uVoltage" "V" 1.000000)
					( Origin gFrontEnd )
				)
				( attribute "XY" "(-7000,3775)"
					( Origin gFrontEnd )
				)
				( attribute "CHIPS_PART_NAME" "CAP_A"
					( Origin gPackager )
				)
				( attribute "CDS_PART_NAME" "CAP_A_0603V-22.0UF,4V,20%,X6S,A"
					( Origin gPackager )
				)
				( objectStatus "C3D1" )
				( pin "a"
					( attribute "PN" "1"
						( Origin gPackager )
					)
					( objectStatus "C3D1.1" )
				)
				( pin "b"
					( attribute "PN" "2"
						( Origin gPackager )
					)
					( objectStatus "C3D1.2" )
				)
			)
			( gate "@baseboard_fab2_lib.baseboard_fab2(sch_1):page76_i112"
				( attribute "BOM_COST" "PROC"
					( Origin gFrontEnd )
				)
				( attribute "CDS_LIB" "dev_discrete"
					( Origin gPackager )
				)
				( attribute "CDS_LOCATION" "C2D23"
					( Origin gPackager )
				)
				( attribute "CDS_SEC" "1"
					( Origin gPackager )
				)
				( attribute "LOCATION" "C2D23"
					( Origin gFrontEnd )
				)
				( attribute "MATERIAL" "X6S"
					( Origin gFrontEnd )
				)
				( attribute "PACK_TYPE" "0603V"
					( Origin gFrontEnd )
				)
				( attribute "PART_NUMBER" "E15431-004"
					( Origin gFrontEnd )
				)
				( attribute "PHYS_PAGE" "76"
					( Origin gFrontEnd )
				)
				( attribute "ROOM" "PVCCIN_CPU1_DECAP_VR"
					( Origin gFrontEnd )
				)
				( attribute "ROT" "0"
					( Origin gFrontEnd )
				)
				( attribute "SEC" "1"
					( Origin gPackager )
				)
				( attribute "TOLERANCE" "20%"
					( Origin gFrontEnd )
				)
				( attribute "VALUE" "22.0UF"
					( Origin gFrontEnd )
				)
				( attribute "VER" "1"
					( Origin gFrontEnd )
				)
				( attribute "VOLTAGE" "4V"
					( Units "uVoltage" "V" 1.000000)
					( Origin gFrontEnd )
				)
				( attribute "XY" "(-6250,3150)"
					( Origin gFrontEnd )
				)
				( attribute "CHIPS_PART_NAME" "CAP_A"
					( Origin gPackager )
				)
				( attribute "CDS_PART_NAME" "CAP_A_0603V-22.0UF,4V,20%,X6S,A"
					( Origin gPackager )
				)
				( objectStatus "C2D23" )
				( pin "a"
					( attribute "PN" "1"
						( Origin gPackager )
					)
					( objectStatus "C2D23.1" )
				)
				( pin "b"
					( attribute "PN" "2"
						( Origin gPackager )
					)
					( objectStatus "C2D23.2" )
				)
			)
			( gate "@baseboard_fab2_lib.baseboard_fab2(sch_1):page76_i114"
				( attribute "BOM_COST" "PROC"
					( Origin gFrontEnd )
				)
				( attribute "CDS_LIB" "dev_discrete"
					( Origin gPackager )
				)
				( attribute "CDS_LOCATION" "C2D17"
					( Origin gPackager )
				)
				( attribute "CDS_SEC" "1"
					( Origin gPackager )
				)
				( attribute "LOCATION" "C2D17"
					( Origin gFrontEnd )
				)
				( attribute "MATERIAL" "X6S"
					( Origin gFrontEnd )
				)
				( attribute "PACK_TYPE" "0603V"
					( Origin gFrontEnd )
				)
				( attribute "PART_NUMBER" "E15431-004"
					( Origin gFrontEnd )
				)
				( attribute "PHYS_PAGE" "76"
					( Origin gFrontEnd )
				)
				( attribute "ROOM" "PVCCIN_CPU1_DECAP_VR"
					( Origin gFrontEnd )
				)
				( attribute "ROT" "0"
					( Origin gFrontEnd )
				)
				( attribute "SEC" "1"
					( Origin gPackager )
				)
				( attribute "TOLERANCE" "20%"
					( Origin gFrontEnd )
				)
				( attribute "VALUE" "22.0UF"
					( Origin gFrontEnd )
				)
				( attribute "VER" "1"
					( Origin gFrontEnd )
				)
				( attribute "VOLTAGE" "4V"
					( Units "uVoltage" "V" 1.000000)
					( Origin gFrontEnd )
				)
				( attribute "XY" "(-6600,3125)"
					( Origin gFrontEnd )
				)
				( attribute "CHIPS_PART_NAME" "CAP_A"
					( Origin gPackager )
				)
				( attribute "CDS_PART_NAME" "CAP_A_0603V-22.0UF,4V,20%,X6S,A"
					( Origin gPackager )
				)
				( objectStatus "C2D17" )
				( pin "a"
					( attribute "PN" "1"
						( Origin gPackager )
					)
					( objectStatus "C2D17.1" )
				)
				( pin "b"
					( attribute "PN" "2"
						( Origin gPackager )
					)
					( objectStatus "C2D17.2" )
				)
			)
			( gate "@baseboard_fab2_lib.baseboard_fab2(sch_1):page76_i116"
				( attribute "BOM_COST" "PROC"
					( Origin gFrontEnd )
				)
				( attribute "CDS_LIB" "dev_discrete"
					( Origin gPackager )
				)
				( attribute "CDS_LOCATION" "C2D1"
					( Origin gPackager )
				)
				( attribute "CDS_SEC" "1"
					( Origin gPackager )
				)
				( attribute "LOCATION" "C2D1"
					( Origin gFrontEnd )
				)
				( attribute "MATERIAL" "X6S"
					( Origin gFrontEnd )
				)
				( attribute "PACK_TYPE" "0603V"
					( Origin gFrontEnd )
				)
				( attribute "PART_NUMBER" "E15431-004"
					( Origin gFrontEnd )
				)
				( attribute "PHYS_PAGE" "76"
					( Origin gFrontEnd )
				)
				( attribute "ROOM" "PVCCIN_CPU1_DECAP_VR"
					( Origin gFrontEnd )
				)
				( attribute "ROT" "0"
					( Origin gFrontEnd )
				)
				( attribute "SEC" "1"
					( Origin gPackager )
				)
				( attribute "TOLERANCE" "20%"
					( Origin gFrontEnd )
				)
				( attribute "VALUE" "22.0UF"
					( Origin gFrontEnd )
				)
				( attribute "VER" "1"
					( Origin gFrontEnd )
				)
				( attribute "VOLTAGE" "4V"
					( Units "uVoltage" "V" 1.000000)
					( Origin gFrontEnd )
				)
				( attribute "XY" "(-6950,3150)"
					( Origin gFrontEnd )
				)
				( attribute "CHIPS_PART_NAME" "CAP_A"
					( Origin gPackager )
				)
				( attribute "CDS_PART_NAME" "CAP_A_0603V-22.0UF,4V,20%,X6S,A"
					( Origin gPackager )
				)
				( objectStatus "C2D1" )
				( pin "a"
					( attribute "PN" "1"
						( Origin gPackager )
					)
					( objectStatus "C2D1.1" )
				)
				( pin "b"
					( attribute "PN" "2"
						( Origin gPackager )
					)
					( objectStatus "C2D1.2" )
				)
			)
			( gate "@baseboard_fab2_lib.baseboard_fab2(sch_1):page76_i118"
				( attribute "BOM_COST" "PROC"
					( Origin gFrontEnd )
				)
				( attribute "CDS_LIB" "mstr_discrete"
					( Origin gPackager )
				)
				( attribute "CDS_LOCATION" "C8P26"
					( Origin gPackager )
				)
				( attribute "CDS_SEC" "1"
					( Origin gPackager )
				)
				( attribute "LOCATION" "C8P26"
					( Origin gFrontEnd )
				)
				( attribute "MATERIAL" "X6S"
					( Origin gFrontEnd )
				)
				( attribute "PACK_TYPE" "0805"
					( Origin gFrontEnd )
				)
				( attribute "PART_NUMBER" "C95333-006"
					( Origin gFrontEnd )
				)
				( attribute "PHYS_PAGE" "76"
					( Origin gFrontEnd )
				)
				( attribute "ROOM" "PVCCIN_CPU1_DECAP_VR"
					( Origin gFrontEnd )
				)
				( attribute "ROT" "0"
					( Origin gFrontEnd )
				)
				( attribute "SEC" "1"
					( Origin gPackager )
				)
				( attribute "TOLERANCE" "20%"
					( Origin gFrontEnd )
				)
				( attribute "VALUE" "47UF"
					( Origin gFrontEnd )
				)
				( attribute "VER" "1"
					( Origin gFrontEnd )
				)
				( attribute "VOLTAGE" "4V"
					( Units "uVoltage" "V" 1.000000)
					( Origin gFrontEnd )
				)
				( attribute "XY" "(-7050,2200)"
					( Origin gFrontEnd )
				)
				( attribute "CHIPS_PART_NAME" "CAP"
					( Origin gPackager )
				)
				( attribute "CDS_PART_NAME" "CAP_0805-47UF,4V,20%,X6S,C9533A"
					( Origin gPackager )
				)
				( objectStatus "C8P26" )
				( pin "a"
					( attribute "PN" "1"
						( Origin gPackager )
					)
					( objectStatus "C8P26.1" )
				)
				( pin "b"
					( attribute "PN" "2"
						( Origin gPackager )
					)
					( objectStatus "C8P26.2" )
				)
			)
			( gate "@baseboard_fab2_lib.baseboard_fab2(sch_1):page76_i119"
				( attribute "BOM_COST" "PROC"
					( Origin gFrontEnd )
				)
				( attribute "CDS_LIB" "dev_discrete"
					( Origin gPackager )
				)
				( attribute "CDS_LOCATION" "C2D37"
					( Origin gPackager )
				)
				( attribute "CDS_SEC" "1"
					( Origin gPackager )
				)
				( attribute "LOCATION" "C2D37"
					( Origin gFrontEnd )
				)
				( attribute "MATERIAL" "X6S"
					( Origin gFrontEnd )
				)
				( attribute "PACK_TYPE" "0603V"
					( Origin gFrontEnd )
				)
				( attribute "PART_NUMBER" "E15431-004"
					( Origin gFrontEnd )
				)
				( attribute "PHYS_PAGE" "76"
					( Origin gFrontEnd )
				)
				( attribute "ROOM" "PVCCIN_CPU1_DECAP_VR"
					( Origin gFrontEnd )
				)
				( attribute "ROT" "0"
					( Origin gFrontEnd )
				)
				( attribute "SEC" "1"
					( Origin gPackager )
				)
				( attribute "TOLERANCE" "20%"
					( Origin gFrontEnd )
				)
				( attribute "VALUE" "22.0UF"
					( Origin gFrontEnd )
				)
				( attribute "VER" "1"
					( Origin gFrontEnd )
				)
				( attribute "VOLTAGE" "4V"
					( Units "uVoltage" "V" 1.000000)
					( Origin gFrontEnd )
				)
				( attribute "XY" "(-7325,3775)"
					( Origin gFrontEnd )
				)
				( attribute "CHIPS_PART_NAME" "CAP_A"
					( Origin gPackager )
				)
				( attribute "CDS_PART_NAME" "CAP_A_0603V-22.0UF,4V,20%,X6S,A"
					( Origin gPackager )
				)
				( objectStatus "C2D37" )
				( pin "a"
					( attribute "PN" "1"
						( Origin gPackager )
					)
					( objectStatus "C2D37.1" )
				)
				( pin "b"
					( attribute "PN" "2"
						( Origin gPackager )
					)
					( objectStatus "C2D37.2" )
				)
			)
			( gate "@baseboard_fab2_lib.baseboard_fab2(sch_1):page76_i122"
				( attribute "BOM_COST" "PROC"
					( Origin gFrontEnd )
				)
				( attribute "CDS_LIB" "dev_discrete"
					( Origin gPackager )
				)
				( attribute "CDS_LOCATION" "C2D34"
					( Origin gPackager )
				)
				( attribute "CDS_SEC" "1"
					( Origin gPackager )
				)
				( attribute "LOCATION" "C2D34"
					( Origin gFrontEnd )
				)
				( attribute "MATERIAL" "X6S"
					( Origin gFrontEnd )
				)
				( attribute "PACK_TYPE" "0603V"
					( Origin gFrontEnd )
				)
				( attribute "PART_NUMBER" "E15431-004"
					( Origin gFrontEnd )
				)
				( attribute "PHYS_PAGE" "76"
					( Origin gFrontEnd )
				)
				( attribute "ROOM" "PVCCIN_CPU1_DECAP_VR"
					( Origin gFrontEnd )
				)
				( attribute "ROT" "0"
					( Origin gFrontEnd )
				)
				( attribute "SEC" "1"
					( Origin gPackager )
				)
				( attribute "TOLERANCE" "20%"
					( Origin gFrontEnd )
				)
				( attribute "VALUE" "22.0UF"
					( Origin gFrontEnd )
				)
				( attribute "VER" "1"
					( Origin gFrontEnd )
				)
				( attribute "VOLTAGE" "4V"
					( Units "uVoltage" "V" 1.000000)
					( Origin gFrontEnd )
				)
				( attribute "XY" "(-7675,3775)"
					( Origin gFrontEnd )
				)
				( attribute "CHIPS_PART_NAME" "CAP_A"
					( Origin gPackager )
				)
				( attribute "CDS_PART_NAME" "CAP_A_0603V-22.0UF,4V,20%,X6S,A"
					( Origin gPackager )
				)
				( objectStatus "C2D34" )
				( pin "a"
					( attribute "PN" "1"
						( Origin gPackager )
					)
					( objectStatus "C2D34.1" )
				)
				( pin "b"
					( attribute "PN" "2"
						( Origin gPackager )
					)
					( objectStatus "C2D34.2" )
				)
			)
			( gate "@baseboard_fab2_lib.baseboard_fab2(sch_1):page76_i123"
				( attribute "BOM_COST" "PROC"
					( Origin gFrontEnd )
				)
				( attribute "CDS_LIB" "dev_discrete"
					( Origin gPackager )
				)
				( attribute "CDS_LOCATION" "C2D45"
					( Origin gPackager )
				)
				( attribute "CDS_SEC" "1"
					( Origin gPackager )
				)
				( attribute "LOCATION" "C2D45"
					( Origin gFrontEnd )
				)
				( attribute "MATERIAL" "X6S"
					( Origin gFrontEnd )
				)
				( attribute "PACK_TYPE" "0603V"
					( Origin gFrontEnd )
				)
				( attribute "PART_NUMBER" "E15431-004"
					( Origin gFrontEnd )
				)
				( attribute "PHYS_PAGE" "76"
					( Origin gFrontEnd )
				)
				( attribute "ROOM" "PVCCIN_CPU1_DECAP_VR"
					( Origin gFrontEnd )
				)
				( attribute "ROT" "0"
					( Origin gFrontEnd )
				)
				( attribute "SEC" "1"
					( Origin gPackager )
				)
				( attribute "TOLERANCE" "20%"
					( Origin gFrontEnd )
				)
				( attribute "VALUE" "22.0UF"
					( Origin gFrontEnd )
				)
				( attribute "VER" "1"
					( Origin gFrontEnd )
				)
				( attribute "VOLTAGE" "4V"
					( Units "uVoltage" "V" 1.000000)
					( Origin gFrontEnd )
				)
				( attribute "XY" "(-7275,3150)"
					( Origin gFrontEnd )
				)
				( attribute "CHIPS_PART_NAME" "CAP_A"
					( Origin gPackager )
				)
				( attribute "CDS_PART_NAME" "CAP_A_0603V-22.0UF,4V,20%,X6S,A"
					( Origin gPackager )
				)
				( objectStatus "C2D45" )
				( pin "a"
					( attribute "PN" "1"
						( Origin gPackager )
					)
					( objectStatus "C2D45.1" )
				)
				( pin "b"
					( attribute "PN" "2"
						( Origin gPackager )
					)
					( objectStatus "C2D45.2" )
				)
			)
			( gate "@baseboard_fab2_lib.baseboard_fab2(sch_1):page76_i124"
				( attribute "BOM_COST" "PROC"
					( Origin gFrontEnd )
				)
				( attribute "CDS_LIB" "dev_discrete"
					( Origin gPackager )
				)
				( attribute "CDS_LOCATION" "C2D16"
					( Origin gPackager )
				)
				( attribute "CDS_SEC" "1"
					( Origin gPackager )
				)
				( attribute "LOCATION" "C2D16"
					( Origin gFrontEnd )
				)
				( attribute "MATERIAL" "X6S"
					( Origin gFrontEnd )
				)
				( attribute "PACK_TYPE" "0603V"
					( Origin gFrontEnd )
				)
				( attribute "PART_NUMBER" "E15431-004"
					( Origin gFrontEnd )
				)
				( attribute "PHYS_PAGE" "76"
					( Origin gFrontEnd )
				)
				( attribute "ROOM" "PVCCIN_CPU1_DECAP_VR"
					( Origin gFrontEnd )
				)
				( attribute "ROT" "0"
					( Origin gFrontEnd )
				)
				( attribute "SEC" "1"
					( Origin gPackager )
				)
				( attribute "TOLERANCE" "20%"
					( Origin gFrontEnd )
				)
				( attribute "VALUE" "22.0UF"
					( Origin gFrontEnd )
				)
				( attribute "VER" "1"
					( Origin gFrontEnd )
				)
				( attribute "VOLTAGE" "4V"
					( Units "uVoltage" "V" 1.000000)
					( Origin gFrontEnd )
				)
				( attribute "XY" "(-7625,3150)"
					( Origin gFrontEnd )
				)
				( attribute "CHIPS_PART_NAME" "CAP_A"
					( Origin gPackager )
				)
				( attribute "CDS_PART_NAME" "CAP_A_0603V-22.0UF,4V,20%,X6S,A"
					( Origin gPackager )
				)
				( objectStatus "C2D16" )
				( pin "a"
					( attribute "PN" "1"
						( Origin gPackager )
					)
					( objectStatus "C2D16.1" )
				)
				( pin "b"
					( attribute "PN" "2"
						( Origin gPackager )
					)
					( objectStatus "C2D16.2" )
				)
			)
			( gate "@baseboard_fab2_lib.baseboard_fab2(sch_1):page76_i125"
				( attribute "BOM_COST" "PROC"
					( Origin gFrontEnd )
				)
				( attribute "CDS_LIB" "mstr_discrete"
					( Origin gPackager )
				)
				( attribute "CDS_LOCATION" "C8P29"
					( Origin gPackager )
				)
				( attribute "CDS_SEC" "1"
					( Origin gPackager )
				)
				( attribute "LOCATION" "C8P29"
					( Origin gFrontEnd )
				)
				( attribute "MATERIAL" "X6S"
					( Origin gFrontEnd )
				)
				( attribute "PACK_TYPE" "0805"
					( Origin gFrontEnd )
				)
				( attribute "PART_NUMBER" "C95333-006"
					( Origin gFrontEnd )
				)
				( attribute "PHYS_PAGE" "76"
					( Origin gFrontEnd )
				)
				( attribute "ROOM" "PVCCIN_CPU1_DECAP_VR"
					( Origin gFrontEnd )
				)
				( attribute "ROT" "0"
					( Origin gFrontEnd )
				)
				( attribute "SEC" "1"
					( Origin gPackager )
				)
				( attribute "TOLERANCE" "20%"
					( Origin gFrontEnd )
				)
				( attribute "VALUE" "47UF"
					( Origin gFrontEnd )
				)
				( attribute "VER" "1"
					( Origin gFrontEnd )
				)
				( attribute "VOLTAGE" "4V"
					( Units "uVoltage" "V" 1.000000)
					( Origin gFrontEnd )
				)
				( attribute "XY" "(-7375,2200)"
					( Origin gFrontEnd )
				)
				( attribute "CHIPS_PART_NAME" "CAP"
					( Origin gPackager )
				)
				( attribute "CDS_PART_NAME" "CAP_0805-47UF,4V,20%,X6S,C9533A"
					( Origin gPackager )
				)
				( objectStatus "C8P29" )
				( pin "a"
					( attribute "PN" "1"
						( Origin gPackager )
					)
					( objectStatus "C8P29.1" )
				)
				( pin "b"
					( attribute "PN" "2"
						( Origin gPackager )
					)
					( objectStatus "C8P29.2" )
				)
			)
			( gate "@baseboard_fab2_lib.baseboard_fab2(sch_1):page76_i127"
				( attribute "BOM_COST" "PROC"
					( Origin gFrontEnd )
				)
				( attribute "CDS_LIB" "mstr_discrete"
					( Origin gPackager )
				)
				( attribute "CDS_LOCATION" "C8P10"
					( Origin gPackager )
				)
				( attribute "CDS_SEC" "1"
					( Origin gPackager )
				)
				( attribute "LOCATION" "C8P10"
					( Origin gFrontEnd )
				)
				( attribute "MATERIAL" "X6S"
					( Origin gFrontEnd )
				)
				( attribute "PACK_TYPE" "0805"
					( Origin gFrontEnd )
				)
				( attribute "PART_NUMBER" "C95333-006"
					( Origin gFrontEnd )
				)
				( attribute "PHYS_PAGE" "76"
					( Origin gFrontEnd )
				)
				( attribute "ROOM" "PVCCIN_CPU1_DECAP_VR"
					( Origin gFrontEnd )
				)
				( attribute "ROT" "0"
					( Origin gFrontEnd )
				)
				( attribute "SEC" "1"
					( Origin gPackager )
				)
				( attribute "TOLERANCE" "20%"
					( Origin gFrontEnd )
				)
				( attribute "VALUE" "47UF"
					( Origin gFrontEnd )
				)
				( attribute "VER" "1"
					( Origin gFrontEnd )
				)
				( attribute "VOLTAGE" "4V"
					( Units "uVoltage" "V" 1.000000)
					( Origin gFrontEnd )
				)
				( attribute "XY" "(-7725,2200)"
					( Origin gFrontEnd )
				)
				( attribute "CHIPS_PART_NAME" "CAP"
					( Origin gPackager )
				)
				( attribute "CDS_PART_NAME" "CAP_0805-47UF,4V,20%,X6S,C9533A"
					( Origin gPackager )
				)
				( objectStatus "C8P10" )
				( pin "a"
					( attribute "PN" "1"
						( Origin gPackager )
					)
					( objectStatus "C8P10.1" )
				)
				( pin "b"
					( attribute "PN" "2"
						( Origin gPackager )
					)
					( objectStatus "C8P10.2" )
				)
			)
			( gate "@baseboard_fab2_lib.baseboard_fab2(sch_1):page76_i129"
				( attribute "BOM_COST" "PROC"
					( Origin gFrontEnd )
				)
				( attribute "CDS_LIB" "mstr_discrete"
					( Origin gPackager )
				)
				( attribute "CDS_LOCATION" "C8P16"
					( Origin gPackager )
				)
				( attribute "CDS_SEC" "1"
					( Origin gPackager )
				)
				( attribute "LOCATION" "C8P16"
					( Origin gFrontEnd )
				)
				( attribute "MATERIAL" "X6S"
					( Origin gFrontEnd )
				)
				( attribute "PACK_TYPE" "0805"
					( Origin gFrontEnd )
				)
				( attribute "PART_NUMBER" "C95333-006"
					( Origin gFrontEnd )
				)
				( attribute "PHYS_PAGE" "76"
					( Origin gFrontEnd )
				)
				( attribute "ROOM" "PVCCIN_CPU1_DECAP_VR"
					( Origin gFrontEnd )
				)
				( attribute "ROT" "0"
					( Origin gFrontEnd )
				)
				( attribute "SEC" "1"
					( Origin gPackager )
				)
				( attribute "TOLERANCE" "20%"
					( Origin gFrontEnd )
				)
				( attribute "VALUE" "47UF"
					( Origin gFrontEnd )
				)
				( attribute "VER" "1"
					( Origin gFrontEnd )
				)
				( attribute "VOLTAGE" "4V"
					( Units "uVoltage" "V" 1.000000)
					( Origin gFrontEnd )
				)
				( attribute "XY" "(-6350,1550)"
					( Origin gFrontEnd )
				)
				( attribute "CHIPS_PART_NAME" "CAP"
					( Origin gPackager )
				)
				( attribute "CDS_PART_NAME" "CAP_0805-47UF,4V,20%,X6S,C9533A"
					( Origin gPackager )
				)
				( objectStatus "C8P16" )
				( pin "a"
					( attribute "PN" "1"
						( Origin gPackager )
					)
					( objectStatus "C8P16.1" )
				)
				( pin "b"
					( attribute "PN" "2"
						( Origin gPackager )
					)
					( objectStatus "C8P16.2" )
				)
			)
			( gate "@baseboard_fab2_lib.baseboard_fab2(sch_1):page76_i131"
				( attribute "BOM_COST" "PROC"
					( Origin gFrontEnd )
				)
				( attribute "CDS_LIB" "mstr_discrete"
					( Origin gPackager )
				)
				( attribute "CDS_LOCATION" "C8P33"
					( Origin gPackager )
				)
				( attribute "CDS_SEC" "1"
					( Origin gPackager )
				)
				( attribute "LOCATION" "C8P33"
					( Origin gFrontEnd )
				)
				( attribute "MATERIAL" "X6S"
					( Origin gFrontEnd )
				)
				( attribute "PACK_TYPE" "0805"
					( Origin gFrontEnd )
				)
				( attribute "PART_NUMBER" "C95333-006"
					( Origin gFrontEnd )
				)
				( attribute "PHYS_PAGE" "76"
					( Origin gFrontEnd )
				)
				( attribute "ROOM" "PVCCIN_CPU1_DECAP_VR"
					( Origin gFrontEnd )
				)
				( attribute "ROT" "0"
					( Origin gFrontEnd )
				)
				( attribute "SEC" "1"
					( Origin gPackager )
				)
				( attribute "TOLERANCE" "20%"
					( Origin gFrontEnd )
				)
				( attribute "VALUE" "47UF"
					( Origin gFrontEnd )
				)
				( attribute "VER" "1"
					( Origin gFrontEnd )
				)
				( attribute "VOLTAGE" "4V"
					( Units "uVoltage" "V" 1.000000)
					( Origin gFrontEnd )
				)
				( attribute "XY" "(-6700,1550)"
					( Origin gFrontEnd )
				)
				( attribute "CHIPS_PART_NAME" "CAP"
					( Origin gPackager )
				)
				( attribute "CDS_PART_NAME" "CAP_0805-47UF,4V,20%,X6S,C9533A"
					( Origin gPackager )
				)
				( objectStatus "C8P33" )
				( pin "a"
					( attribute "PN" "1"
						( Origin gPackager )
					)
					( objectStatus "C8P33.1" )
				)
				( pin "b"
					( attribute "PN" "2"
						( Origin gPackager )
					)
					( objectStatus "C8P33.2" )
				)
			)
			( gate "@baseboard_fab2_lib.baseboard_fab2(sch_1):page76_i132"
				( attribute "BOM_COST" "PROC"
					( Origin gFrontEnd )
				)
				( attribute "CDS_LIB" "mstr_discrete"
					( Origin gPackager )
				)
				( attribute "CDS_LOCATION" "C8P13"
					( Origin gPackager )
				)
				( attribute "CDS_SEC" "1"
					( Origin gPackager )
				)
				( attribute "LOCATION" "C8P13"
					( Origin gFrontEnd )
				)
				( attribute "MATERIAL" "X6S"
					( Origin gFrontEnd )
				)
				( attribute "PACK_TYPE" "0805"
					( Origin gFrontEnd )
				)
				( attribute "PART_NUMBER" "C95333-006"
					( Origin gFrontEnd )
				)
				( attribute "PHYS_PAGE" "76"
					( Origin gFrontEnd )
				)
				( attribute "ROOM" "PVCCIN_CPU1_DECAP_VR"
					( Origin gFrontEnd )
				)
				( attribute "ROT" "0"
					( Origin gFrontEnd )
				)
				( attribute "SEC" "1"
					( Origin gPackager )
				)
				( attribute "TOLERANCE" "20%"
					( Origin gFrontEnd )
				)
				( attribute "VALUE" "47UF"
					( Origin gFrontEnd )
				)
				( attribute "VER" "1"
					( Origin gFrontEnd )
				)
				( attribute "VOLTAGE" "4V"
					( Units "uVoltage" "V" 1.000000)
					( Origin gFrontEnd )
				)
				( attribute "XY" "(-7050,1550)"
					( Origin gFrontEnd )
				)
				( attribute "CHIPS_PART_NAME" "CAP"
					( Origin gPackager )
				)
				( attribute "CDS_PART_NAME" "CAP_0805-47UF,4V,20%,X6S,C9533A"
					( Origin gPackager )
				)
				( objectStatus "C8P13" )
				( pin "a"
					( attribute "PN" "1"
						( Origin gPackager )
					)
					( objectStatus "C8P13.1" )
				)
				( pin "b"
					( attribute "PN" "2"
						( Origin gPackager )
					)
					( objectStatus "C8P13.2" )
				)
			)
			( gate "@baseboard_fab2_lib.baseboard_fab2(sch_1):page76_i133"
				( attribute "BOM_COST" "PROC"
					( Origin gFrontEnd )
				)
				( attribute "CDS_LIB" "mstr_discrete"
					( Origin gPackager )
				)
				( attribute "CDS_LOCATION" "C8P17"
					( Origin gPackager )
				)
				( attribute "CDS_SEC" "1"
					( Origin gPackager )
				)
				( attribute "LOCATION" "C8P17"
					( Origin gFrontEnd )
				)
				( attribute "MATERIAL" "X6S"
					( Origin gFrontEnd )
				)
				( attribute "PACK_TYPE" "0805"
					( Origin gFrontEnd )
				)
				( attribute "PART_NUMBER" "C95333-006"
					( Origin gFrontEnd )
				)
				( attribute "PHYS_PAGE" "76"
					( Origin gFrontEnd )
				)
				( attribute "ROOM" "PVCCIN_CPU1_DECAP_VR"
					( Origin gFrontEnd )
				)
				( attribute "ROT" "0"
					( Origin gFrontEnd )
				)
				( attribute "SEC" "1"
					( Origin gPackager )
				)
				( attribute "TOLERANCE" "20%"
					( Origin gFrontEnd )
				)
				( attribute "VALUE" "47UF"
					( Origin gFrontEnd )
				)
				( attribute "VER" "1"
					( Origin gFrontEnd )
				)
				( attribute "VOLTAGE" "4V"
					( Units "uVoltage" "V" 1.000000)
					( Origin gFrontEnd )
				)
				( attribute "XY" "(-6350,900)"
					( Origin gFrontEnd )
				)
				( attribute "CHIPS_PART_NAME" "CAP"
					( Origin gPackager )
				)
				( attribute "CDS_PART_NAME" "CAP_0805-47UF,4V,20%,X6S,C9533A"
					( Origin gPackager )
				)
				( objectStatus "C8P17" )
				( pin "a"
					( attribute "PN" "1"
						( Origin gPackager )
					)
					( objectStatus "C8P17.1" )
				)
				( pin "b"
					( attribute "PN" "2"
						( Origin gPackager )
					)
					( objectStatus "C8P17.2" )
				)
			)
			( gate "@baseboard_fab2_lib.baseboard_fab2(sch_1):page76_i135"
				( attribute "BOM_COST" "PROC"
					( Origin gFrontEnd )
				)
				( attribute "CDS_LIB" "mstr_discrete"
					( Origin gPackager )
				)
				( attribute "CDS_LOCATION" "C8P21"
					( Origin gPackager )
				)
				( attribute "CDS_SEC" "1"
					( Origin gPackager )
				)
				( attribute "LOCATION" "C8P21"
					( Origin gFrontEnd )
				)
				( attribute "MATERIAL" "X6S"
					( Origin gFrontEnd )
				)
				( attribute "PACK_TYPE" "0805"
					( Origin gFrontEnd )
				)
				( attribute "PART_NUMBER" "C95333-006"
					( Origin gFrontEnd )
				)
				( attribute "PHYS_PAGE" "76"
					( Origin gFrontEnd )
				)
				( attribute "ROOM" "PVCCIN_CPU1_DECAP_VR"
					( Origin gFrontEnd )
				)
				( attribute "ROT" "0"
					( Origin gFrontEnd )
				)
				( attribute "SEC" "1"
					( Origin gPackager )
				)
				( attribute "TOLERANCE" "20%"
					( Origin gFrontEnd )
				)
				( attribute "VALUE" "47UF"
					( Origin gFrontEnd )
				)
				( attribute "VER" "1"
					( Origin gFrontEnd )
				)
				( attribute "VOLTAGE" "4V"
					( Units "uVoltage" "V" 1.000000)
					( Origin gFrontEnd )
				)
				( attribute "XY" "(-6700,900)"
					( Origin gFrontEnd )
				)
				( attribute "CHIPS_PART_NAME" "CAP"
					( Origin gPackager )
				)
				( attribute "CDS_PART_NAME" "CAP_0805-47UF,4V,20%,X6S,C9533A"
					( Origin gPackager )
				)
				( objectStatus "C8P21" )
				( pin "a"
					( attribute "PN" "1"
						( Origin gPackager )
					)
					( objectStatus "C8P21.1" )
				)
				( pin "b"
					( attribute "PN" "2"
						( Origin gPackager )
					)
					( objectStatus "C8P21.2" )
				)
			)
			( gate "@baseboard_fab2_lib.baseboard_fab2(sch_1):page76_i136"
				( attribute "BOM_COST" "PROC"
					( Origin gFrontEnd )
				)
				( attribute "CDS_LIB" "mstr_discrete"
					( Origin gPackager )
				)
				( attribute "CDS_LOCATION" "C8P25"
					( Origin gPackager )
				)
				( attribute "CDS_SEC" "1"
					( Origin gPackager )
				)
				( attribute "LOCATION" "C8P25"
					( Origin gFrontEnd )
				)
				( attribute "MATERIAL" "X6S"
					( Origin gFrontEnd )
				)
				( attribute "PACK_TYPE" "0805"
					( Origin gFrontEnd )
				)
				( attribute "PART_NUMBER" "C95333-006"
					( Origin gFrontEnd )
				)
				( attribute "PHYS_PAGE" "76"
					( Origin gFrontEnd )
				)
				( attribute "ROOM" "PVCCIN_CPU1_DECAP_VR"
					( Origin gFrontEnd )
				)
				( attribute "ROT" "0"
					( Origin gFrontEnd )
				)
				( attribute "SEC" "1"
					( Origin gPackager )
				)
				( attribute "TOLERANCE" "20%"
					( Origin gFrontEnd )
				)
				( attribute "VALUE" "47UF"
					( Origin gFrontEnd )
				)
				( attribute "VER" "1"
					( Origin gFrontEnd )
				)
				( attribute "VOLTAGE" "4V"
					( Units "uVoltage" "V" 1.000000)
					( Origin gFrontEnd )
				)
				( attribute "XY" "(-7050,900)"
					( Origin gFrontEnd )
				)
				( attribute "CHIPS_PART_NAME" "CAP"
					( Origin gPackager )
				)
				( attribute "CDS_PART_NAME" "CAP_0805-47UF,4V,20%,X6S,C9533A"
					( Origin gPackager )
				)
				( objectStatus "C8P25" )
				( pin "a"
					( attribute "PN" "1"
						( Origin gPackager )
					)
					( objectStatus "C8P25.1" )
				)
				( pin "b"
					( attribute "PN" "2"
						( Origin gPackager )
					)
					( objectStatus "C8P25.2" )
				)
			)
			( gate "@baseboard_fab2_lib.baseboard_fab2(sch_1):page76_i137"
				( attribute "BOM_COST" "PROC"
					( Origin gFrontEnd )
				)
				( attribute "CDS_LIB" "mstr_discrete"
					( Origin gPackager )
				)
				( attribute "CDS_LOCATION" "C8P28"
					( Origin gPackager )
				)
				( attribute "CDS_SEC" "1"
					( Origin gPackager )
				)
				( attribute "LOCATION" "C8P28"
					( Origin gFrontEnd )
				)
				( attribute "MATERIAL" "X6S"
					( Origin gFrontEnd )
				)
				( attribute "PACK_TYPE" "0805"
					( Origin gFrontEnd )
				)
				( attribute "PART_NUMBER" "C95333-006"
					( Origin gFrontEnd )
				)
				( attribute "PHYS_PAGE" "76"
					( Origin gFrontEnd )
				)
				( attribute "ROOM" "PVCCIN_CPU1_DECAP_VR"
					( Origin gFrontEnd )
				)
				( attribute "ROT" "0"
					( Origin gFrontEnd )
				)
				( attribute "SEC" "1"
					( Origin gPackager )
				)
				( attribute "TOLERANCE" "20%"
					( Origin gFrontEnd )
				)
				( attribute "VALUE" "47UF"
					( Origin gFrontEnd )
				)
				( attribute "VER" "1"
					( Origin gFrontEnd )
				)
				( attribute "VOLTAGE" "4V"
					( Units "uVoltage" "V" 1.000000)
					( Origin gFrontEnd )
				)
				( attribute "XY" "(-7375,1550)"
					( Origin gFrontEnd )
				)
				( attribute "CHIPS_PART_NAME" "CAP"
					( Origin gPackager )
				)
				( attribute "CDS_PART_NAME" "CAP_0805-47UF,4V,20%,X6S,C9533A"
					( Origin gPackager )
				)
				( objectStatus "C8P28" )
				( pin "a"
					( attribute "PN" "1"
						( Origin gPackager )
					)
					( objectStatus "C8P28.1" )
				)
				( pin "b"
					( attribute "PN" "2"
						( Origin gPackager )
					)
					( objectStatus "C8P28.2" )
				)
			)
			( gate "@baseboard_fab2_lib.baseboard_fab2(sch_1):page76_i139"
				( attribute "BOM_COST" "PROC"
					( Origin gFrontEnd )
				)
				( attribute "CDS_LIB" "mstr_discrete"
					( Origin gPackager )
				)
				( attribute "CDS_LOCATION" "C8P11"
					( Origin gPackager )
				)
				( attribute "CDS_SEC" "1"
					( Origin gPackager )
				)
				( attribute "LOCATION" "C8P11"
					( Origin gFrontEnd )
				)
				( attribute "MATERIAL" "X6S"
					( Origin gFrontEnd )
				)
				( attribute "PACK_TYPE" "0805"
					( Origin gFrontEnd )
				)
				( attribute "PART_NUMBER" "C95333-006"
					( Origin gFrontEnd )
				)
				( attribute "PHYS_PAGE" "76"
					( Origin gFrontEnd )
				)
				( attribute "ROOM" "PVCCIN_CPU1_DECAP_VR"
					( Origin gFrontEnd )
				)
				( attribute "ROT" "0"
					( Origin gFrontEnd )
				)
				( attribute "SEC" "1"
					( Origin gPackager )
				)
				( attribute "TOLERANCE" "20%"
					( Origin gFrontEnd )
				)
				( attribute "VALUE" "47UF"
					( Origin gFrontEnd )
				)
				( attribute "VER" "1"
					( Origin gFrontEnd )
				)
				( attribute "VOLTAGE" "4V"
					( Units "uVoltage" "V" 1.000000)
					( Origin gFrontEnd )
				)
				( attribute "XY" "(-7725,1550)"
					( Origin gFrontEnd )
				)
				( attribute "CHIPS_PART_NAME" "CAP"
					( Origin gPackager )
				)
				( attribute "CDS_PART_NAME" "CAP_0805-47UF,4V,20%,X6S,C9533A"
					( Origin gPackager )
				)
				( objectStatus "C8P11" )
				( pin "a"
					( attribute "PN" "1"
						( Origin gPackager )
					)
					( objectStatus "C8P11.1" )
				)
				( pin "b"
					( attribute "PN" "2"
						( Origin gPackager )
					)
					( objectStatus "C8P11.2" )
				)
			)
			( gate "@baseboard_fab2_lib.baseboard_fab2(sch_1):page76_i141"
				( attribute "BOM_COST" "PROC"
					( Origin gFrontEnd )
				)
				( attribute "CDS_LIB" "mstr_discrete"
					( Origin gPackager )
				)
				( attribute "CDS_LOCATION" "C8P27"
					( Origin gPackager )
				)
				( attribute "CDS_SEC" "1"
					( Origin gPackager )
				)
				( attribute "LOCATION" "C8P27"
					( Origin gFrontEnd )
				)
				( attribute "MATERIAL" "X6S"
					( Origin gFrontEnd )
				)
				( attribute "PACK_TYPE" "0805"
					( Origin gFrontEnd )
				)
				( attribute "PART_NUMBER" "C95333-006"
					( Origin gFrontEnd )
				)
				( attribute "PHYS_PAGE" "76"
					( Origin gFrontEnd )
				)
				( attribute "ROOM" "PVCCIN_CPU1_DECAP_VR"
					( Origin gFrontEnd )
				)
				( attribute "ROT" "0"
					( Origin gFrontEnd )
				)
				( attribute "SEC" "1"
					( Origin gPackager )
				)
				( attribute "TOLERANCE" "20%"
					( Origin gFrontEnd )
				)
				( attribute "VALUE" "47UF"
					( Origin gFrontEnd )
				)
				( attribute "VER" "1"
					( Origin gFrontEnd )
				)
				( attribute "VOLTAGE" "4V"
					( Units "uVoltage" "V" 1.000000)
					( Origin gFrontEnd )
				)
				( attribute "XY" "(-7375,900)"
					( Origin gFrontEnd )
				)
				( attribute "CHIPS_PART_NAME" "CAP"
					( Origin gPackager )
				)
				( attribute "CDS_PART_NAME" "CAP_0805-47UF,4V,20%,X6S,C9533A"
					( Origin gPackager )
				)
				( objectStatus "C8P27" )
				( pin "a"
					( attribute "PN" "1"
						( Origin gPackager )
					)
					( objectStatus "C8P27.1" )
				)
				( pin "b"
					( attribute "PN" "2"
						( Origin gPackager )
					)
					( objectStatus "C8P27.2" )
				)
			)
			( gate "@baseboard_fab2_lib.baseboard_fab2(sch_1):page76_i159"
				( attribute "BOM_COST" "PROC"
					( Origin gFrontEnd )
				)
				( attribute "CDS_LIB" "dev_discrete"
					( Origin gPackager )
				)
				( attribute "CDS_LOCATION" "C2D15"
					( Origin gPackager )
				)
				( attribute "CDS_SEC" "1"
					( Origin gPackager )
				)
				( attribute "LOCATION" "C2D15"
					( Origin gFrontEnd )
				)
				( attribute "MATERIAL" "X6S"
					( Origin gFrontEnd )
				)
				( attribute "PACK_TYPE" "0603V"
					( Origin gFrontEnd )
				)
				( attribute "PART_NUMBER" "E15431-004"
					( Origin gFrontEnd )
				)
				( attribute "PHYS_PAGE" "76"
					( Origin gFrontEnd )
				)
				( attribute "ROOM" "PVCCIN_CPU1_DECAP_VR"
					( Origin gFrontEnd )
				)
				( attribute "ROT" "0"
					( Origin gFrontEnd )
				)
				( attribute "SEC" "1"
					( Origin gPackager )
				)
				( attribute "TOLERANCE" "20%"
					( Origin gFrontEnd )
				)
				( attribute "VALUE" "22.0UF"
					( Origin gFrontEnd )
				)
				( attribute "VER" "1"
					( Origin gFrontEnd )
				)
				( attribute "VOLTAGE" "4V"
					( Units "uVoltage" "V" 1.000000)
					( Origin gFrontEnd )
				)
				( attribute "XY" "(-4325,4425)"
					( Origin gFrontEnd )
				)
				( attribute "CHIPS_PART_NAME" "CAP_A"
					( Origin gPackager )
				)
				( attribute "CDS_PART_NAME" "CAP_A_0603V-22.0UF,4V,20%,X6S,A"
					( Origin gPackager )
				)
				( objectStatus "C2D15" )
				( pin "a"
					( attribute "PN" "1"
						( Origin gPackager )
					)
					( objectStatus "C2D15.1" )
				)
				( pin "b"
					( attribute "PN" "2"
						( Origin gPackager )
					)
					( objectStatus "C2D15.2" )
				)
			)
			( gate "@baseboard_fab2_lib.baseboard_fab2(sch_1):page76_i160"
				( attribute "BOM_COST" "PROC"
					( Origin gFrontEnd )
				)
				( attribute "CDS_LIB" "dev_discrete"
					( Origin gPackager )
				)
				( attribute "CDS_LOCATION" "C2D38"
					( Origin gPackager )
				)
				( attribute "CDS_SEC" "1"
					( Origin gPackager )
				)
				( attribute "LOCATION" "C2D38"
					( Origin gFrontEnd )
				)
				( attribute "MATERIAL" "X6S"
					( Origin gFrontEnd )
				)
				( attribute "PACK_TYPE" "0603V"
					( Origin gFrontEnd )
				)
				( attribute "PART_NUMBER" "E15431-004"
					( Origin gFrontEnd )
				)
				( attribute "PHYS_PAGE" "76"
					( Origin gFrontEnd )
				)
				( attribute "ROOM" "PVCCIN_CPU1_DECAP_VR"
					( Origin gFrontEnd )
				)
				( attribute "ROT" "0"
					( Origin gFrontEnd )
				)
				( attribute "SEC" "1"
					( Origin gPackager )
				)
				( attribute "TOLERANCE" "20%"
					( Origin gFrontEnd )
				)
				( attribute "VALUE" "22.0UF"
					( Origin gFrontEnd )
				)
				( attribute "VER" "1"
					( Origin gFrontEnd )
				)
				( attribute "VOLTAGE" "4V"
					( Units "uVoltage" "V" 1.000000)
					( Origin gFrontEnd )
				)
				( attribute "XY" "(-4325,3750)"
					( Origin gFrontEnd )
				)
				( attribute "CHIPS_PART_NAME" "CAP_A"
					( Origin gPackager )
				)
				( attribute "CDS_PART_NAME" "CAP_A_0603V-22.0UF,4V,20%,X6S,A"
					( Origin gPackager )
				)
				( objectStatus "C2D38" )
				( pin "a"
					( attribute "PN" "1"
						( Origin gPackager )
					)
					( objectStatus "C2D38.1" )
				)
				( pin "b"
					( attribute "PN" "2"
						( Origin gPackager )
					)
					( objectStatus "C2D38.2" )
				)
			)
			( gate "@baseboard_fab2_lib.baseboard_fab2(sch_1):page76_i161"
				( attribute "BOM_COST" "PROC"
					( Origin gFrontEnd )
				)
				( attribute "CDS_LIB" "dev_discrete"
					( Origin gPackager )
				)
				( attribute "CDS_LOCATION" "C2D35"
					( Origin gPackager )
				)
				( attribute "CDS_SEC" "1"
					( Origin gPackager )
				)
				( attribute "LOCATION" "C2D35"
					( Origin gFrontEnd )
				)
				( attribute "MATERIAL" "X6S"
					( Origin gFrontEnd )
				)
				( attribute "PACK_TYPE" "0603V"
					( Origin gFrontEnd )
				)
				( attribute "PART_NUMBER" "E15431-004"
					( Origin gFrontEnd )
				)
				( attribute "PHYS_PAGE" "76"
					( Origin gFrontEnd )
				)
				( attribute "ROOM" "PVCCIN_CPU1_DECAP_VR"
					( Origin gFrontEnd )
				)
				( attribute "ROT" "0"
					( Origin gFrontEnd )
				)
				( attribute "SEC" "1"
					( Origin gPackager )
				)
				( attribute "TOLERANCE" "20%"
					( Origin gFrontEnd )
				)
				( attribute "VALUE" "22.0UF"
					( Origin gFrontEnd )
				)
				( attribute "VER" "1"
					( Origin gFrontEnd )
				)
				( attribute "VOLTAGE" "4V"
					( Units "uVoltage" "V" 1.000000)
					( Origin gFrontEnd )
				)
				( attribute "XY" "(-4325,3150)"
					( Origin gFrontEnd )
				)
				( attribute "CHIPS_PART_NAME" "CAP_A"
					( Origin gPackager )
				)
				( attribute "CDS_PART_NAME" "CAP_A_0603V-22.0UF,4V,20%,X6S,A"
					( Origin gPackager )
				)
				( objectStatus "C2D35" )
				( pin "a"
					( attribute "PN" "1"
						( Origin gPackager )
					)
					( objectStatus "C2D35.1" )
				)
				( pin "b"
					( attribute "PN" "2"
						( Origin gPackager )
					)
					( objectStatus "C2D35.2" )
				)
			)
			( gate "@baseboard_fab2_lib.baseboard_fab2(sch_1):page76_i164"
				( attribute "CDS_LIB" "dev_discrete"
					( Origin gPackager )
				)
				( attribute "CDS_LOCATION" "C3D7"
					( Origin gPackager )
				)
				( attribute "CDS_SEC" "1"
					( Origin gPackager )
				)
				( attribute "LOCATION" "C3D7"
					( Origin gFrontEnd )
				)
				( attribute "MATERIAL" "X6S"
					( Origin gFrontEnd )
				)
				( attribute "PACK_TYPE" "0603V"
					( Origin gFrontEnd )
				)
				( attribute "PART_NUMBER" "E15431-004"
					( Origin gFrontEnd )
				)
				( attribute "PHYS_PAGE" "76"
					( Origin gFrontEnd )
				)
				( attribute "ROOM" "PVCCIN_CPU1_DECAP_VR"
					( Origin gFrontEnd )
				)
				( attribute "ROT" "0"
					( Origin gFrontEnd )
				)
				( attribute "SEC" "1"
					( Origin gPackager )
				)
				( attribute "TOLERANCE" "20%"
					( Origin gFrontEnd )
				)
				( attribute "VALUE" "22.0UF"
					( Origin gFrontEnd )
				)
				( attribute "VER" "1"
					( Origin gFrontEnd )
				)
				( attribute "VOLTAGE" "4V"
					( Units "uVoltage" "V" 1.000000)
					( Origin gFrontEnd )
				)
				( attribute "XY" "(-4000,4450)"
					( Origin gFrontEnd )
				)
				( attribute "CHIPS_PART_NAME" "CAP_A"
					( Origin gPackager )
				)
				( attribute "CDS_PART_NAME" "CAP_A_0603V-22.0UF,4V,20%,X6S,A"
					( Origin gPackager )
				)
				( objectStatus "C3D7" )
				( pin "a"
					( attribute "PN" "1"
						( Origin gPackager )
					)
					( objectStatus "C3D7.1" )
				)
				( pin "b"
					( attribute "PN" "2"
						( Origin gPackager )
					)
					( objectStatus "C3D7.2" )
				)
			)
			( gate "@baseboard_fab2_lib.baseboard_fab2(sch_1):page76_i165"
				( attribute "BOM_COST" "PROC"
					( Origin gFrontEnd )
				)
				( attribute "CDS_LIB" "dev_discrete"
					( Origin gPackager )
				)
				( attribute "CDS_LOCATION" "C2D39"
					( Origin gPackager )
				)
				( attribute "CDS_SEC" "1"
					( Origin gPackager )
				)
				( attribute "LOCATION" "C2D39"
					( Origin gFrontEnd )
				)
				( attribute "MATERIAL" "X6S"
					( Origin gFrontEnd )
				)
				( attribute "PACK_TYPE" "0603V"
					( Origin gFrontEnd )
				)
				( attribute "PART_NUMBER" "E15431-004"
					( Origin gFrontEnd )
				)
				( attribute "PHYS_PAGE" "76"
					( Origin gFrontEnd )
				)
				( attribute "ROOM" "PVCCIN_CPU1_DECAP_VR"
					( Origin gFrontEnd )
				)
				( attribute "ROT" "0"
					( Origin gFrontEnd )
				)
				( attribute "SEC" "1"
					( Origin gPackager )
				)
				( attribute "TOLERANCE" "20%"
					( Origin gFrontEnd )
				)
				( attribute "VALUE" "22.0UF"
					( Origin gFrontEnd )
				)
				( attribute "VER" "1"
					( Origin gFrontEnd )
				)
				( attribute "VOLTAGE" "4V"
					( Units "uVoltage" "V" 1.000000)
					( Origin gFrontEnd )
				)
				( attribute "XY" "(-3750,4450)"
					( Origin gFrontEnd )
				)
				( attribute "CHIPS_PART_NAME" "CAP_A"
					( Origin gPackager )
				)
				( attribute "CDS_PART_NAME" "CAP_A_0603V-22.0UF,4V,20%,X6S,A"
					( Origin gPackager )
				)
				( objectStatus "C2D39" )
				( pin "a"
					( attribute "PN" "1"
						( Origin gPackager )
					)
					( objectStatus "C2D39.1" )
				)
				( pin "b"
					( attribute "PN" "2"
						( Origin gPackager )
					)
					( objectStatus "C2D39.2" )
				)
			)
			( gate "@baseboard_fab2_lib.baseboard_fab2(sch_1):page76_i166"
				( attribute "BOM_COST" "PROC"
					( Origin gFrontEnd )
				)
				( attribute "CDS_LIB" "dev_discrete"
					( Origin gPackager )
				)
				( attribute "CDS_LOCATION" "C3D17"
					( Origin gPackager )
				)
				( attribute "CDS_SEC" "1"
					( Origin gPackager )
				)
				( attribute "LOCATION" "C3D17"
					( Origin gFrontEnd )
				)
				( attribute "MATERIAL" "X6S"
					( Origin gFrontEnd )
				)
				( attribute "PACK_TYPE" "0603V"
					( Origin gFrontEnd )
				)
				( attribute "PART_NUMBER" "E15431-004"
					( Origin gFrontEnd )
				)
				( attribute "PHYS_PAGE" "76"
					( Origin gFrontEnd )
				)
				( attribute "ROOM" "PVCCIN_CPU1_DECAP_VR"
					( Origin gFrontEnd )
				)
				( attribute "ROT" "0"
					( Origin gFrontEnd )
				)
				( attribute "SEC" "1"
					( Origin gPackager )
				)
				( attribute "TOLERANCE" "20%"
					( Origin gFrontEnd )
				)
				( attribute "VALUE" "22.0UF"
					( Origin gFrontEnd )
				)
				( attribute "VER" "1"
					( Origin gFrontEnd )
				)
				( attribute "VOLTAGE" "4V"
					( Units "uVoltage" "V" 1.000000)
					( Origin gFrontEnd )
				)
				( attribute "XY" "(-3500,4450)"
					( Origin gFrontEnd )
				)
				( attribute "CHIPS_PART_NAME" "CAP_A"
					( Origin gPackager )
				)
				( attribute "CDS_PART_NAME" "CAP_A_0603V-22.0UF,4V,20%,X6S,A"
					( Origin gPackager )
				)
				( objectStatus "C3D17" )
				( pin "a"
					( attribute "PN" "1"
						( Origin gPackager )
					)
					( objectStatus "C3D17.1" )
				)
				( pin "b"
					( attribute "PN" "2"
						( Origin gPackager )
					)
					( objectStatus "C3D17.2" )
				)
			)
			( gate "@baseboard_fab2_lib.baseboard_fab2(sch_1):page76_i169"
				( attribute "BOM_COST" "PROC"
					( Origin gFrontEnd )
				)
				( attribute "CDS_LIB" "dev_discrete"
					( Origin gPackager )
				)
				( attribute "CDS_LOCATION" "C3D18"
					( Origin gPackager )
				)
				( attribute "CDS_SEC" "1"
					( Origin gPackager )
				)
				( attribute "LOCATION" "C3D18"
					( Origin gFrontEnd )
				)
				( attribute "MATERIAL" "X6S"
					( Origin gFrontEnd )
				)
				( attribute "PACK_TYPE" "0603V"
					( Origin gFrontEnd )
				)
				( attribute "PART_NUMBER" "E15431-004"
					( Origin gFrontEnd )
				)
				( attribute "PHYS_PAGE" "76"
					( Origin gFrontEnd )
				)
				( attribute "ROOM" "PVCCIN_CPU1_DECAP_VR"
					( Origin gFrontEnd )
				)
				( attribute "ROT" "0"
					( Origin gFrontEnd )
				)
				( attribute "SEC" "1"
					( Origin gPackager )
				)
				( attribute "TOLERANCE" "20%"
					( Origin gFrontEnd )
				)
				( attribute "VALUE" "22.0UF"
					( Origin gFrontEnd )
				)
				( attribute "VER" "1"
					( Origin gFrontEnd )
				)
				( attribute "VOLTAGE" "4V"
					( Units "uVoltage" "V" 1.000000)
					( Origin gFrontEnd )
				)
				( attribute "XY" "(-975,4450)"
					( Origin gFrontEnd )
				)
				( attribute "CHIPS_PART_NAME" "CAP_A"
					( Origin gPackager )
				)
				( attribute "CDS_PART_NAME" "CAP_A_0603V-22.0UF,4V,20%,X6S,A"
					( Origin gPackager )
				)
				( objectStatus "C3D18" )
				( pin "a"
					( attribute "PN" "1"
						( Origin gPackager )
					)
					( objectStatus "C3D18.1" )
				)
				( pin "b"
					( attribute "PN" "2"
						( Origin gPackager )
					)
					( objectStatus "C3D18.2" )
				)
			)
			( gate "@baseboard_fab2_lib.baseboard_fab2(sch_1):page76_i170"
				( attribute "BOM_COST" "PROC"
					( Origin gFrontEnd )
				)
				( attribute "CDS_LIB" "dev_discrete"
					( Origin gPackager )
				)
				( attribute "CDS_LOCATION" "C3D6"
					( Origin gPackager )
				)
				( attribute "CDS_SEC" "1"
					( Origin gPackager )
				)
				( attribute "LOCATION" "C3D6"
					( Origin gFrontEnd )
				)
				( attribute "MATERIAL" "X6S"
					( Origin gFrontEnd )
				)
				( attribute "PACK_TYPE" "0603V"
					( Origin gFrontEnd )
				)
				( attribute "PART_NUMBER" "E15431-004"
					( Origin gFrontEnd )
				)
				( attribute "PHYS_PAGE" "76"
					( Origin gFrontEnd )
				)
				( attribute "ROOM" "PVCCIN_CPU1_DECAP_VR"
					( Origin gFrontEnd )
				)
				( attribute "ROT" "0"
					( Origin gFrontEnd )
				)
				( attribute "SEC" "1"
					( Origin gPackager )
				)
				( attribute "TOLERANCE" "20%"
					( Origin gFrontEnd )
				)
				( attribute "VALUE" "22.0UF"
					( Origin gFrontEnd )
				)
				( attribute "VER" "1"
					( Origin gFrontEnd )
				)
				( attribute "VOLTAGE" "4V"
					( Units "uVoltage" "V" 1.000000)
					( Origin gFrontEnd )
				)
				( attribute "XY" "(-725,4450)"
					( Origin gFrontEnd )
				)
				( attribute "CHIPS_PART_NAME" "CAP_A"
					( Origin gPackager )
				)
				( attribute "CDS_PART_NAME" "CAP_A_0603V-22.0UF,4V,20%,X6S,A"
					( Origin gPackager )
				)
				( objectStatus "C3D6" )
				( pin "a"
					( attribute "PN" "1"
						( Origin gPackager )
					)
					( objectStatus "C3D6.1" )
				)
				( pin "b"
					( attribute "PN" "2"
						( Origin gPackager )
					)
					( objectStatus "C3D6.2" )
				)
			)
			( gate "@baseboard_fab2_lib.baseboard_fab2(sch_1):page76_i171"
				( attribute "BOM_COST" "PROC"
					( Origin gFrontEnd )
				)
				( attribute "CDS_LIB" "dev_discrete"
					( Origin gPackager )
				)
				( attribute "CDS_LOCATION" "C3D14"
					( Origin gPackager )
				)
				( attribute "CDS_SEC" "1"
					( Origin gPackager )
				)
				( attribute "LOCATION" "C3D14"
					( Origin gFrontEnd )
				)
				( attribute "MATERIAL" "X6S"
					( Origin gFrontEnd )
				)
				( attribute "PACK_TYPE" "0603V"
					( Origin gFrontEnd )
				)
				( attribute "PART_NUMBER" "E15431-004"
					( Origin gFrontEnd )
				)
				( attribute "PHYS_PAGE" "76"
					( Origin gFrontEnd )
				)
				( attribute "ROOM" "PVCCIN_CPU1_DECAP_VR"
					( Origin gFrontEnd )
				)
				( attribute "ROT" "0"
					( Origin gFrontEnd )
				)
				( attribute "SEC" "1"
					( Origin gPackager )
				)
				( attribute "TOLERANCE" "20%"
					( Origin gFrontEnd )
				)
				( attribute "VALUE" "22.0UF"
					( Origin gFrontEnd )
				)
				( attribute "VER" "1"
					( Origin gFrontEnd )
				)
				( attribute "VOLTAGE" "4V"
					( Units "uVoltage" "V" 1.000000)
					( Origin gFrontEnd )
				)
				( attribute "XY" "(-2725,4450)"
					( Origin gFrontEnd )
				)
				( attribute "CHIPS_PART_NAME" "CAP_A"
					( Origin gPackager )
				)
				( attribute "CDS_PART_NAME" "CAP_A_0603V-22.0UF,4V,20%,X6S,A"
					( Origin gPackager )
				)
				( objectStatus "C3D14" )
				( pin "a"
					( attribute "PN" "1"
						( Origin gPackager )
					)
					( objectStatus "C3D14.1" )
				)
				( pin "b"
					( attribute "PN" "2"
						( Origin gPackager )
					)
					( objectStatus "C3D14.2" )
				)
			)
			( gate "@baseboard_fab2_lib.baseboard_fab2(sch_1):page76_i172"
				( attribute "BOM_COST" "PROC"
					( Origin gFrontEnd )
				)
				( attribute "CDS_LIB" "dev_discrete"
					( Origin gPackager )
				)
				( attribute "CDS_LOCATION" "C3D23"
					( Origin gPackager )
				)
				( attribute "CDS_SEC" "1"
					( Origin gPackager )
				)
				( attribute "LOCATION" "C3D23"
					( Origin gFrontEnd )
				)
				( attribute "MATERIAL" "X6S"
					( Origin gFrontEnd )
				)
				( attribute "PACK_TYPE" "0603V"
					( Origin gFrontEnd )
				)
				( attribute "PART_NUMBER" "E15431-004"
					( Origin gFrontEnd )
				)
				( attribute "PHYS_PAGE" "76"
					( Origin gFrontEnd )
				)
				( attribute "ROOM" "PVCCIN_CPU1_DECAP_VR"
					( Origin gFrontEnd )
				)
				( attribute "ROT" "0"
					( Origin gFrontEnd )
				)
				( attribute "SEC" "1"
					( Origin gPackager )
				)
				( attribute "TOLERANCE" "20%"
					( Origin gFrontEnd )
				)
				( attribute "VALUE" "22.0UF"
					( Origin gFrontEnd )
				)
				( attribute "VER" "1"
					( Origin gFrontEnd )
				)
				( attribute "VOLTAGE" "4V"
					( Units "uVoltage" "V" 1.000000)
					( Origin gFrontEnd )
				)
				( attribute "XY" "(-3975,3750)"
					( Origin gFrontEnd )
				)
				( attribute "CHIPS_PART_NAME" "CAP_A"
					( Origin gPackager )
				)
				( attribute "CDS_PART_NAME" "CAP_A_0603V-22.0UF,4V,20%,X6S,A"
					( Origin gPackager )
				)
				( objectStatus "C3D23" )
				( pin "a"
					( attribute "PN" "1"
						( Origin gPackager )
					)
					( objectStatus "C3D23.1" )
				)
				( pin "b"
					( attribute "PN" "2"
						( Origin gPackager )
					)
					( objectStatus "C3D23.2" )
				)
			)
			( gate "@baseboard_fab2_lib.baseboard_fab2(sch_1):page76_i174"
				( attribute "BOM_COST" "PROC"
					( Origin gFrontEnd )
				)
				( attribute "CDS_LIB" "dev_discrete"
					( Origin gPackager )
				)
				( attribute "CDS_LOCATION" "C3D15"
					( Origin gPackager )
				)
				( attribute "CDS_SEC" "1"
					( Origin gPackager )
				)
				( attribute "LOCATION" "C3D15"
					( Origin gFrontEnd )
				)
				( attribute "MATERIAL" "X6S"
					( Origin gFrontEnd )
				)
				( attribute "PACK_TYPE" "0603V"
					( Origin gFrontEnd )
				)
				( attribute "PART_NUMBER" "E15431-004"
					( Origin gFrontEnd )
				)
				( attribute "PHYS_PAGE" "76"
					( Origin gFrontEnd )
				)
				( attribute "ROOM" "PVCCIN_CPU1_DECAP_VR"
					( Origin gFrontEnd )
				)
				( attribute "ROT" "0"
					( Origin gFrontEnd )
				)
				( attribute "SEC" "1"
					( Origin gPackager )
				)
				( attribute "TOLERANCE" "20%"
					( Origin gFrontEnd )
				)
				( attribute "VALUE" "22.0UF"
					( Origin gFrontEnd )
				)
				( attribute "VER" "1"
					( Origin gFrontEnd )
				)
				( attribute "VOLTAGE" "4V"
					( Units "uVoltage" "V" 1.000000)
					( Origin gFrontEnd )
				)
				( attribute "XY" "(-3675,3750)"
					( Origin gFrontEnd )
				)
				( attribute "CHIPS_PART_NAME" "CAP_A"
					( Origin gPackager )
				)
				( attribute "CDS_PART_NAME" "CAP_A_0603V-22.0UF,4V,20%,X6S,A"
					( Origin gPackager )
				)
				( objectStatus "C3D15" )
				( pin "a"
					( attribute "PN" "1"
						( Origin gPackager )
					)
					( objectStatus "C3D15.1" )
				)
				( pin "b"
					( attribute "PN" "2"
						( Origin gPackager )
					)
					( objectStatus "C3D15.2" )
				)
			)
			( gate "@baseboard_fab2_lib.baseboard_fab2(sch_1):page76_i175"
				( attribute "BOM_COST" "PROC"
					( Origin gFrontEnd )
				)
				( attribute "CDS_LIB" "dev_discrete"
					( Origin gPackager )
				)
				( attribute "CDS_LOCATION" "C3D24"
					( Origin gPackager )
				)
				( attribute "CDS_SEC" "1"
					( Origin gPackager )
				)
				( attribute "LOCATION" "C3D24"
					( Origin gFrontEnd )
				)
				( attribute "MATERIAL" "X6S"
					( Origin gFrontEnd )
				)
				( attribute "PACK_TYPE" "0603V"
					( Origin gFrontEnd )
				)
				( attribute "PART_NUMBER" "E15431-004"
					( Origin gFrontEnd )
				)
				( attribute "PHYS_PAGE" "76"
					( Origin gFrontEnd )
				)
				( attribute "ROOM" "PVCCIN_CPU1_DECAP_VR"
					( Origin gFrontEnd )
				)
				( attribute "ROT" "0"
					( Origin gFrontEnd )
				)
				( attribute "SEC" "1"
					( Origin gPackager )
				)
				( attribute "TOLERANCE" "20%"
					( Origin gFrontEnd )
				)
				( attribute "VALUE" "22.0UF"
					( Origin gFrontEnd )
				)
				( attribute "VER" "1"
					( Origin gFrontEnd )
				)
				( attribute "VOLTAGE" "4V"
					( Units "uVoltage" "V" 1.000000)
					( Origin gFrontEnd )
				)
				( attribute "XY" "(-3350,3775)"
					( Origin gFrontEnd )
				)
				( attribute "CHIPS_PART_NAME" "CAP_A"
					( Origin gPackager )
				)
				( attribute "CDS_PART_NAME" "CAP_A_0603V-22.0UF,4V,20%,X6S,A"
					( Origin gPackager )
				)
				( objectStatus "C3D24" )
				( pin "a"
					( attribute "PN" "1"
						( Origin gPackager )
					)
					( objectStatus "C3D24.1" )
				)
				( pin "b"
					( attribute "PN" "2"
						( Origin gPackager )
					)
					( objectStatus "C3D24.2" )
				)
			)
			( gate "@baseboard_fab2_lib.baseboard_fab2(sch_1):page76_i176"
				( attribute "BOM_COST" "PROC"
					( Origin gFrontEnd )
				)
				( attribute "CDS_LIB" "dev_discrete"
					( Origin gPackager )
				)
				( attribute "CDS_LOCATION" "C3D16"
					( Origin gPackager )
				)
				( attribute "CDS_SEC" "1"
					( Origin gPackager )
				)
				( attribute "LOCATION" "C3D16"
					( Origin gFrontEnd )
				)
				( attribute "MATERIAL" "X6S"
					( Origin gFrontEnd )
				)
				( attribute "PACK_TYPE" "0603V"
					( Origin gFrontEnd )
				)
				( attribute "PART_NUMBER" "E15431-004"
					( Origin gFrontEnd )
				)
				( attribute "PHYS_PAGE" "76"
					( Origin gFrontEnd )
				)
				( attribute "ROOM" "PVCCIN_CPU1_DECAP_VR"
					( Origin gFrontEnd )
				)
				( attribute "ROT" "0"
					( Origin gFrontEnd )
				)
				( attribute "SEC" "1"
					( Origin gPackager )
				)
				( attribute "TOLERANCE" "20%"
					( Origin gFrontEnd )
				)
				( attribute "VALUE" "22.0UF"
					( Origin gFrontEnd )
				)
				( attribute "VER" "1"
					( Origin gFrontEnd )
				)
				( attribute "VOLTAGE" "4V"
					( Units "uVoltage" "V" 1.000000)
					( Origin gFrontEnd )
				)
				( attribute "XY" "(-3050,3775)"
					( Origin gFrontEnd )
				)
				( attribute "CHIPS_PART_NAME" "CAP_A"
					( Origin gPackager )
				)
				( attribute "CDS_PART_NAME" "CAP_A_0603V-22.0UF,4V,20%,X6S,A"
					( Origin gPackager )
				)
				( objectStatus "C3D16" )
				( pin "a"
					( attribute "PN" "1"
						( Origin gPackager )
					)
					( objectStatus "C3D16.1" )
				)
				( pin "b"
					( attribute "PN" "2"
						( Origin gPackager )
					)
					( objectStatus "C3D16.2" )
				)
			)
			( gate "@baseboard_fab2_lib.baseboard_fab2(sch_1):page76_i179"
				( attribute "BOM_COST" "PROC"
					( Origin gFrontEnd )
				)
				( attribute "CDS_LIB" "dev_discrete"
					( Origin gPackager )
				)
				( attribute "CDS_LOCATION" "C7P12"
					( Origin gPackager )
				)
				( attribute "CDS_SEC" "1"
					( Origin gPackager )
				)
				( attribute "LOCATION" "C7P12"
					( Origin gFrontEnd )
				)
				( attribute "MATERIAL" "X6S"
					( Origin gFrontEnd )
				)
				( attribute "PACK_TYPE" "0603V"
					( Origin gFrontEnd )
				)
				( attribute "PART_NUMBER" "E15431-004"
					( Origin gFrontEnd )
				)
				( attribute "PHYS_PAGE" "76"
					( Origin gFrontEnd )
				)
				( attribute "ROOM" "PVCCIN_CPU1_DECAP_VR"
					( Origin gFrontEnd )
				)
				( attribute "ROT" "0"
					( Origin gFrontEnd )
				)
				( attribute "SEC" "1"
					( Origin gPackager )
				)
				( attribute "TOLERANCE" "20%"
					( Origin gFrontEnd )
				)
				( attribute "VALUE" "22.0UF"
					( Origin gFrontEnd )
				)
				( attribute "VER" "1"
					( Origin gFrontEnd )
				)
				( attribute "VOLTAGE" "4V"
					( Units "uVoltage" "V" 1.000000)
					( Origin gFrontEnd )
				)
				( attribute "XY" "(-2375,925)"
					( Origin gFrontEnd )
				)
				( attribute "CHIPS_PART_NAME" "CAP_A"
					( Origin gPackager )
				)
				( attribute "CDS_PART_NAME" "CAP_A_0603V-22.0UF,4V,20%,X6S,A"
					( Origin gPackager )
				)
				( objectStatus "C7P12" )
				( pin "a"
					( attribute "PN" "1"
						( Origin gPackager )
					)
					( objectStatus "C7P12.1" )
				)
				( pin "b"
					( attribute "PN" "2"
						( Origin gPackager )
					)
					( objectStatus "C7P12.2" )
				)
			)
			( gate "@baseboard_fab2_lib.baseboard_fab2(sch_1):page76_i181"
				( attribute "BOM_COST" "PROC"
					( Origin gFrontEnd )
				)
				( attribute "CDS_LIB" "mstr_discrete"
					( Origin gPackager )
				)
				( attribute "CDS_LOCATION" "C7P9"
					( Origin gPackager )
				)
				( attribute "CDS_SEC" "1"
					( Origin gPackager )
				)
				( attribute "LOCATION" "C7P9"
					( Origin gFrontEnd )
				)
				( attribute "MATERIAL" "X6S"
					( Origin gFrontEnd )
				)
				( attribute "PACK_TYPE" "0805"
					( Origin gFrontEnd )
				)
				( attribute "PART_NUMBER" "C95333-006"
					( Origin gFrontEnd )
				)
				( attribute "PHYS_PAGE" "76"
					( Origin gFrontEnd )
				)
				( attribute "ROOM" "PVCCIN_CPU1_DECAP_VR"
					( Origin gFrontEnd )
				)
				( attribute "ROT" "0"
					( Origin gFrontEnd )
				)
				( attribute "SEC" "1"
					( Origin gFrontEnd )
				)
				( attribute "SEC_TYPE" "0805"
					( Origin gFrontEnd )
				)
				( attribute "TOLERANCE" "20%"
					( Origin gFrontEnd )
				)
				( attribute "VALUE" "47UF"
					( Origin gFrontEnd )
				)
				( attribute "VER" "1"
					( Origin gFrontEnd )
				)
				( attribute "VOLTAGE" "4V"
					( Units "uVoltage" "V" 1.000000)
					( Origin gFrontEnd )
				)
				( attribute "XY" "(-4775,2150)"
					( Origin gFrontEnd )
				)
				( attribute "CHIPS_PART_NAME" "CAP"
					( Origin gPackager )
				)
				( attribute "CDS_PART_NAME" "CAP_0805-47UF,4V,20%,X6S,C9533A"
					( Origin gPackager )
				)
				( objectStatus "C7P9" )
				( pin "a"
					( attribute "PN" "1"
						( Origin gPackager )
					)
					( objectStatus "C7P9.1" )
				)
				( pin "b"
					( attribute "PN" "2"
						( Origin gPackager )
					)
					( objectStatus "C7P9.2" )
				)
			)
			( gate "@baseboard_fab2_lib.baseboard_fab2(sch_1):page76_i182"
				( attribute "BOM_COST" "PROC"
					( Origin gFrontEnd )
				)
				( attribute "CDS_LIB" "mstr_discrete"
					( Origin gPackager )
				)
				( attribute "CDS_LOCATION" "C7P5"
					( Origin gPackager )
				)
				( attribute "CDS_SEC" "1"
					( Origin gPackager )
				)
				( attribute "LOCATION" "C7P5"
					( Origin gFrontEnd )
				)
				( attribute "MATERIAL" "X6S"
					( Origin gFrontEnd )
				)
				( attribute "PACK_TYPE" "0805"
					( Origin gFrontEnd )
				)
				( attribute "PART_NUMBER" "C95333-006"
					( Origin gFrontEnd )
				)
				( attribute "PHYS_PAGE" "76"
					( Origin gFrontEnd )
				)
				( attribute "ROOM" "PVCCIN_CPU1_DECAP_VR"
					( Origin gFrontEnd )
				)
				( attribute "ROT" "0"
					( Origin gFrontEnd )
				)
				( attribute "SEC" "1"
					( Origin gPackager )
				)
				( attribute "TOLERANCE" "20%"
					( Origin gFrontEnd )
				)
				( attribute "VALUE" "47UF"
					( Origin gFrontEnd )
				)
				( attribute "VER" "1"
					( Origin gFrontEnd )
				)
				( attribute "VOLTAGE" "4V"
					( Units "uVoltage" "V" 1.000000)
					( Origin gFrontEnd )
				)
				( attribute "XY" "(-4525,2150)"
					( Origin gFrontEnd )
				)
				( attribute "CHIPS_PART_NAME" "CAP"
					( Origin gPackager )
				)
				( attribute "CDS_PART_NAME" "CAP_0805-47UF,4V,20%,X6S,C9533A"
					( Origin gPackager )
				)
				( objectStatus "C7P5" )
				( pin "a"
					( attribute "PN" "1"
						( Origin gPackager )
					)
					( objectStatus "C7P5.1" )
				)
				( pin "b"
					( attribute "PN" "2"
						( Origin gPackager )
					)
					( objectStatus "C7P5.2" )
				)
			)
			( gate "@baseboard_fab2_lib.baseboard_fab2(sch_1):page76_i183"
				( attribute "BOM_COST" "PROC"
					( Origin gFrontEnd )
				)
				( attribute "CDS_LIB" "mstr_discrete"
					( Origin gPackager )
				)
				( attribute "CDS_LOCATION" "C7P11"
					( Origin gPackager )
				)
				( attribute "CDS_SEC" "1"
					( Origin gPackager )
				)
				( attribute "LOCATION" "C7P11"
					( Origin gFrontEnd )
				)
				( attribute "MATERIAL" "X6S"
					( Origin gFrontEnd )
				)
				( attribute "PACK_TYPE" "0805"
					( Origin gFrontEnd )
				)
				( attribute "PART_NUMBER" "C95333-006"
					( Origin gFrontEnd )
				)
				( attribute "PHYS_PAGE" "76"
					( Origin gFrontEnd )
				)
				( attribute "ROOM" "PVCCIN_CPU1_DECAP_VR"
					( Origin gFrontEnd )
				)
				( attribute "ROT" "0"
					( Origin gFrontEnd )
				)
				( attribute "SEC" "1"
					( Origin gPackager )
				)
				( attribute "TOLERANCE" "20%"
					( Origin gFrontEnd )
				)
				( attribute "VALUE" "47UF"
					( Origin gFrontEnd )
				)
				( attribute "VER" "1"
					( Origin gFrontEnd )
				)
				( attribute "VOLTAGE" "4V"
					( Units "uVoltage" "V" 1.000000)
					( Origin gFrontEnd )
				)
				( attribute "XY" "(-3425,2150)"
					( Origin gFrontEnd )
				)
				( attribute "CHIPS_PART_NAME" "CAP"
					( Origin gPackager )
				)
				( attribute "CDS_PART_NAME" "CAP_0805-47UF,4V,20%,X6S,C9533A"
					( Origin gPackager )
				)
				( objectStatus "C7P11" )
				( pin "a"
					( attribute "PN" "1"
						( Origin gPackager )
					)
					( objectStatus "C7P11.1" )
				)
				( pin "b"
					( attribute "PN" "2"
						( Origin gPackager )
					)
					( objectStatus "C7P11.2" )
				)
			)
			( gate "@baseboard_fab2_lib.baseboard_fab2(sch_1):page76_i184"
				( attribute "BOM_COST" "PROC"
					( Origin gFrontEnd )
				)
				( attribute "CDS_LIB" "mstr_discrete"
					( Origin gPackager )
				)
				( attribute "CDS_LOCATION" "C7P8"
					( Origin gPackager )
				)
				( attribute "CDS_SEC" "1"
					( Origin gPackager )
				)
				( attribute "LOCATION" "C7P8"
					( Origin gFrontEnd )
				)
				( attribute "MATERIAL" "X6S"
					( Origin gFrontEnd )
				)
				( attribute "PACK_TYPE" "0805"
					( Origin gFrontEnd )
				)
				( attribute "PART_NUMBER" "C95333-006"
					( Origin gFrontEnd )
				)
				( attribute "PHYS_PAGE" "76"
					( Origin gFrontEnd )
				)
				( attribute "ROOM" "PVCCIN_CPU1_DECAP_VR"
					( Origin gFrontEnd )
				)
				( attribute "ROT" "0"
					( Origin gFrontEnd )
				)
				( attribute "SEC" "1"
					( Origin gPackager )
				)
				( attribute "TOLERANCE" "20%"
					( Origin gFrontEnd )
				)
				( attribute "VALUE" "47UF"
					( Origin gFrontEnd )
				)
				( attribute "VER" "1"
					( Origin gFrontEnd )
				)
				( attribute "VOLTAGE" "4V"
					( Units "uVoltage" "V" 1.000000)
					( Origin gFrontEnd )
				)
				( attribute "XY" "(-3175,2150)"
					( Origin gFrontEnd )
				)
				( attribute "CHIPS_PART_NAME" "CAP"
					( Origin gPackager )
				)
				( attribute "CDS_PART_NAME" "CAP_0805-47UF,4V,20%,X6S,C9533A"
					( Origin gPackager )
				)
				( objectStatus "C7P8" )
				( pin "a"
					( attribute "PN" "1"
						( Origin gPackager )
					)
					( objectStatus "C7P8.1" )
				)
				( pin "b"
					( attribute "PN" "2"
						( Origin gPackager )
					)
					( objectStatus "C7P8.2" )
				)
			)
			( gate "@baseboard_fab2_lib.baseboard_fab2(sch_1):page76_i195"
				( attribute "BOM_COST" "PROC"
					( Origin gFrontEnd )
				)
				( attribute "CDS_LIB" "mstr_discrete"
					( Origin gPackager )
				)
				( attribute "CDS_LOCATION" "C7P4"
					( Origin gPackager )
				)
				( attribute "CDS_SEC" "1"
					( Origin gPackager )
				)
				( attribute "LOCATION" "C7P4"
					( Origin gFrontEnd )
				)
				( attribute "MATERIAL" "X6S"
					( Origin gFrontEnd )
				)
				( attribute "PACK_TYPE" "0805"
					( Origin gFrontEnd )
				)
				( attribute "PART_NUMBER" "C95333-006"
					( Origin gFrontEnd )
				)
				( attribute "PHYS_PAGE" "76"
					( Origin gFrontEnd )
				)
				( attribute "ROOM" "PVCCIN_CPU1_DECAP_VR"
					( Origin gFrontEnd )
				)
				( attribute "ROT" "0"
					( Origin gFrontEnd )
				)
				( attribute "SEC" "1"
					( Origin gPackager )
				)
				( attribute "TOLERANCE" "20%"
					( Origin gFrontEnd )
				)
				( attribute "VALUE" "47UF"
					( Origin gFrontEnd )
				)
				( attribute "VER" "1"
					( Origin gFrontEnd )
				)
				( attribute "VOLTAGE" "4V"
					( Units "uVoltage" "V" 1.000000)
					( Origin gFrontEnd )
				)
				( attribute "XY" "(-1450,2125)"
					( Origin gFrontEnd )
				)
				( attribute "CHIPS_PART_NAME" "CAP"
					( Origin gPackager )
				)
				( attribute "CDS_PART_NAME" "CAP_0805-47UF,4V,20%,X6S,C9533A"
					( Origin gPackager )
				)
				( objectStatus "C7P4" )
				( pin "a"
					( attribute "PN" "1"
						( Origin gPackager )
					)
					( objectStatus "C7P4.1" )
				)
				( pin "b"
					( attribute "PN" "2"
						( Origin gPackager )
					)
					( objectStatus "C7P4.2" )
				)
			)
			( gate "@baseboard_fab2_lib.baseboard_fab2(sch_1):page76_i196"
				( attribute "BOM_COST" "PROC"
					( Origin gFrontEnd )
				)
				( attribute "CDS_LIB" "dev_discrete"
					( Origin gPackager )
				)
				( attribute "CDS_LOCATION" "C3D10"
					( Origin gPackager )
				)
				( attribute "CDS_SEC" "1"
					( Origin gPackager )
				)
				( attribute "LOCATION" "C3D10"
					( Origin gFrontEnd )
				)
				( attribute "MATERIAL" "X6S"
					( Origin gFrontEnd )
				)
				( attribute "PACK_TYPE" "0603V"
					( Origin gFrontEnd )
				)
				( attribute "PART_NUMBER" "E15431-004"
					( Origin gFrontEnd )
				)
				( attribute "PHYS_PAGE" "76"
					( Origin gFrontEnd )
				)
				( attribute "ROOM" "PVCCIN_CPU1_DECAP_VR"
					( Origin gFrontEnd )
				)
				( attribute "ROT" "0"
					( Origin gFrontEnd )
				)
				( attribute "SEC" "1"
					( Origin gPackager )
				)
				( attribute "TOLERANCE" "20%"
					( Origin gFrontEnd )
				)
				( attribute "VALUE" "22.0UF"
					( Origin gFrontEnd )
				)
				( attribute "VER" "1"
					( Origin gFrontEnd )
				)
				( attribute "VOLTAGE" "4V"
					( Units "uVoltage" "V" 1.000000)
					( Origin gFrontEnd )
				)
				( attribute "XY" "(-1950,3725)"
					( Origin gFrontEnd )
				)
				( attribute "CHIPS_PART_NAME" "CAP_A"
					( Origin gPackager )
				)
				( attribute "CDS_PART_NAME" "CAP_A_0603V-22.0UF,4V,20%,X6S,A"
					( Origin gPackager )
				)
				( objectStatus "C3D10" )
				( pin "a"
					( attribute "PN" "1"
						( Origin gPackager )
					)
					( objectStatus "C3D10.1" )
				)
				( pin "b"
					( attribute "PN" "2"
						( Origin gPackager )
					)
					( objectStatus "C3D10.2" )
				)
			)
			( gate "@baseboard_fab2_lib.baseboard_fab2(sch_1):page76_i197"
				( attribute "BOM_COST" "PROC"
					( Origin gFrontEnd )
				)
				( attribute "CDS_LIB" "dev_discrete"
					( Origin gPackager )
				)
				( attribute "CDS_LOCATION" "C2D18"
					( Origin gPackager )
				)
				( attribute "CDS_SEC" "1"
					( Origin gPackager )
				)
				( attribute "LOCATION" "C2D18"
					( Origin gFrontEnd )
				)
				( attribute "MATERIAL" "X6S"
					( Origin gFrontEnd )
				)
				( attribute "PACK_TYPE" "0603V"
					( Origin gFrontEnd )
				)
				( attribute "PART_NUMBER" "E15431-004"
					( Origin gFrontEnd )
				)
				( attribute "PHYS_PAGE" "76"
					( Origin gFrontEnd )
				)
				( attribute "ROOM" "PVCCIN_CPU1_DECAP_VR"
					( Origin gFrontEnd )
				)
				( attribute "ROT" "0"
					( Origin gFrontEnd )
				)
				( attribute "SEC" "1"
					( Origin gPackager )
				)
				( attribute "TOLERANCE" "20%"
					( Origin gFrontEnd )
				)
				( attribute "VALUE" "22.0UF"
					( Origin gFrontEnd )
				)
				( attribute "VER" "1"
					( Origin gFrontEnd )
				)
				( attribute "VOLTAGE" "4V"
					( Units "uVoltage" "V" 1.000000)
					( Origin gFrontEnd )
				)
				( attribute "XY" "(-1700,3725)"
					( Origin gFrontEnd )
				)
				( attribute "CHIPS_PART_NAME" "CAP_A"
					( Origin gPackager )
				)
				( attribute "CDS_PART_NAME" "CAP_A_0603V-22.0UF,4V,20%,X6S,A"
					( Origin gPackager )
				)
				( objectStatus "C2D18" )
				( pin "a"
					( attribute "PN" "1"
						( Origin gPackager )
					)
					( objectStatus "C2D18.1" )
				)
				( pin "b"
					( attribute "PN" "2"
						( Origin gPackager )
					)
					( objectStatus "C2D18.2" )
				)
			)
			( gate "@baseboard_fab2_lib.baseboard_fab2(sch_1):page76_i198"
				( attribute "BOM_COST" "PROC"
					( Origin gFrontEnd )
				)
				( attribute "CDS_LIB" "dev_discrete"
					( Origin gPackager )
				)
				( attribute "CDS_LOCATION" "C2D28"
					( Origin gPackager )
				)
				( attribute "CDS_SEC" "1"
					( Origin gPackager )
				)
				( attribute "LOCATION" "C2D28"
					( Origin gFrontEnd )
				)
				( attribute "MATERIAL" "X6S"
					( Origin gFrontEnd )
				)
				( attribute "PACK_TYPE" "0603V"
					( Origin gFrontEnd )
				)
				( attribute "PART_NUMBER" "E15431-004"
					( Origin gFrontEnd )
				)
				( attribute "PHYS_PAGE" "76"
					( Origin gFrontEnd )
				)
				( attribute "ROOM" "PVCCIN_CPU1_DECAP_VR"
					( Origin gFrontEnd )
				)
				( attribute "ROT" "0"
					( Origin gFrontEnd )
				)
				( attribute "SEC" "1"
					( Origin gPackager )
				)
				( attribute "TOLERANCE" "20%"
					( Origin gFrontEnd )
				)
				( attribute "VALUE" "22.0UF"
					( Origin gFrontEnd )
				)
				( attribute "VER" "1"
					( Origin gFrontEnd )
				)
				( attribute "VOLTAGE" "4V"
					( Units "uVoltage" "V" 1.000000)
					( Origin gFrontEnd )
				)
				( attribute "XY" "(-1450,3725)"
					( Origin gFrontEnd )
				)
				( attribute "CHIPS_PART_NAME" "CAP_A"
					( Origin gPackager )
				)
				( attribute "CDS_PART_NAME" "CAP_A_0603V-22.0UF,4V,20%,X6S,A"
					( Origin gPackager )
				)
				( objectStatus "C2D28" )
				( pin "a"
					( attribute "PN" "1"
						( Origin gPackager )
					)
					( objectStatus "C2D28.1" )
				)
				( pin "b"
					( attribute "PN" "2"
						( Origin gPackager )
					)
					( objectStatus "C2D28.2" )
				)
			)
			( gate "@baseboard_fab2_lib.baseboard_fab2(sch_1):page76_i199"
				( attribute "BOM_COST" "PROC"
					( Origin gFrontEnd )
				)
				( attribute "CDS_LIB" "dev_discrete"
					( Origin gPackager )
				)
				( attribute "CDS_LOCATION" "C2D29"
					( Origin gPackager )
				)
				( attribute "CDS_SEC" "1"
					( Origin gPackager )
				)
				( attribute "LOCATION" "C2D29"
					( Origin gFrontEnd )
				)
				( attribute "MATERIAL" "X6S"
					( Origin gFrontEnd )
				)
				( attribute "PACK_TYPE" "0603V"
					( Origin gFrontEnd )
				)
				( attribute "PART_NUMBER" "E15431-004"
					( Origin gFrontEnd )
				)
				( attribute "PHYS_PAGE" "76"
					( Origin gFrontEnd )
				)
				( attribute "ROOM" "PVCCIN_CPU1_DECAP_VR"
					( Origin gFrontEnd )
				)
				( attribute "ROT" "0"
					( Origin gFrontEnd )
				)
				( attribute "SEC" "1"
					( Origin gPackager )
				)
				( attribute "TOLERANCE" "20%"
					( Origin gFrontEnd )
				)
				( attribute "VALUE" "22.0UF"
					( Origin gFrontEnd )
				)
				( attribute "VER" "1"
					( Origin gFrontEnd )
				)
				( attribute "VOLTAGE" "4V"
					( Units "uVoltage" "V" 1.000000)
					( Origin gFrontEnd )
				)
				( attribute "XY" "(-1200,3725)"
					( Origin gFrontEnd )
				)
				( attribute "CHIPS_PART_NAME" "CAP_A"
					( Origin gPackager )
				)
				( attribute "CDS_PART_NAME" "CAP_A_0603V-22.0UF,4V,20%,X6S,A"
					( Origin gPackager )
				)
				( objectStatus "C2D29" )
				( pin "a"
					( attribute "PN" "1"
						( Origin gPackager )
					)
					( objectStatus "C2D29.1" )
				)
				( pin "b"
					( attribute "PN" "2"
						( Origin gPackager )
					)
					( objectStatus "C2D29.2" )
				)
			)
			( gate "@baseboard_fab2_lib.baseboard_fab2(sch_1):page76_i201"
				( attribute "BOM_COST" "PROC"
					( Origin gFrontEnd )
				)
				( attribute "CDS_LIB" "dev_discrete"
					( Origin gPackager )
				)
				( attribute "CDS_LOCATION" "C2D2"
					( Origin gPackager )
				)
				( attribute "CDS_SEC" "1"
					( Origin gPackager )
				)
				( attribute "LOCATION" "C2D2"
					( Origin gFrontEnd )
				)
				( attribute "MATERIAL" "X6S"
					( Origin gFrontEnd )
				)
				( attribute "PACK_TYPE" "0603V"
					( Origin gFrontEnd )
				)
				( attribute "PART_NUMBER" "E15431-004"
					( Origin gFrontEnd )
				)
				( attribute "PHYS_PAGE" "76"
					( Origin gFrontEnd )
				)
				( attribute "ROOM" "PVCCIN_CPU1_DECAP_VR"
					( Origin gFrontEnd )
				)
				( attribute "ROT" "0"
					( Origin gFrontEnd )
				)
				( attribute "SEC" "1"
					( Origin gPackager )
				)
				( attribute "TOLERANCE" "20%"
					( Origin gFrontEnd )
				)
				( attribute "VALUE" "22.0UF"
					( Origin gFrontEnd )
				)
				( attribute "VER" "1"
					( Origin gFrontEnd )
				)
				( attribute "VOLTAGE" "4V"
					( Units "uVoltage" "V" 1.000000)
					( Origin gFrontEnd )
				)
				( attribute "XY" "(-7725,4450)"
					( Origin gFrontEnd )
				)
				( attribute "CHIPS_PART_NAME" "CAP_A"
					( Origin gPackager )
				)
				( attribute "CDS_PART_NAME" "CAP_A_0603V-22.0UF,4V,20%,X6S,A"
					( Origin gPackager )
				)
				( objectStatus "C2D2" )
				( pin "a"
					( attribute "PN" "1"
						( Origin gPackager )
					)
					( objectStatus "C2D2.1" )
				)
				( pin "b"
					( attribute "PN" "2"
						( Origin gPackager )
					)
					( objectStatus "C2D2.2" )
				)
			)
			( gate "@baseboard_fab2_lib.baseboard_fab2(sch_1):page76_i202"
				( attribute "BOM_COST" "PROC"
					( Origin gFrontEnd )
				)
				( attribute "CDS_LIB" "dev_discrete"
					( Origin gPackager )
				)
				( attribute "CDS_LOCATION" "C2D3"
					( Origin gPackager )
				)
				( attribute "CDS_SEC" "1"
					( Origin gPackager )
				)
				( attribute "LOCATION" "C2D3"
					( Origin gFrontEnd )
				)
				( attribute "MATERIAL" "X6S"
					( Origin gFrontEnd )
				)
				( attribute "PACK_TYPE" "0603V"
					( Origin gFrontEnd )
				)
				( attribute "PART_NUMBER" "E15431-004"
					( Origin gFrontEnd )
				)
				( attribute "PHYS_PAGE" "76"
					( Origin gFrontEnd )
				)
				( attribute "ROOM" "PVCCIN_CPU1_DECAP_VR"
					( Origin gFrontEnd )
				)
				( attribute "ROT" "0"
					( Origin gFrontEnd )
				)
				( attribute "SEC" "1"
					( Origin gPackager )
				)
				( attribute "TOLERANCE" "20%"
					( Origin gFrontEnd )
				)
				( attribute "VALUE" "22.0UF"
					( Origin gFrontEnd )
				)
				( attribute "VER" "1"
					( Origin gFrontEnd )
				)
				( attribute "VOLTAGE" "4V"
					( Units "uVoltage" "V" 1.000000)
					( Origin gFrontEnd )
				)
				( attribute "XY" "(-6675,4450)"
					( Origin gFrontEnd )
				)
				( attribute "CHIPS_PART_NAME" "CAP_A"
					( Origin gPackager )
				)
				( attribute "CDS_PART_NAME" "CAP_A_0603V-22.0UF,4V,20%,X6S,A"
					( Origin gPackager )
				)
				( objectStatus "C2D3" )
				( pin "a"
					( attribute "PN" "1"
						( Origin gPackager )
					)
					( objectStatus "C2D3.1" )
				)
				( pin "b"
					( attribute "PN" "2"
						( Origin gPackager )
					)
					( objectStatus "C2D3.2" )
				)
			)
			( gate "@baseboard_fab2_lib.baseboard_fab2(sch_1):page76_i203"
				( attribute "BOM_COST" "PROC"
					( Origin gFrontEnd )
				)
				( attribute "CDS_LIB" "dev_discrete"
					( Origin gPackager )
				)
				( attribute "CDS_LOCATION" "C2D47"
					( Origin gPackager )
				)
				( attribute "CDS_SEC" "1"
					( Origin gPackager )
				)
				( attribute "LOCATION" "C2D47"
					( Origin gFrontEnd )
				)
				( attribute "MATERIAL" "X6S"
					( Origin gFrontEnd )
				)
				( attribute "PACK_TYPE" "0603V"
					( Origin gFrontEnd )
				)
				( attribute "PART_NUMBER" "E15431-004"
					( Origin gFrontEnd )
				)
				( attribute "PHYS_PAGE" "76"
					( Origin gFrontEnd )
				)
				( attribute "ROOM" "PVCCIN_CPU1_DECAP_VR"
					( Origin gFrontEnd )
				)
				( attribute "ROT" "0"
					( Origin gFrontEnd )
				)
				( attribute "SEC" "1"
					( Origin gPackager )
				)
				( attribute "TOLERANCE" "20%"
					( Origin gFrontEnd )
				)
				( attribute "VALUE" "22.0UF"
					( Origin gFrontEnd )
				)
				( attribute "VER" "1"
					( Origin gFrontEnd )
				)
				( attribute "VOLTAGE" "4V"
					( Units "uVoltage" "V" 1.000000)
					( Origin gFrontEnd )
				)
				( attribute "XY" "(-6650,3775)"
					( Origin gFrontEnd )
				)
				( attribute "CHIPS_PART_NAME" "CAP_A"
					( Origin gPackager )
				)
				( attribute "CDS_PART_NAME" "CAP_A_0603V-22.0UF,4V,20%,X6S,A"
					( Origin gPackager )
				)
				( objectStatus "C2D47" )
				( pin "a"
					( attribute "PN" "1"
						( Origin gPackager )
					)
					( objectStatus "C2D47.1" )
				)
				( pin "b"
					( attribute "PN" "2"
						( Origin gPackager )
					)
					( objectStatus "C2D47.2" )
				)
			)
			( gate "@baseboard_fab2_lib.baseboard_fab2(sch_1):page76_i204"
				( attribute "BOM_COST" "PROC"
					( Origin gFrontEnd )
				)
				( attribute "CDS_LIB" "dev_discrete"
					( Origin gPackager )
				)
				( attribute "CDS_LOCATION" "C2D46"
					( Origin gPackager )
				)
				( attribute "CDS_SEC" "1"
					( Origin gPackager )
				)
				( attribute "LOCATION" "C2D46"
					( Origin gFrontEnd )
				)
				( attribute "MATERIAL" "X6S"
					( Origin gFrontEnd )
				)
				( attribute "PACK_TYPE" "0603V"
					( Origin gFrontEnd )
				)
				( attribute "PART_NUMBER" "E15431-004"
					( Origin gFrontEnd )
				)
				( attribute "PHYS_PAGE" "76"
					( Origin gFrontEnd )
				)
				( attribute "ROOM" "PVCCIN_CPU1_DECAP_VR"
					( Origin gFrontEnd )
				)
				( attribute "ROT" "0"
					( Origin gFrontEnd )
				)
				( attribute "SEC" "1"
					( Origin gPackager )
				)
				( attribute "TOLERANCE" "20%"
					( Origin gFrontEnd )
				)
				( attribute "VALUE" "22.0UF"
					( Origin gFrontEnd )
				)
				( attribute "VER" "1"
					( Origin gFrontEnd )
				)
				( attribute "VOLTAGE" "4V"
					( Units "uVoltage" "V" 1.000000)
					( Origin gFrontEnd )
				)
				( attribute "XY" "(-5275,4450)"
					( Origin gFrontEnd )
				)
				( attribute "CHIPS_PART_NAME" "CAP_A"
					( Origin gPackager )
				)
				( attribute "CDS_PART_NAME" "CAP_A_0603V-22.0UF,4V,20%,X6S,A"
					( Origin gPackager )
				)
				( objectStatus "C2D46" )
				( pin "a"
					( attribute "PN" "1"
						( Origin gPackager )
					)
					( objectStatus "C2D46.1" )
				)
				( pin "b"
					( attribute "PN" "2"
						( Origin gPackager )
					)
					( objectStatus "C2D46.2" )
				)
			)
			( gate "@baseboard_fab2_lib.baseboard_fab2(sch_1):page76_i205"
				( attribute "BOM_COST" "PROC"
					( Origin gFrontEnd )
				)
				( attribute "CDS_LIB" "dev_discrete"
					( Origin gPackager )
				)
				( attribute "CDS_LOCATION" "C3D25"
					( Origin gPackager )
				)
				( attribute "CDS_SEC" "1"
					( Origin gPackager )
				)
				( attribute "LOCATION" "C3D25"
					( Origin gFrontEnd )
				)
				( attribute "MATERIAL" "X6S"
					( Origin gFrontEnd )
				)
				( attribute "PACK_TYPE" "0603V"
					( Origin gFrontEnd )
				)
				( attribute "PART_NUMBER" "E15431-004"
					( Origin gFrontEnd )
				)
				( attribute "PHYS_PAGE" "76"
					( Origin gFrontEnd )
				)
				( attribute "ROOM" "PVCCIN_CPU1_DECAP_VR"
					( Origin gFrontEnd )
				)
				( attribute "ROT" "0"
					( Origin gFrontEnd )
				)
				( attribute "SEC" "1"
					( Origin gPackager )
				)
				( attribute "TOLERANCE" "20%"
					( Origin gFrontEnd )
				)
				( attribute "VALUE" "22.0UF"
					( Origin gFrontEnd )
				)
				( attribute "VER" "1"
					( Origin gFrontEnd )
				)
				( attribute "VOLTAGE" "4V"
					( Units "uVoltage" "V" 1.000000)
					( Origin gFrontEnd )
				)
				( attribute "XY" "(-5500,3150)"
					( Origin gFrontEnd )
				)
				( attribute "CHIPS_PART_NAME" "CAP_A"
					( Origin gPackager )
				)
				( attribute "CDS_PART_NAME" "CAP_A_0603V-22.0UF,4V,20%,X6S,A"
					( Origin gPackager )
				)
				( objectStatus "C3D25" )
				( pin "a"
					( attribute "PN" "1"
						( Origin gPackager )
					)
					( objectStatus "C3D25.1" )
				)
				( pin "b"
					( attribute "PN" "2"
						( Origin gPackager )
					)
					( objectStatus "C3D25.2" )
				)
			)
			( gate "@baseboard_fab2_lib.baseboard_fab2(sch_1):page76_i206"
				( attribute "BOM_COST" "PROC"
					( Origin gFrontEnd )
				)
				( attribute "CDS_LIB" "dev_discrete"
					( Origin gPackager )
				)
				( attribute "CDS_LOCATION" "C7P16"
					( Origin gPackager )
				)
				( attribute "CDS_SEC" "1"
					( Origin gPackager )
				)
				( attribute "LOCATION" "C7P16"
					( Origin gFrontEnd )
				)
				( attribute "MATERIAL" "X6S"
					( Origin gFrontEnd )
				)
				( attribute "PACK_TYPE" "0603V"
					( Origin gFrontEnd )
				)
				( attribute "PART_NUMBER" "E15431-004"
					( Origin gFrontEnd )
				)
				( attribute "PHYS_PAGE" "76"
					( Origin gFrontEnd )
				)
				( attribute "ROOM" "PVCCIN_CPU1_DECAP_VR"
					( Origin gFrontEnd )
				)
				( attribute "ROT" "0"
					( Origin gFrontEnd )
				)
				( attribute "SEC" "1"
					( Origin gPackager )
				)
				( attribute "TOLERANCE" "20%"
					( Origin gFrontEnd )
				)
				( attribute "VALUE" "22.0UF"
					( Origin gFrontEnd )
				)
				( attribute "VER" "1"
					( Origin gFrontEnd )
				)
				( attribute "VOLTAGE" "4V"
					( Units "uVoltage" "V" 1.000000)
					( Origin gFrontEnd )
				)
				( attribute "XY" "(-2100,925)"
					( Origin gFrontEnd )
				)
				( attribute "CHIPS_PART_NAME" "CAP_A"
					( Origin gPackager )
				)
				( attribute "CDS_PART_NAME" "CAP_A_0603V-22.0UF,4V,20%,X6S,A"
					( Origin gPackager )
				)
				( objectStatus "C7P16" )
				( pin "a"
					( attribute "PN" "1"
						( Origin gPackager )
					)
					( objectStatus "C7P16.1" )
				)
				( pin "b"
					( attribute "PN" "2"
						( Origin gPackager )
					)
					( objectStatus "C7P16.2" )
				)
			)
			( gate "@baseboard_fab2_lib.baseboard_fab2(sch_1):page76_i207"
				( attribute "BOM_COST" "PROC"
					( Origin gFrontEnd )
				)
				( attribute "CDS_LIB" "dev_discrete"
					( Origin gPackager )
				)
				( attribute "CDS_LOCATION" "C3D20"
					( Origin gPackager )
				)
				( attribute "CDS_SEC" "1"
					( Origin gPackager )
				)
				( attribute "LOCATION" "C3D20"
					( Origin gFrontEnd )
				)
				( attribute "MATERIAL" "X6S"
					( Origin gFrontEnd )
				)
				( attribute "PACK_TYPE" "0603V"
					( Origin gFrontEnd )
				)
				( attribute "PART_NUMBER" "E15431-004"
					( Origin gFrontEnd )
				)
				( attribute "PHYS_PAGE" "76"
					( Origin gFrontEnd )
				)
				( attribute "ROOM" "PVCCIN_CPU1_DECAP_VR"
					( Origin gFrontEnd )
				)
				( attribute "ROT" "0"
					( Origin gFrontEnd )
				)
				( attribute "SEC" "1"
					( Origin gPackager )
				)
				( attribute "TOLERANCE" "20%"
					( Origin gFrontEnd )
				)
				( attribute "VALUE" "22.0UF"
					( Origin gFrontEnd )
				)
				( attribute "VER" "1"
					( Origin gFrontEnd )
				)
				( attribute "VOLTAGE" "4V"
					( Units "uVoltage" "V" 1.000000)
					( Origin gFrontEnd )
				)
				( attribute "XY" "(-725,3700)"
					( Origin gFrontEnd )
				)
				( attribute "CHIPS_PART_NAME" "CAP_A"
					( Origin gPackager )
				)
				( attribute "CDS_PART_NAME" "CAP_A_0603V-22.0UF,4V,20%,X6S,A"
					( Origin gPackager )
				)
				( objectStatus "C3D20" )
				( pin "a"
					( attribute "PN" "1"
						( Origin gPackager )
					)
					( objectStatus "C3D20.1" )
				)
				( pin "b"
					( attribute "PN" "2"
						( Origin gPackager )
					)
					( objectStatus "C3D20.2" )
				)
			)
			( gate "@baseboard_fab2_lib.baseboard_fab2(sch_1):page76_i208"
				( attribute "BOM_COST" "PROC"
					( Origin gFrontEnd )
				)
				( attribute "CDS_LIB" "dev_discrete"
					( Origin gPackager )
				)
				( attribute "CDS_LOCATION" "C3D19"
					( Origin gPackager )
				)
				( attribute "CDS_SEC" "1"
					( Origin gPackager )
				)
				( attribute "LOCATION" "C3D19"
					( Origin gFrontEnd )
				)
				( attribute "MATERIAL" "X6S"
					( Origin gFrontEnd )
				)
				( attribute "PACK_TYPE" "0603V"
					( Origin gFrontEnd )
				)
				( attribute "PART_NUMBER" "E15431-004"
					( Origin gFrontEnd )
				)
				( attribute "PHYS_PAGE" "76"
					( Origin gFrontEnd )
				)
				( attribute "ROOM" "PVCCIN_CPU1_DECAP_VR"
					( Origin gFrontEnd )
				)
				( attribute "ROT" "0"
					( Origin gFrontEnd )
				)
				( attribute "SEC" "1"
					( Origin gPackager )
				)
				( attribute "TOLERANCE" "20%"
					( Origin gFrontEnd )
				)
				( attribute "VALUE" "22.0UF"
					( Origin gFrontEnd )
				)
				( attribute "VER" "1"
					( Origin gFrontEnd )
				)
				( attribute "VOLTAGE" "4V"
					( Units "uVoltage" "V" 1.000000)
					( Origin gFrontEnd )
				)
				( attribute "XY" "(-950,3725)"
					( Origin gFrontEnd )
				)
				( attribute "CHIPS_PART_NAME" "CAP_A"
					( Origin gPackager )
				)
				( attribute "CDS_PART_NAME" "CAP_A_0603V-22.0UF,4V,20%,X6S,A"
					( Origin gPackager )
				)
				( objectStatus "C3D19" )
				( pin "a"
					( attribute "PN" "1"
						( Origin gPackager )
					)
					( objectStatus "C3D19.1" )
				)
				( pin "b"
					( attribute "PN" "2"
						( Origin gPackager )
					)
					( objectStatus "C3D19.2" )
				)
			)
			( gate "@baseboard_fab2_lib.baseboard_fab2(sch_1):page76_i211"
				( attribute "BOM_COST" "PROC"
					( Origin gFrontEnd )
				)
				( attribute "CDS_LIB" "mstr_discrete"
					( Origin gPackager )
				)
				( attribute "CDS_LOCATION" "C8P14"
					( Origin gPackager )
				)
				( attribute "CDS_SEC" "1"
					( Origin gPackager )
				)
				( attribute "LOCATION" "C8P14"
					( Origin gFrontEnd )
				)
				( attribute "MATERIAL" "X6S"
					( Origin gFrontEnd )
				)
				( attribute "PACK_TYPE" "0805"
					( Origin gFrontEnd )
				)
				( attribute "PART_NUMBER" "C95333-006"
					( Origin gFrontEnd )
				)
				( attribute "PHYS_PAGE" "76"
					( Origin gFrontEnd )
				)
				( attribute "ROOM" "PVCCIN_CPU1_DECAP_VR"
					( Origin gFrontEnd )
				)
				( attribute "ROT" "0"
					( Origin gFrontEnd )
				)
				( attribute "SEC" "1"
					( Origin gPackager )
				)
				( attribute "TOLERANCE" "20%"
					( Origin gFrontEnd )
				)
				( attribute "VALUE" "47UF"
					( Origin gFrontEnd )
				)
				( attribute "VER" "1"
					( Origin gFrontEnd )
				)
				( attribute "VOLTAGE" "4V"
					( Units "uVoltage" "V" 1.000000)
					( Origin gFrontEnd )
				)
				( attribute "XY" "(-975,2150)"
					( Origin gFrontEnd )
				)
				( attribute "CHIPS_PART_NAME" "CAP"
					( Origin gPackager )
				)
				( attribute "CDS_PART_NAME" "CAP_0805-47UF,4V,20%,X6S,C9533A"
					( Origin gPackager )
				)
				( objectStatus "C8P14" )
				( pin "a"
					( attribute "PN" "1"
						( Origin gPackager )
					)
					( objectStatus "C8P14.1" )
				)
				( pin "b"
					( attribute "PN" "2"
						( Origin gPackager )
					)
					( objectStatus "C8P14.2" )
				)
			)
			( gate "@baseboard_fab2_lib.baseboard_fab2(sch_1):page76_i212"
				( attribute "BOM_COST" "PROC"
					( Origin gFrontEnd )
				)
				( attribute "CDS_LIB" "mstr_discrete"
					( Origin gPackager )
				)
				( attribute "CDS_LOCATION" "C8P15"
					( Origin gPackager )
				)
				( attribute "CDS_SEC" "1"
					( Origin gPackager )
				)
				( attribute "LOCATION" "C8P15"
					( Origin gFrontEnd )
				)
				( attribute "MATERIAL" "X6S"
					( Origin gFrontEnd )
				)
				( attribute "PACK_TYPE" "0805"
					( Origin gFrontEnd )
				)
				( attribute "PART_NUMBER" "C95333-006"
					( Origin gFrontEnd )
				)
				( attribute "PHYS_PAGE" "76"
					( Origin gFrontEnd )
				)
				( attribute "ROOM" "PVCCIN_CPU1_DECAP_VR"
					( Origin gFrontEnd )
				)
				( attribute "ROT" "0"
					( Origin gFrontEnd )
				)
				( attribute "SEC" "1"
					( Origin gPackager )
				)
				( attribute "TOLERANCE" "20%"
					( Origin gFrontEnd )
				)
				( attribute "VALUE" "47UF"
					( Origin gFrontEnd )
				)
				( attribute "VER" "1"
					( Origin gFrontEnd )
				)
				( attribute "VOLTAGE" "4V"
					( Units "uVoltage" "V" 1.000000)
					( Origin gFrontEnd )
				)
				( attribute "XY" "(-1225,2150)"
					( Origin gFrontEnd )
				)
				( attribute "CHIPS_PART_NAME" "CAP"
					( Origin gPackager )
				)
				( attribute "CDS_PART_NAME" "CAP_0805-47UF,4V,20%,X6S,C9533A"
					( Origin gPackager )
				)
				( objectStatus "C8P15" )
				( pin "a"
					( attribute "PN" "1"
						( Origin gPackager )
					)
					( objectStatus "C8P15.1" )
				)
				( pin "b"
					( attribute "PN" "2"
						( Origin gPackager )
					)
					( objectStatus "C8P15.2" )
				)
			)
			( gate "@baseboard_fab2_lib.baseboard_fab2(sch_1):page76_i213"
				( attribute "BOM_COST" "PROC"
					( Origin gFrontEnd )
				)
				( attribute "CDS_LIB" "mstr_discrete"
					( Origin gPackager )
				)
				( attribute "CDS_LOCATION" "C8P8"
					( Origin gPackager )
				)
				( attribute "CDS_SEC" "1"
					( Origin gPackager )
				)
				( attribute "LOCATION" "C8P8"
					( Origin gFrontEnd )
				)
				( attribute "MATERIAL" "X6S"
					( Origin gFrontEnd )
				)
				( attribute "PACK_TYPE" "0805"
					( Origin gFrontEnd )
				)
				( attribute "PART_NUMBER" "C95333-006"
					( Origin gFrontEnd )
				)
				( attribute "PHYS_PAGE" "76"
					( Origin gFrontEnd )
				)
				( attribute "ROOM" "PVCCIN_CPU1_DECAP_VR"
					( Origin gFrontEnd )
				)
				( attribute "ROT" "0"
					( Origin gFrontEnd )
				)
				( attribute "SEC" "1"
					( Origin gPackager )
				)
				( attribute "TOLERANCE" "20%"
					( Origin gFrontEnd )
				)
				( attribute "VALUE" "47UF"
					( Origin gFrontEnd )
				)
				( attribute "VER" "1"
					( Origin gFrontEnd )
				)
				( attribute "VOLTAGE" "4V"
					( Units "uVoltage" "V" 1.000000)
					( Origin gFrontEnd )
				)
				( attribute "XY" "(-500,2100)"
					( Origin gFrontEnd )
				)
				( attribute "CHIPS_PART_NAME" "CAP"
					( Origin gPackager )
				)
				( attribute "CDS_PART_NAME" "CAP_0805-47UF,4V,20%,X6S,C9533A"
					( Origin gPackager )
				)
				( objectStatus "C8P8" )
				( pin "a"
					( attribute "PN" "1"
						( Origin gPackager )
					)
					( objectStatus "C8P8.1" )
				)
				( pin "b"
					( attribute "PN" "2"
						( Origin gPackager )
					)
					( objectStatus "C8P8.2" )
				)
			)
			( gate "@baseboard_fab2_lib.baseboard_fab2(sch_1):page76_i214"
				( attribute "BOM_COST" "PROC"
					( Origin gFrontEnd )
				)
				( attribute "CDS_LIB" "mstr_discrete"
					( Origin gPackager )
				)
				( attribute "CDS_LOCATION" "C8P9"
					( Origin gPackager )
				)
				( attribute "CDS_SEC" "1"
					( Origin gPackager )
				)
				( attribute "LOCATION" "C8P9"
					( Origin gFrontEnd )
				)
				( attribute "MATERIAL" "X6S"
					( Origin gFrontEnd )
				)
				( attribute "PACK_TYPE" "0805"
					( Origin gFrontEnd )
				)
				( attribute "PART_NUMBER" "C95333-006"
					( Origin gFrontEnd )
				)
				( attribute "PHYS_PAGE" "76"
					( Origin gFrontEnd )
				)
				( attribute "ROOM" "PVCCIN_CPU1_DECAP_VR"
					( Origin gFrontEnd )
				)
				( attribute "ROT" "0"
					( Origin gFrontEnd )
				)
				( attribute "SEC" "1"
					( Origin gPackager )
				)
				( attribute "TOLERANCE" "20%"
					( Origin gFrontEnd )
				)
				( attribute "VALUE" "47UF"
					( Origin gFrontEnd )
				)
				( attribute "VER" "1"
					( Origin gFrontEnd )
				)
				( attribute "VOLTAGE" "4V"
					( Units "uVoltage" "V" 1.000000)
					( Origin gFrontEnd )
				)
				( attribute "XY" "(-700,2150)"
					( Origin gFrontEnd )
				)
				( attribute "CHIPS_PART_NAME" "CAP"
					( Origin gPackager )
				)
				( attribute "CDS_PART_NAME" "CAP_0805-47UF,4V,20%,X6S,C9533A"
					( Origin gPackager )
				)
				( objectStatus "C8P9" )
				( pin "a"
					( attribute "PN" "1"
						( Origin gPackager )
					)
					( objectStatus "C8P9.1" )
				)
				( pin "b"
					( attribute "PN" "2"
						( Origin gPackager )
					)
					( objectStatus "C8P9.2" )
				)
			)
			( gate "@baseboard_fab2_lib.baseboard_fab2(sch_1):page76_i215"
				( attribute "BOM_COST" "PROC"
					( Origin gFrontEnd )
				)
				( attribute "CDS_LIB" "mstr_discrete"
					( Origin gPackager )
				)
				( attribute "CDS_LOCATION" "C7P19"
					( Origin gPackager )
				)
				( attribute "CDS_SEC" "1"
					( Origin gPackager )
				)
				( attribute "LOCATION" "C7P19"
					( Origin gFrontEnd )
				)
				( attribute "MATERIAL" "X6S"
					( Origin gFrontEnd )
				)
				( attribute "PACK_TYPE" "0805"
					( Origin gFrontEnd )
				)
				( attribute "PART_NUMBER" "C95333-006"
					( Origin gFrontEnd )
				)
				( attribute "PHYS_PAGE" "76"
					( Origin gFrontEnd )
				)
				( attribute "ROOM" "PVCCIN_CPU1_DECAP_VR"
					( Origin gFrontEnd )
				)
				( attribute "ROT" "0"
					( Origin gFrontEnd )
				)
				( attribute "SEC" "1"
					( Origin gPackager )
				)
				( attribute "TOLERANCE" "20%"
					( Origin gFrontEnd )
				)
				( attribute "VALUE" "47UF"
					( Origin gFrontEnd )
				)
				( attribute "VER" "1"
					( Origin gFrontEnd )
				)
				( attribute "VOLTAGE" "4V"
					( Units "uVoltage" "V" 1.000000)
					( Origin gFrontEnd )
				)
				( attribute "XY" "(-6700,2200)"
					( Origin gFrontEnd )
				)
				( attribute "CHIPS_PART_NAME" "CAP"
					( Origin gPackager )
				)
				( attribute "CDS_PART_NAME" "CAP_0805-47UF,4V,20%,X6S,C9533A"
					( Origin gPackager )
				)
				( objectStatus "C7P19" )
				( pin "a"
					( attribute "PN" "1"
						( Origin gPackager )
					)
					( objectStatus "C7P19.1" )
				)
				( pin "b"
					( attribute "PN" "2"
						( Origin gPackager )
					)
					( objectStatus "C7P19.2" )
				)
			)
			( gate "@baseboard_fab2_lib.baseboard_fab2(sch_1):page76_i216"
				( attribute "BOM_COST" "PROC"
					( Origin gFrontEnd )
				)
				( attribute "CDS_LIB" "mstr_discrete"
					( Origin gPackager )
				)
				( attribute "CDS_LOCATION" "C8P32"
					( Origin gPackager )
				)
				( attribute "CDS_SEC" "1"
					( Origin gPackager )
				)
				( attribute "LOCATION" "C8P32"
					( Origin gFrontEnd )
				)
				( attribute "MATERIAL" "X6S"
					( Origin gFrontEnd )
				)
				( attribute "PACK_TYPE" "0805"
					( Origin gFrontEnd )
				)
				( attribute "PART_NUMBER" "C95333-006"
					( Origin gFrontEnd )
				)
				( attribute "PHYS_PAGE" "76"
					( Origin gFrontEnd )
				)
				( attribute "ROOM" "PVCCIN_CPU1_DECAP_VR"
					( Origin gFrontEnd )
				)
				( attribute "ROT" "0"
					( Origin gFrontEnd )
				)
				( attribute "SEC" "1"
					( Origin gPackager )
				)
				( attribute "TOLERANCE" "20%"
					( Origin gFrontEnd )
				)
				( attribute "VALUE" "47UF"
					( Origin gFrontEnd )
				)
				( attribute "VER" "1"
					( Origin gFrontEnd )
				)
				( attribute "VOLTAGE" "4V"
					( Units "uVoltage" "V" 1.000000)
					( Origin gFrontEnd )
				)
				( attribute "XY" "(-6350,2200)"
					( Origin gFrontEnd )
				)
				( attribute "CHIPS_PART_NAME" "CAP"
					( Origin gPackager )
				)
				( attribute "CDS_PART_NAME" "CAP_0805-47UF,4V,20%,X6S,C9533A"
					( Origin gPackager )
				)
				( objectStatus "C8P32" )
				( pin "a"
					( attribute "PN" "1"
						( Origin gPackager )
					)
					( objectStatus "C8P32.1" )
				)
				( pin "b"
					( attribute "PN" "2"
						( Origin gPackager )
					)
					( objectStatus "C8P32.2" )
				)
			)
			( gate "@baseboard_fab2_lib.baseboard_fab2(sch_1):page76_i217"
				( attribute "BOM_COST" "PROC"
					( Origin gFrontEnd )
				)
				( attribute "CDS_LIB" "mstr_discrete"
					( Origin gPackager )
				)
				( attribute "CDS_LOCATION" "C8P24"
					( Origin gPackager )
				)
				( attribute "CDS_SEC" "1"
					( Origin gPackager )
				)
				( attribute "LOCATION" "C8P24"
					( Origin gFrontEnd )
				)
				( attribute "MATERIAL" "X6S"
					( Origin gFrontEnd )
				)
				( attribute "PACK_TYPE" "0805"
					( Origin gFrontEnd )
				)
				( attribute "PART_NUMBER" "C95333-006"
					( Origin gFrontEnd )
				)
				( attribute "PHYS_PAGE" "76"
					( Origin gFrontEnd )
				)
				( attribute "ROOM" "PVCCIN_CPU1_DECAP_VR"
					( Origin gFrontEnd )
				)
				( attribute "ROT" "0"
					( Origin gFrontEnd )
				)
				( attribute "SEC" "1"
					( Origin gPackager )
				)
				( attribute "TOLERANCE" "20%"
					( Origin gFrontEnd )
				)
				( attribute "VALUE" "47UF"
					( Origin gFrontEnd )
				)
				( attribute "VER" "1"
					( Origin gFrontEnd )
				)
				( attribute "VOLTAGE" "4V"
					( Units "uVoltage" "V" 1.000000)
					( Origin gFrontEnd )
				)
				( attribute "XY" "(-7725,900)"
					( Origin gFrontEnd )
				)
				( attribute "CHIPS_PART_NAME" "CAP"
					( Origin gPackager )
				)
				( attribute "CDS_PART_NAME" "CAP_0805-47UF,4V,20%,X6S,C9533A"
					( Origin gPackager )
				)
				( objectStatus "C8P24" )
				( pin "a"
					( attribute "PN" "1"
						( Origin gPackager )
					)
					( objectStatus "C8P24.1" )
				)
				( pin "b"
					( attribute "PN" "2"
						( Origin gPackager )
					)
					( objectStatus "C8P24.2" )
				)
			)
			( gate "@baseboard_fab2_lib.baseboard_fab2(sch_1):page76_i218"
				( attribute "BOM_COST" "PROC"
					( Origin gFrontEnd )
				)
				( attribute "CDS_LIB" "mstr_discrete"
					( Origin gPackager )
				)
				( attribute "CDS_LOCATION" "C7P20"
					( Origin gPackager )
				)
				( attribute "CDS_SEC" "1"
					( Origin gPackager )
				)
				( attribute "LOCATION" "C7P20"
					( Origin gFrontEnd )
				)
				( attribute "MATERIAL" "X6S"
					( Origin gFrontEnd )
				)
				( attribute "PACK_TYPE" "0805"
					( Origin gFrontEnd )
				)
				( attribute "PART_NUMBER" "C95333-006"
					( Origin gFrontEnd )
				)
				( attribute "PHYS_PAGE" "76"
					( Origin gFrontEnd )
				)
				( attribute "ROOM" "PVCCIN_CPU1_DECAP_VR"
					( Origin gFrontEnd )
				)
				( attribute "ROT" "0"
					( Origin gFrontEnd )
				)
				( attribute "SEC" "1"
					( Origin gPackager )
				)
				( attribute "TOLERANCE" "20%"
					( Origin gFrontEnd )
				)
				( attribute "VALUE" "47UF"
					( Origin gFrontEnd )
				)
				( attribute "VER" "1"
					( Origin gFrontEnd )
				)
				( attribute "VOLTAGE" "4V"
					( Units "uVoltage" "V" 1.000000)
					( Origin gFrontEnd )
				)
				( attribute "XY" "(-5150,2200)"
					( Origin gFrontEnd )
				)
				( attribute "CHIPS_PART_NAME" "CAP"
					( Origin gPackager )
				)
				( attribute "CDS_PART_NAME" "CAP_0805-47UF,4V,20%,X6S,C9533A"
					( Origin gPackager )
				)
				( objectStatus "C7P20" )
				( pin "a"
					( attribute "PN" "1"
						( Origin gPackager )
					)
					( objectStatus "C7P20.1" )
				)
				( pin "b"
					( attribute "PN" "2"
						( Origin gPackager )
					)
					( objectStatus "C7P20.2" )
				)
			)
			( gate "@baseboard_fab2_lib.baseboard_fab2(sch_1):page77_i43"
				( attribute "BOM_COST" "MEM"
					( Origin gFrontEnd )
				)
				( attribute "CDS_LIB" "mstr_sconn"
					( Origin gPackager )
				)
				( attribute "CDS_LOCATION" "J1G1"
					( Origin gPackager )
				)
				( attribute "CDS_SEC" "3"
					( Origin gPackager )
				)
				( attribute "LOCATION" "J1G1"
					( Origin gFrontEnd )
				)
				( attribute "MATERIAL" "SCONN"
					( Origin gFrontEnd )
				)
				( attribute "PACK_TYPE" "PIP"
					( Origin gFrontEnd )
				)
				( attribute "PART_NUMBER" "H44441-004"
					( Origin gFrontEnd )
				)
				( attribute "PHYS_PAGE" "77"
					( Origin gFrontEnd )
				)
				( attribute "ROOM" "DDR4_CH_G"
					( Origin gFrontEnd )
				)
				( attribute "ROT" "0"
					( Origin gFrontEnd )
				)
				( attribute "SEC" "3"
					( Origin gFrontEnd )
				)
				( attribute "SEC_TYPE" "PIP"
					( Origin gFrontEnd )
				)
				( attribute "VER" "3"
					( Origin gFrontEnd )
				)
				( attribute "XY" "(1800,2200)"
					( Origin gFrontEnd )
				)
				( attribute "CHIPS_PART_NAME" "SCONN288_H44441004"
					( Origin gPackager )
				)
				( attribute "CDS_PART_NAME" "SCONN288_H44441004_PIP-SCONN,HA"
					( Origin gPackager )
				)
				( objectStatus "J1G1" )
				( pin "vss(0)"
					( attribute "PN" "283"
						( Origin gPackager )
					)
					( objectStatus "J1G1.283" )
				)
				( pin "vss(1)"
					( attribute "PN" "281"
						( Origin gPackager )
					)
					( objectStatus "J1G1.281" )
				)
				( pin "vss(2)"
					( attribute "PN" "279"
						( Origin gPackager )
					)
					( objectStatus "J1G1.279" )
				)
				( pin "vss(3)"
					( attribute "PN" "276"
						( Origin gPackager )
					)
					( objectStatus "J1G1.276" )
				)
				( pin "vss(4)"
					( attribute "PN" "274"
						( Origin gPackager )
					)
					( objectStatus "J1G1.274" )
				)
				( pin "vss(5)"
					( attribute "PN" "272"
						( Origin gPackager )
					)
					( objectStatus "J1G1.272" )
				)
				( pin "vss(6)"
					( attribute "PN" "270"
						( Origin gPackager )
					)
					( objectStatus "J1G1.270" )
				)
				( pin "vss(7)"
					( attribute "PN" "268"
						( Origin gPackager )
					)
					( objectStatus "J1G1.268" )
				)
				( pin "vss(8)"
					( attribute "PN" "265"
						( Origin gPackager )
					)
					( objectStatus "J1G1.265" )
				)
				( pin "vss(9)"
					( attribute "PN" "263"
						( Origin gPackager )
					)
					( objectStatus "J1G1.263" )
				)
				( pin "vss(10)"
					( attribute "PN" "261"
						( Origin gPackager )
					)
					( objectStatus "J1G1.261" )
				)
				( pin "vss(11)"
					( attribute "PN" "259"
						( Origin gPackager )
					)
					( objectStatus "J1G1.259" )
				)
				( pin "vss(12)"
					( attribute "PN" "257"
						( Origin gPackager )
					)
					( objectStatus "J1G1.257" )
				)
				( pin "vss(13)"
					( attribute "PN" "254"
						( Origin gPackager )
					)
					( objectStatus "J1G1.254" )
				)
				( pin "vss(14)"
					( attribute "PN" "252"
						( Origin gPackager )
					)
					( objectStatus "J1G1.252" )
				)
				( pin "vss(15)"
					( attribute "PN" "250"
						( Origin gPackager )
					)
					( objectStatus "J1G1.250" )
				)
				( pin "vss(16)"
					( attribute "PN" "248"
						( Origin gPackager )
					)
					( objectStatus "J1G1.248" )
				)
				( pin "vss(17)"
					( attribute "PN" "246"
						( Origin gPackager )
					)
					( objectStatus "J1G1.246" )
				)
				( pin "vss(18)"
					( attribute "PN" "243"
						( Origin gPackager )
					)
					( objectStatus "J1G1.243" )
				)
				( pin "vss(19)"
					( attribute "PN" "241"
						( Origin gPackager )
					)
					( objectStatus "J1G1.241" )
				)
				( pin "vss(20)"
					( attribute "PN" "239"
						( Origin gPackager )
					)
					( objectStatus "J1G1.239" )
				)
				( pin "vss(21)"
					( attribute "PN" "202"
						( Origin gPackager )
					)
					( objectStatus "J1G1.202" )
				)
				( pin "vss(22)"
					( attribute "PN" "200"
						( Origin gPackager )
					)
					( objectStatus "J1G1.200" )
				)
				( pin "vss(23)"
					( attribute "PN" "198"
						( Origin gPackager )
					)
					( objectStatus "J1G1.198" )
				)
				( pin "vss(24)"
					( attribute "PN" "195"
						( Origin gPackager )
					)
					( objectStatus "J1G1.195" )
				)
				( pin "vss(25)"
					( attribute "PN" "193"
						( Origin gPackager )
					)
					( objectStatus "J1G1.193" )
				)
				( pin "vss(26)"
					( attribute "PN" "191"
						( Origin gPackager )
					)
					( objectStatus "J1G1.191" )
				)
				( pin "vss(27)"
					( attribute "PN" "189"
						( Origin gPackager )
					)
					( objectStatus "J1G1.189" )
				)
				( pin "vss(28)"
					( attribute "PN" "187"
						( Origin gPackager )
					)
					( objectStatus "J1G1.187" )
				)
				( pin "vss(29)"
					( attribute "PN" "184"
						( Origin gPackager )
					)
					( objectStatus "J1G1.184" )
				)
				( pin "vss(30)"
					( attribute "PN" "182"
						( Origin gPackager )
					)
					( objectStatus "J1G1.182" )
				)
				( pin "vss(31)"
					( attribute "PN" "180"
						( Origin gPackager )
					)
					( objectStatus "J1G1.180" )
				)
				( pin "vss(32)"
					( attribute "PN" "178"
						( Origin gPackager )
					)
					( objectStatus "J1G1.178" )
				)
				( pin "vss(33)"
					( attribute "PN" "176"
						( Origin gPackager )
					)
					( objectStatus "J1G1.176" )
				)
				( pin "vss(34)"
					( attribute "PN" "173"
						( Origin gPackager )
					)
					( objectStatus "J1G1.173" )
				)
				( pin "vss(35)"
					( attribute "PN" "171"
						( Origin gPackager )
					)
					( objectStatus "J1G1.171" )
				)
				( pin "vss(36)"
					( attribute "PN" "169"
						( Origin gPackager )
					)
					( objectStatus "J1G1.169" )
				)
				( pin "vss(37)"
					( attribute "PN" "167"
						( Origin gPackager )
					)
					( objectStatus "J1G1.167" )
				)
				( pin "vss(38)"
					( attribute "PN" "165"
						( Origin gPackager )
					)
					( objectStatus "J1G1.165" )
				)
				( pin "vss(39)"
					( attribute "PN" "162"
						( Origin gPackager )
					)
					( objectStatus "J1G1.162" )
				)
				( pin "vss(40)"
					( attribute "PN" "160"
						( Origin gPackager )
					)
					( objectStatus "J1G1.160" )
				)
				( pin "vss(41)"
					( attribute "PN" "158"
						( Origin gPackager )
					)
					( objectStatus "J1G1.158" )
				)
				( pin "vss(42)"
					( attribute "PN" "156"
						( Origin gPackager )
					)
					( objectStatus "J1G1.156" )
				)
				( pin "vss(43)"
					( attribute "PN" "154"
						( Origin gPackager )
					)
					( objectStatus "J1G1.154" )
				)
				( pin "vss(44)"
					( attribute "PN" "151"
						( Origin gPackager )
					)
					( objectStatus "J1G1.151" )
				)
				( pin "vss(45)"
					( attribute "PN" "149"
						( Origin gPackager )
					)
					( objectStatus "J1G1.149" )
				)
				( pin "vss(46)"
					( attribute "PN" "147"
						( Origin gPackager )
					)
					( objectStatus "J1G1.147" )
				)
				( pin "vss(47)"
					( attribute "PN" "138"
						( Origin gPackager )
					)
					( objectStatus "J1G1.138" )
				)
				( pin "vss(48)"
					( attribute "PN" "136"
						( Origin gPackager )
					)
					( objectStatus "J1G1.136" )
				)
				( pin "vss(49)"
					( attribute "PN" "134"
						( Origin gPackager )
					)
					( objectStatus "J1G1.134" )
				)
				( pin "vss(50)"
					( attribute "PN" "131"
						( Origin gPackager )
					)
					( objectStatus "J1G1.131" )
				)
				( pin "vss(51)"
					( attribute "PN" "129"
						( Origin gPackager )
					)
					( objectStatus "J1G1.129" )
				)
				( pin "vss(52)"
					( attribute "PN" "127"
						( Origin gPackager )
					)
					( objectStatus "J1G1.127" )
				)
				( pin "vss(53)"
					( attribute "PN" "125"
						( Origin gPackager )
					)
					( objectStatus "J1G1.125" )
				)
				( pin "vss(54)"
					( attribute "PN" "123"
						( Origin gPackager )
					)
					( objectStatus "J1G1.123" )
				)
				( pin "vss(55)"
					( attribute "PN" "120"
						( Origin gPackager )
					)
					( objectStatus "J1G1.120" )
				)
				( pin "vss(56)"
					( attribute "PN" "118"
						( Origin gPackager )
					)
					( objectStatus "J1G1.118" )
				)
				( pin "vss(57)"
					( attribute "PN" "116"
						( Origin gPackager )
					)
					( objectStatus "J1G1.116" )
				)
				( pin "vss(58)"
					( attribute "PN" "114"
						( Origin gPackager )
					)
					( objectStatus "J1G1.114" )
				)
				( pin "vss(59)"
					( attribute "PN" "112"
						( Origin gPackager )
					)
					( objectStatus "J1G1.112" )
				)
				( pin "vss(60)"
					( attribute "PN" "109"
						( Origin gPackager )
					)
					( objectStatus "J1G1.109" )
				)
				( pin "vss(61)"
					( attribute "PN" "107"
						( Origin gPackager )
					)
					( objectStatus "J1G1.107" )
				)
				( pin "vss(62)"
					( attribute "PN" "105"
						( Origin gPackager )
					)
					( objectStatus "J1G1.105" )
				)
				( pin "vss(63)"
					( attribute "PN" "103"
						( Origin gPackager )
					)
					( objectStatus "J1G1.103" )
				)
				( pin "vss(64)"
					( attribute "PN" "101"
						( Origin gPackager )
					)
					( objectStatus "J1G1.101" )
				)
				( pin "vss(65)"
					( attribute "PN" "98"
						( Origin gPackager )
					)
					( objectStatus "J1G1.98" )
				)
				( pin "vss(66)"
					( attribute "PN" "96"
						( Origin gPackager )
					)
					( objectStatus "J1G1.96" )
				)
				( pin "vss(67)"
					( attribute "PN" "94"
						( Origin gPackager )
					)
					( objectStatus "J1G1.94" )
				)
				( pin "vss(68)"
					( attribute "PN" "57"
						( Origin gPackager )
					)
					( objectStatus "J1G1.57" )
				)
				( pin "vss(69)"
					( attribute "PN" "55"
						( Origin gPackager )
					)
					( objectStatus "J1G1.55" )
				)
				( pin "vss(70)"
					( attribute "PN" "53"
						( Origin gPackager )
					)
					( objectStatus "J1G1.53" )
				)
				( pin "vss(71)"
					( attribute "PN" "50"
						( Origin gPackager )
					)
					( objectStatus "J1G1.50" )
				)
				( pin "vss(72)"
					( attribute "PN" "48"
						( Origin gPackager )
					)
					( objectStatus "J1G1.48" )
				)
				( pin "vss(73)"
					( attribute "PN" "46"
						( Origin gPackager )
					)
					( objectStatus "J1G1.46" )
				)
				( pin "vss(74)"
					( attribute "PN" "44"
						( Origin gPackager )
					)
					( objectStatus "J1G1.44" )
				)
				( pin "vss(75)"
					( attribute "PN" "42"
						( Origin gPackager )
					)
					( objectStatus "J1G1.42" )
				)
				( pin "vss(76)"
					( attribute "PN" "39"
						( Origin gPackager )
					)
					( objectStatus "J1G1.39" )
				)
				( pin "vss(77)"
					( attribute "PN" "37"
						( Origin gPackager )
					)
					( objectStatus "J1G1.37" )
				)
				( pin "vss(78)"
					( attribute "PN" "35"
						( Origin gPackager )
					)
					( objectStatus "J1G1.35" )
				)
				( pin "vss(79)"
					( attribute "PN" "33"
						( Origin gPackager )
					)
					( objectStatus "J1G1.33" )
				)
				( pin "vss(80)"
					( attribute "PN" "31"
						( Origin gPackager )
					)
					( objectStatus "J1G1.31" )
				)
				( pin "vss(81)"
					( attribute "PN" "28"
						( Origin gPackager )
					)
					( objectStatus "J1G1.28" )
				)
				( pin "vss(82)"
					( attribute "PN" "26"
						( Origin gPackager )
					)
					( objectStatus "J1G1.26" )
				)
				( pin "vss(83)"
					( attribute "PN" "24"
						( Origin gPackager )
					)
					( objectStatus "J1G1.24" )
				)
				( pin "vss(84)"
					( attribute "PN" "22"
						( Origin gPackager )
					)
					( objectStatus "J1G1.22" )
				)
				( pin "vss(85)"
					( attribute "PN" "20"
						( Origin gPackager )
					)
					( objectStatus "J1G1.20" )
				)
				( pin "vss(86)"
					( attribute "PN" "17"
						( Origin gPackager )
					)
					( objectStatus "J1G1.17" )
				)
				( pin "vss(87)"
					( attribute "PN" "15"
						( Origin gPackager )
					)
					( objectStatus "J1G1.15" )
				)
				( pin "vss(88)"
					( attribute "PN" "13"
						( Origin gPackager )
					)
					( objectStatus "J1G1.13" )
				)
				( pin "vss(89)"
					( attribute "PN" "11"
						( Origin gPackager )
					)
					( objectStatus "J1G1.11" )
				)
				( pin "vss(90)"
					( attribute "PN" "9"
						( Origin gPackager )
					)
					( objectStatus "J1G1.9" )
				)
				( pin "vss(91)"
					( attribute "PN" "6"
						( Origin gPackager )
					)
					( objectStatus "J1G1.6" )
				)
				( pin "vss(92)"
					( attribute "PN" "4"
						( Origin gPackager )
					)
					( objectStatus "J1G1.4" )
				)
				( pin "vss(93)"
					( attribute "PN" "2"
						( Origin gPackager )
					)
					( objectStatus "J1G1.2" )
				)
			)
			( gate "@baseboard_fab2_lib.baseboard_fab2(sch_1):page77_i66"
				( attribute "BOM_COST" "MEM"
					( Origin gFrontEnd )
				)
				( attribute "CDS_LIB" "mstr_sconn"
					( Origin gPackager )
				)
				( attribute "CDS_LOCATION" "J1G1"
					( Origin gPackager )
				)
				( attribute "CDS_SEC" "2"
					( Origin gPackager )
				)
				( attribute "LOCATION" "J1G1"
					( Origin gFrontEnd )
				)
				( attribute "MATERIAL" "SCONN"
					( Origin gFrontEnd )
				)
				( attribute "PACK_TYPE" "PIP"
					( Origin gFrontEnd )
				)
				( attribute "PART_NUMBER" "H44441-004"
					( Origin gFrontEnd )
				)
				( attribute "PHYS_PAGE" "77"
					( Origin gFrontEnd )
				)
				( attribute "ROOM" "DDR4_CH_G"
					( Origin gFrontEnd )
				)
				( attribute "ROT" "0"
					( Origin gFrontEnd )
				)
				( attribute "SEC" "2"
					( Origin gFrontEnd )
				)
				( attribute "SEC_TYPE" "PIP"
					( Origin gFrontEnd )
				)
				( attribute "VER" "2"
					( Origin gFrontEnd )
				)
				( attribute "XY" "(0,4200)"
					( Origin gFrontEnd )
				)
				( attribute "CHIPS_PART_NAME" "SCONN288_H44441004"
					( Origin gPackager )
				)
				( attribute "CDS_PART_NAME" "SCONN288_H44441004_PIP-SCONN,HA"
					( Origin gPackager )
				)
				( objectStatus "J1G1" )
				( pin "dqs0n"
					( attribute "PN" "152"
						( Origin gPackager )
					)
					( objectStatus "J1G1.152" )
				)
				( pin "dqs0p"
					( attribute "PN" "153"
						( Origin gPackager )
					)
					( objectStatus "J1G1.153" )
				)
				( pin "dqs1n"
					( attribute "PN" "163"
						( Origin gPackager )
					)
					( objectStatus "J1G1.163" )
				)
				( pin "dqs1p"
					( attribute "PN" "164"
						( Origin gPackager )
					)
					( objectStatus "J1G1.164" )
				)
				( pin "dqs2n"
					( attribute "PN" "174"
						( Origin gPackager )
					)
					( objectStatus "J1G1.174" )
				)
				( pin "dqs2p"
					( attribute "PN" "175"
						( Origin gPackager )
					)
					( objectStatus "J1G1.175" )
				)
				( pin "dqs3n"
					( attribute "PN" "185"
						( Origin gPackager )
					)
					( objectStatus "J1G1.185" )
				)
				( pin "dqs3p"
					( attribute "PN" "186"
						( Origin gPackager )
					)
					( objectStatus "J1G1.186" )
				)
				( pin "dqs4n"
					( attribute "PN" "244"
						( Origin gPackager )
					)
					( objectStatus "J1G1.244" )
				)
				( pin "dqs4p"
					( attribute "PN" "245"
						( Origin gPackager )
					)
					( objectStatus "J1G1.245" )
				)
				( pin "dqs5n"
					( attribute "PN" "255"
						( Origin gPackager )
					)
					( objectStatus "J1G1.255" )
				)
				( pin "dqs5p"
					( attribute "PN" "256"
						( Origin gPackager )
					)
					( objectStatus "J1G1.256" )
				)
				( pin "dqs6n"
					( attribute "PN" "266"
						( Origin gPackager )
					)
					( objectStatus "J1G1.266" )
				)
				( pin "dqs6p"
					( attribute "PN" "267"
						( Origin gPackager )
					)
					( objectStatus "J1G1.267" )
				)
				( pin "dqs7n"
					( attribute "PN" "277"
						( Origin gPackager )
					)
					( objectStatus "J1G1.277" )
				)
				( pin "dqs7p"
					( attribute "PN" "278"
						( Origin gPackager )
					)
					( objectStatus "J1G1.278" )
				)
				( pin "dqs8n"
					( attribute "PN" "196"
						( Origin gPackager )
					)
					( objectStatus "J1G1.196" )
				)
				( pin "dqs8p"
					( attribute "PN" "197"
						( Origin gPackager )
					)
					( objectStatus "J1G1.197" )
				)
				( pin "dqs9n"
					( attribute "PN" "8"
						( Origin gPackager )
					)
					( objectStatus "J1G1.8" )
				)
				( pin "dqs9p"
					( attribute "PN" "7"
						( Origin gPackager )
					)
					( objectStatus "J1G1.7" )
				)
				( pin "dqs10n"
					( attribute "PN" "19"
						( Origin gPackager )
					)
					( objectStatus "J1G1.19" )
				)
				( pin "dqs10p"
					( attribute "PN" "18"
						( Origin gPackager )
					)
					( objectStatus "J1G1.18" )
				)
				( pin "dqs11n"
					( attribute "PN" "30"
						( Origin gPackager )
					)
					( objectStatus "J1G1.30" )
				)
				( pin "dqs11p"
					( attribute "PN" "29"
						( Origin gPackager )
					)
					( objectStatus "J1G1.29" )
				)
				( pin "dqs12n"
					( attribute "PN" "41"
						( Origin gPackager )
					)
					( objectStatus "J1G1.41" )
				)
				( pin "dqs12p"
					( attribute "PN" "40"
						( Origin gPackager )
					)
					( objectStatus "J1G1.40" )
				)
				( pin "dqs13n"
					( attribute "PN" "100"
						( Origin gPackager )
					)
					( objectStatus "J1G1.100" )
				)
				( pin "dqs13p"
					( attribute "PN" "99"
						( Origin gPackager )
					)
					( objectStatus "J1G1.99" )
				)
				( pin "dqs14n"
					( attribute "PN" "111"
						( Origin gPackager )
					)
					( objectStatus "J1G1.111" )
				)
				( pin "dqs14p"
					( attribute "PN" "110"
						( Origin gPackager )
					)
					( objectStatus "J1G1.110" )
				)
				( pin "dqs15n"
					( attribute "PN" "122"
						( Origin gPackager )
					)
					( objectStatus "J1G1.122" )
				)
				( pin "dqs15p"
					( attribute "PN" "121"
						( Origin gPackager )
					)
					( objectStatus "J1G1.121" )
				)
				( pin "dqs16n"
					( attribute "PN" "133"
						( Origin gPackager )
					)
					( objectStatus "J1G1.133" )
				)
				( pin "dqs16p"
					( attribute "PN" "132"
						( Origin gPackager )
					)
					( objectStatus "J1G1.132" )
				)
				( pin "dqs17n"
					( attribute "PN" "52"
						( Origin gPackager )
					)
					( objectStatus "J1G1.52" )
				)
				( pin "dqs17p"
					( attribute "PN" "51"
						( Origin gPackager )
					)
					( objectStatus "J1G1.51" )
				)
			)
			( gate "@baseboard_fab2_lib.baseboard_fab2(sch_1):page77_i111"
				( attribute "BOM_COST" "MEM"
					( Origin gFrontEnd )
				)
				( attribute "CDS_LIB" "mstr_sconn"
					( Origin gPackager )
				)
				( attribute "CDS_LOCATION" "J1G1"
					( Origin gPackager )
				)
				( attribute "CDS_SEC" "1"
					( Origin gPackager )
				)
				( attribute "LOCATION" "J1G1"
					( Origin gFrontEnd )
				)
				( attribute "MATERIAL" "SCONN"
					( Origin gFrontEnd )
				)
				( attribute "PACK_TYPE" "PIP"
					( Origin gFrontEnd )
				)
				( attribute "PART_NUMBER" "H44441-004"
					( Origin gFrontEnd )
				)
				( attribute "PHYS_PAGE" "77"
					( Origin gFrontEnd )
				)
				( attribute "ROOM" "DDR4_CH_G"
					( Origin gFrontEnd )
				)
				( attribute "ROT" "0"
					( Origin gFrontEnd )
				)
				( attribute "SEC" "1"
					( Origin gFrontEnd )
				)
				( attribute "SEC_TYPE" "PIP"
					( Origin gFrontEnd )
				)
				( attribute "VER" "1"
					( Origin gFrontEnd )
				)
				( attribute "XY" "(-2375,2775)"
					( Origin gFrontEnd )
				)
				( attribute "CHIPS_PART_NAME" "SCONN288_H44441004"
					( Origin gPackager )
				)
				( attribute "CDS_PART_NAME" "SCONN288_H44441004_PIP-SCONN,HA"
					( Origin gPackager )
				)
				( objectStatus "J1G1" )
				( pin "a0"
					( attribute "PN" "79"
						( Origin gPackager )
					)
					( objectStatus "J1G1.79" )
				)
				( pin "a1"
					( attribute "PN" "72"
						( Origin gPackager )
					)
					( objectStatus "J1G1.72" )
				)
				( pin "a2"
					( attribute "PN" "216"
						( Origin gPackager )
					)
					( objectStatus "J1G1.216" )
				)
				( pin "a3"
					( attribute "PN" "71"
						( Origin gPackager )
					)
					( objectStatus "J1G1.71" )
				)
				( pin "a4"
					( attribute "PN" "214"
						( Origin gPackager )
					)
					( objectStatus "J1G1.214" )
				)
				( pin "a5"
					( attribute "PN" "213"
						( Origin gPackager )
					)
					( objectStatus "J1G1.213" )
				)
				( pin "a6"
					( attribute "PN" "69"
						( Origin gPackager )
					)
					( objectStatus "J1G1.69" )
				)
				( pin "a7"
					( attribute "PN" "211"
						( Origin gPackager )
					)
					( objectStatus "J1G1.211" )
				)
				( pin "a8"
					( attribute "PN" "68"
						( Origin gPackager )
					)
					( objectStatus "J1G1.68" )
				)
				( pin "a9"
					( attribute "PN" "66"
						( Origin gPackager )
					)
					( objectStatus "J1G1.66" )
				)
				( pin "a10"
					( attribute "PN" "225"
						( Origin gPackager )
					)
					( objectStatus "J1G1.225" )
				)
				( pin "a11"
					( attribute "PN" "210"
						( Origin gPackager )
					)
					( objectStatus "J1G1.210" )
				)
				( pin "a12"
					( attribute "PN" "65"
						( Origin gPackager )
					)
					( objectStatus "J1G1.65" )
				)
				( pin "a13"
					( attribute "PN" "232"
						( Origin gPackager )
					)
					( objectStatus "J1G1.232" )
				)
				( pin "a14_we_n"
					( attribute "PN" "228"
						( Origin gPackager )
					)
					( objectStatus "J1G1.228" )
				)
				( pin "a15_cas_n"
					( attribute "PN" "86"
						( Origin gPackager )
					)
					( objectStatus "J1G1.86" )
				)
				( pin "a16_ras_n"
					( attribute "PN" "82"
						( Origin gPackager )
					)
					( objectStatus "J1G1.82" )
				)
				( pin "a17"
					( attribute "PN" "234"
						( Origin gPackager )
					)
					( objectStatus "J1G1.234" )
				)
				( pin "act_n"
					( attribute "PN" "62"
						( Origin gPackager )
					)
					( objectStatus "J1G1.62" )
				)
				( pin "alert_n"
					( attribute "PN" "208"
						( Origin gPackager )
					)
					( objectStatus "J1G1.208" )
				)
				( pin "ba(0)"
					( attribute "PN" "81"
						( Origin gPackager )
					)
					( objectStatus "J1G1.81" )
				)
				( pin "ba(1)"
					( attribute "PN" "224"
						( Origin gPackager )
					)
					( objectStatus "J1G1.224" )
				)
				( pin "bg(0)"
					( attribute "PN" "63"
						( Origin gPackager )
					)
					( objectStatus "J1G1.63" )
				)
				( pin "bg(1)"
					( attribute "PN" "207"
						( Origin gPackager )
					)
					( objectStatus "J1G1.207" )
				)
				( pin "c(2)"
					( attribute "PN" "235"
						( Origin gPackager )
					)
					( objectStatus "J1G1.235" )
				)
				( pin "cb(0)"
					( attribute "PN" "49"
						( Origin gPackager )
					)
					( objectStatus "J1G1.49" )
				)
				( pin "cb(1)"
					( attribute "PN" "194"
						( Origin gPackager )
					)
					( objectStatus "J1G1.194" )
				)
				( pin "cb(2)"
					( attribute "PN" "56"
						( Origin gPackager )
					)
					( objectStatus "J1G1.56" )
				)
				( pin "cb(3)"
					( attribute "PN" "201"
						( Origin gPackager )
					)
					( objectStatus "J1G1.201" )
				)
				( pin "cb(4)"
					( attribute "PN" "47"
						( Origin gPackager )
					)
					( objectStatus "J1G1.47" )
				)
				( pin "cb(5)"
					( attribute "PN" "192"
						( Origin gPackager )
					)
					( objectStatus "J1G1.192" )
				)
				( pin "cb(6)"
					( attribute "PN" "54"
						( Origin gPackager )
					)
					( objectStatus "J1G1.54" )
				)
				( pin "cb(7)"
					( attribute "PN" "199"
						( Origin gPackager )
					)
					( objectStatus "J1G1.199" )
				)
				( pin "ck0n"
					( attribute "PN" "75"
						( Origin gPackager )
					)
					( objectStatus "J1G1.75" )
				)
				( pin "ck0p"
					( attribute "PN" "74"
						( Origin gPackager )
					)
					( objectStatus "J1G1.74" )
				)
				( pin "ck1n"
					( attribute "PN" "219"
						( Origin gPackager )
					)
					( objectStatus "J1G1.219" )
				)
				( pin "ck1p"
					( attribute "PN" "218"
						( Origin gPackager )
					)
					( objectStatus "J1G1.218" )
				)
				( pin "cke(0)"
					( attribute "PN" "60"
						( Origin gPackager )
					)
					( objectStatus "J1G1.60" )
				)
				( pin "cke(1)"
					( attribute "PN" "203"
						( Origin gPackager )
					)
					( objectStatus "J1G1.203" )
				)
				( pin "dq(0)"
					( attribute "PN" "5"
						( Origin gPackager )
					)
					( objectStatus "J1G1.5" )
				)
				( pin "dq(1)"
					( attribute "PN" "150"
						( Origin gPackager )
					)
					( objectStatus "J1G1.150" )
				)
				( pin "dq(2)"
					( attribute "PN" "12"
						( Origin gPackager )
					)
					( objectStatus "J1G1.12" )
				)
				( pin "dq(3)"
					( attribute "PN" "157"
						( Origin gPackager )
					)
					( objectStatus "J1G1.157" )
				)
				( pin "dq(4)"
					( attribute "PN" "3"
						( Origin gPackager )
					)
					( objectStatus "J1G1.3" )
				)
				( pin "dq(5)"
					( attribute "PN" "148"
						( Origin gPackager )
					)
					( objectStatus "J1G1.148" )
				)
				( pin "dq(6)"
					( attribute "PN" "10"
						( Origin gPackager )
					)
					( objectStatus "J1G1.10" )
				)
				( pin "dq(7)"
					( attribute "PN" "155"
						( Origin gPackager )
					)
					( objectStatus "J1G1.155" )
				)
				( pin "dq(8)"
					( attribute "PN" "16"
						( Origin gPackager )
					)
					( objectStatus "J1G1.16" )
				)
				( pin "dq(9)"
					( attribute "PN" "161"
						( Origin gPackager )
					)
					( objectStatus "J1G1.161" )
				)
				( pin "dq(10)"
					( attribute "PN" "23"
						( Origin gPackager )
					)
					( objectStatus "J1G1.23" )
				)
				( pin "dq(11)"
					( attribute "PN" "168"
						( Origin gPackager )
					)
					( objectStatus "J1G1.168" )
				)
				( pin "dq(12)"
					( attribute "PN" "14"
						( Origin gPackager )
					)
					( objectStatus "J1G1.14" )
				)
				( pin "dq(13)"
					( attribute "PN" "159"
						( Origin gPackager )
					)
					( objectStatus "J1G1.159" )
				)
				( pin "dq(14)"
					( attribute "PN" "21"
						( Origin gPackager )
					)
					( objectStatus "J1G1.21" )
				)
				( pin "dq(15)"
					( attribute "PN" "166"
						( Origin gPackager )
					)
					( objectStatus "J1G1.166" )
				)
				( pin "dq(16)"
					( attribute "PN" "27"
						( Origin gPackager )
					)
					( objectStatus "J1G1.27" )
				)
				( pin "dq(17)"
					( attribute "PN" "172"
						( Origin gPackager )
					)
					( objectStatus "J1G1.172" )
				)
				( pin "dq(18)"
					( attribute "PN" "34"
						( Origin gPackager )
					)
					( objectStatus "J1G1.34" )
				)
				( pin "dq(19)"
					( attribute "PN" "179"
						( Origin gPackager )
					)
					( objectStatus "J1G1.179" )
				)
				( pin "dq(20)"
					( attribute "PN" "25"
						( Origin gPackager )
					)
					( objectStatus "J1G1.25" )
				)
				( pin "dq(21)"
					( attribute "PN" "170"
						( Origin gPackager )
					)
					( objectStatus "J1G1.170" )
				)
				( pin "dq(22)"
					( attribute "PN" "32"
						( Origin gPackager )
					)
					( objectStatus "J1G1.32" )
				)
				( pin "dq(23)"
					( attribute "PN" "177"
						( Origin gPackager )
					)
					( objectStatus "J1G1.177" )
				)
				( pin "dq(24)"
					( attribute "PN" "38"
						( Origin gPackager )
					)
					( objectStatus "J1G1.38" )
				)
				( pin "dq(25)"
					( attribute "PN" "183"
						( Origin gPackager )
					)
					( objectStatus "J1G1.183" )
				)
				( pin "dq(26)"
					( attribute "PN" "45"
						( Origin gPackager )
					)
					( objectStatus "J1G1.45" )
				)
				( pin "dq(27)"
					( attribute "PN" "190"
						( Origin gPackager )
					)
					( objectStatus "J1G1.190" )
				)
				( pin "dq(28)"
					( attribute "PN" "36"
						( Origin gPackager )
					)
					( objectStatus "J1G1.36" )
				)
				( pin "dq(29)"
					( attribute "PN" "181"
						( Origin gPackager )
					)
					( objectStatus "J1G1.181" )
				)
				( pin "dq(30)"
					( attribute "PN" "43"
						( Origin gPackager )
					)
					( objectStatus "J1G1.43" )
				)
				( pin "dq(31)"
					( attribute "PN" "188"
						( Origin gPackager )
					)
					( objectStatus "J1G1.188" )
				)
				( pin "dq(32)"
					( attribute "PN" "97"
						( Origin gPackager )
					)
					( objectStatus "J1G1.97" )
				)
				( pin "dq(33)"
					( attribute "PN" "242"
						( Origin gPackager )
					)
					( objectStatus "J1G1.242" )
				)
				( pin "dq(34)"
					( attribute "PN" "104"
						( Origin gPackager )
					)
					( objectStatus "J1G1.104" )
				)
				( pin "dq(35)"
					( attribute "PN" "249"
						( Origin gPackager )
					)
					( objectStatus "J1G1.249" )
				)
				( pin "dq(36)"
					( attribute "PN" "95"
						( Origin gPackager )
					)
					( objectStatus "J1G1.95" )
				)
				( pin "dq(37)"
					( attribute "PN" "240"
						( Origin gPackager )
					)
					( objectStatus "J1G1.240" )
				)
				( pin "dq(38)"
					( attribute "PN" "102"
						( Origin gPackager )
					)
					( objectStatus "J1G1.102" )
				)
				( pin "dq(39)"
					( attribute "PN" "247"
						( Origin gPackager )
					)
					( objectStatus "J1G1.247" )
				)
				( pin "dq(40)"
					( attribute "PN" "108"
						( Origin gPackager )
					)
					( objectStatus "J1G1.108" )
				)
				( pin "dq(41)"
					( attribute "PN" "253"
						( Origin gPackager )
					)
					( objectStatus "J1G1.253" )
				)
				( pin "dq(42)"
					( attribute "PN" "115"
						( Origin gPackager )
					)
					( objectStatus "J1G1.115" )
				)
				( pin "dq(43)"
					( attribute "PN" "260"
						( Origin gPackager )
					)
					( objectStatus "J1G1.260" )
				)
				( pin "dq(44)"
					( attribute "PN" "106"
						( Origin gPackager )
					)
					( objectStatus "J1G1.106" )
				)
				( pin "dq(45)"
					( attribute "PN" "251"
						( Origin gPackager )
					)
					( objectStatus "J1G1.251" )
				)
				( pin "dq(46)"
					( attribute "PN" "113"
						( Origin gPackager )
					)
					( objectStatus "J1G1.113" )
				)
				( pin "dq(47)"
					( attribute "PN" "258"
						( Origin gPackager )
					)
					( objectStatus "J1G1.258" )
				)
				( pin "dq(48)"
					( attribute "PN" "119"
						( Origin gPackager )
					)
					( objectStatus "J1G1.119" )
				)
				( pin "dq(49)"
					( attribute "PN" "264"
						( Origin gPackager )
					)
					( objectStatus "J1G1.264" )
				)
				( pin "dq(50)"
					( attribute "PN" "126"
						( Origin gPackager )
					)
					( objectStatus "J1G1.126" )
				)
				( pin "dq(51)"
					( attribute "PN" "271"
						( Origin gPackager )
					)
					( objectStatus "J1G1.271" )
				)
				( pin "dq(52)"
					( attribute "PN" "117"
						( Origin gPackager )
					)
					( objectStatus "J1G1.117" )
				)
				( pin "dq(53)"
					( attribute "PN" "262"
						( Origin gPackager )
					)
					( objectStatus "J1G1.262" )
				)
				( pin "dq(54)"
					( attribute "PN" "124"
						( Origin gPackager )
					)
					( objectStatus "J1G1.124" )
				)
				( pin "dq(55)"
					( attribute "PN" "269"
						( Origin gPackager )
					)
					( objectStatus "J1G1.269" )
				)
				( pin "dq(56)"
					( attribute "PN" "130"
						( Origin gPackager )
					)
					( objectStatus "J1G1.130" )
				)
				( pin "dq(57)"
					( attribute "PN" "275"
						( Origin gPackager )
					)
					( objectStatus "J1G1.275" )
				)
				( pin "dq(58)"
					( attribute "PN" "137"
						( Origin gPackager )
					)
					( objectStatus "J1G1.137" )
				)
				( pin "dq(59)"
					( attribute "PN" "282"
						( Origin gPackager )
					)
					( objectStatus "J1G1.282" )
				)
				( pin "dq(60)"
					( attribute "PN" "128"
						( Origin gPackager )
					)
					( objectStatus "J1G1.128" )
				)
				( pin "dq(61)"
					( attribute "PN" "273"
						( Origin gPackager )
					)
					( objectStatus "J1G1.273" )
				)
				( pin "dq(62)"
					( attribute "PN" "135"
						( Origin gPackager )
					)
					( objectStatus "J1G1.135" )
				)
				( pin "dq(63)"
					( attribute "PN" "280"
						( Origin gPackager )
					)
					( objectStatus "J1G1.280" )
				)
				( pin "event_n"
					( attribute "PN" "78"
						( Origin gPackager )
					)
					( objectStatus "J1G1.78" )
				)
				( pin "odt(0)"
					( attribute "PN" "87"
						( Origin gPackager )
					)
					( objectStatus "J1G1.87" )
				)
				( pin "odt(1)"
					( attribute "PN" "91"
						( Origin gPackager )
					)
					( objectStatus "J1G1.91" )
				)
				( pin "par"
					( attribute "PN" "222"
						( Origin gPackager )
					)
					( objectStatus "J1G1.222" )
				)
				( pin "reset_n"
					( attribute "PN" "58"
						( Origin gPackager )
					)
					( objectStatus "J1G1.58" )
				)
				( pin "rfu(0)"
					( attribute "PN" "205"
						( Origin gPackager )
					)
					( objectStatus "J1G1.205" )
				)
				( pin "rfu(1)"
					( attribute "PN" "227"
						( Origin gPackager )
					)
					( objectStatus "J1G1.227" )
				)
				( pin "rfu(2)"
					( attribute "PN" "144"
						( Origin gPackager )
					)
					( objectStatus "J1G1.144" )
				)
				( pin "s0_n"
					( attribute "PN" "84"
						( Origin gPackager )
					)
					( objectStatus "J1G1.84" )
				)
				( pin "s1_n"
					( attribute "PN" "89"
						( Origin gPackager )
					)
					( objectStatus "J1G1.89" )
				)
				( pin "s2_n_c(0)"
					( attribute "PN" "93"
						( Origin gPackager )
					)
					( objectStatus "J1G1.93" )
				)
				( pin "s3_n_c(1)"
					( attribute "PN" "237"
						( Origin gPackager )
					)
					( objectStatus "J1G1.237" )
				)
				( pin "sa(0)"
					( attribute "PN" "139"
						( Origin gPackager )
					)
					( objectStatus "J1G1.139" )
				)
				( pin "sa(1)"
					( attribute "PN" "140"
						( Origin gPackager )
					)
					( objectStatus "J1G1.140" )
				)
				( pin "sa(2)"
					( attribute "PN" "238"
						( Origin gPackager )
					)
					( objectStatus "J1G1.238" )
				)
				( pin "save_n_nc"
					( attribute "PN" "230"
						( Origin gPackager )
					)
					( objectStatus "J1G1.230" )
				)
				( pin "scl"
					( attribute "PN" "141"
						( Origin gPackager )
					)
					( objectStatus "J1G1.141" )
				)
				( pin "sda"
					( attribute "PN" "285"
						( Origin gPackager )
					)
					( objectStatus "J1G1.285" )
				)
				( pin "vddspd"
					( attribute "PN" "284"
						( Origin gPackager )
					)
					( objectStatus "J1G1.284" )
				)
				( pin "vrefca"
					( attribute "PN" "146"
						( Origin gPackager )
					)
					( objectStatus "J1G1.146" )
				)
			)
			( gate "@baseboard_fab2_lib.baseboard_fab2(sch_1):page77_i171"
				( attribute "BOM_COST" "MEM"
					( Origin gFrontEnd )
				)
				( attribute "CDS_LIB" "mstr_sconn"
					( Origin gPackager )
				)
				( attribute "CDS_LOCATION" "J1G1"
					( Origin gPackager )
				)
				( attribute "CDS_SEC" "4"
					( Origin gPackager )
				)
				( attribute "LOCATION" "J1G1"
					( Origin gFrontEnd )
				)
				( attribute "MATERIAL" "SCONN"
					( Origin gFrontEnd )
				)
				( attribute "PACK_TYPE" "PIP"
					( Origin gFrontEnd )
				)
				( attribute "PART_NUMBER" "H44441-004"
					( Origin gFrontEnd )
				)
				( attribute "PHYS_PAGE" "77"
					( Origin gFrontEnd )
				)
				( attribute "ROOM" "DDR4_CH_G"
					( Origin gFrontEnd )
				)
				( attribute "ROT" "0"
					( Origin gFrontEnd )
				)
				( attribute "SEC" "4"
					( Origin gFrontEnd )
				)
				( attribute "SEC_TYPE" "PIP"
					( Origin gFrontEnd )
				)
				( attribute "VER" "4"
					( Origin gFrontEnd )
				)
				( attribute "XY" "(-300,1950)"
					( Origin gFrontEnd )
				)
				( attribute "CHIPS_PART_NAME" "SCONN288_H44441004"
					( Origin gPackager )
				)
				( attribute "CDS_PART_NAME" "SCONN288_H44441004_PIP-SCONN,HA"
					( Origin gPackager )
				)
				( objectStatus "J1G1" )
				( pin "\12v\(0)"
					( attribute "PN" "145"
						( Origin gPackager )
					)
					( objectStatus "J1G1.145" )
				)
				( pin "\12v\(1)"
					( attribute "PN" "1"
						( Origin gPackager )
					)
					( objectStatus "J1G1.1" )
				)
				( pin "vdd(0)"
					( attribute "PN" "236"
						( Origin gPackager )
					)
					( objectStatus "J1G1.236" )
				)
				( pin "vdd(1)"
					( attribute "PN" "233"
						( Origin gPackager )
					)
					( objectStatus "J1G1.233" )
				)
				( pin "vdd(2)"
					( attribute "PN" "231"
						( Origin gPackager )
					)
					( objectStatus "J1G1.231" )
				)
				( pin "vdd(3)"
					( attribute "PN" "229"
						( Origin gPackager )
					)
					( objectStatus "J1G1.229" )
				)
				( pin "vdd(4)"
					( attribute "PN" "226"
						( Origin gPackager )
					)
					( objectStatus "J1G1.226" )
				)
				( pin "vdd(5)"
					( attribute "PN" "223"
						( Origin gPackager )
					)
					( objectStatus "J1G1.223" )
				)
				( pin "vdd(6)"
					( attribute "PN" "220"
						( Origin gPackager )
					)
					( objectStatus "J1G1.220" )
				)
				( pin "vdd(7)"
					( attribute "PN" "217"
						( Origin gPackager )
					)
					( objectStatus "J1G1.217" )
				)
				( pin "vdd(8)"
					( attribute "PN" "215"
						( Origin gPackager )
					)
					( objectStatus "J1G1.215" )
				)
				( pin "vdd(9)"
					( attribute "PN" "212"
						( Origin gPackager )
					)
					( objectStatus "J1G1.212" )
				)
				( pin "vdd(10)"
					( attribute "PN" "209"
						( Origin gPackager )
					)
					( objectStatus "J1G1.209" )
				)
				( pin "vdd(11)"
					( attribute "PN" "206"
						( Origin gPackager )
					)
					( objectStatus "J1G1.206" )
				)
				( pin "vdd(12)"
					( attribute "PN" "204"
						( Origin gPackager )
					)
					( objectStatus "J1G1.204" )
				)
				( pin "vdd(13)"
					( attribute "PN" "92"
						( Origin gPackager )
					)
					( objectStatus "J1G1.92" )
				)
				( pin "vdd(14)"
					( attribute "PN" "90"
						( Origin gPackager )
					)
					( objectStatus "J1G1.90" )
				)
				( pin "vdd(15)"
					( attribute "PN" "88"
						( Origin gPackager )
					)
					( objectStatus "J1G1.88" )
				)
				( pin "vdd(16)"
					( attribute "PN" "85"
						( Origin gPackager )
					)
					( objectStatus "J1G1.85" )
				)
				( pin "vdd(17)"
					( attribute "PN" "83"
						( Origin gPackager )
					)
					( objectStatus "J1G1.83" )
				)
				( pin "vdd(18)"
					( attribute "PN" "80"
						( Origin gPackager )
					)
					( objectStatus "J1G1.80" )
				)
				( pin "vdd(19)"
					( attribute "PN" "76"
						( Origin gPackager )
					)
					( objectStatus "J1G1.76" )
				)
				( pin "vdd(20)"
					( attribute "PN" "73"
						( Origin gPackager )
					)
					( objectStatus "J1G1.73" )
				)
				( pin "vdd(21)"
					( attribute "PN" "70"
						( Origin gPackager )
					)
					( objectStatus "J1G1.70" )
				)
				( pin "vdd(22)"
					( attribute "PN" "67"
						( Origin gPackager )
					)
					( objectStatus "J1G1.67" )
				)
				( pin "vdd(23)"
					( attribute "PN" "64"
						( Origin gPackager )
					)
					( objectStatus "J1G1.64" )
				)
				( pin "vdd(24)"
					( attribute "PN" "61"
						( Origin gPackager )
					)
					( objectStatus "J1G1.61" )
				)
				( pin "vdd(25)"
					( attribute "PN" "59"
						( Origin gPackager )
					)
					( objectStatus "J1G1.59" )
				)
				( pin "vpp(0)"
					( attribute "PN" "287"
						( Origin gPackager )
					)
					( objectStatus "J1G1.287" )
				)
				( pin "vpp(1)"
					( attribute "PN" "286"
						( Origin gPackager )
					)
					( objectStatus "J1G1.286" )
				)
				( pin "vpp(2)"
					( attribute "PN" "288"
						( Origin gPackager )
					)
					( objectStatus "J1G1.288" )
				)
				( pin "vpp(3)"
					( attribute "PN" "143"
						( Origin gPackager )
					)
					( objectStatus "J1G1.143" )
				)
				( pin "vpp(4)"
					( attribute "PN" "142"
						( Origin gPackager )
					)
					( objectStatus "J1G1.142" )
				)
				( pin "vtt(0)"
					( attribute "PN" "221"
						( Origin gPackager )
					)
					( objectStatus "J1G1.221" )
				)
				( pin "vtt(1)"
					( attribute "PN" "77"
						( Origin gPackager )
					)
					( objectStatus "J1G1.77" )
				)
			)
			( gate "@baseboard_fab2_lib.baseboard_fab2(sch_1):page77_i181"
				( attribute "BOM_COST" "MEM"
					( Origin gFrontEnd )
				)
				( attribute "CDS_LIB" "dev_discrete"
					( Origin gPackager )
				)
				( attribute "CDS_LOCATION" "C1F22"
					( Origin gPackager )
				)
				( attribute "CDS_SEC" "1"
					( Origin gPackager )
				)
				( attribute "LOCATION" "C1F22"
					( Origin gFrontEnd )
				)
				( attribute "MATERIAL" "X7R"
					( Origin gFrontEnd )
				)
				( attribute "PACK_TYPE" "0402V"
					( Origin gFrontEnd )
				)
				( attribute "PART_NUMBER" "A36096-045"
					( Origin gFrontEnd )
				)
				( attribute "PHYS_PAGE" "77"
					( Origin gFrontEnd )
				)
				( attribute "ROOM" "DDR4_CH_G"
					( Origin gFrontEnd )
				)
				( attribute "ROT" "2"
					( Origin gFrontEnd )
				)
				( attribute "SEC" "1"
					( Origin gPackager )
				)
				( attribute "TOLERANCE" "10%"
					( Origin gFrontEnd )
				)
				( attribute "VALUE" "0.01UF"
					( Origin gFrontEnd )
				)
				( attribute "VER" "1"
					( Origin gFrontEnd )
				)
				( attribute "VOLTAGE" "25V"
					( Units "uVoltage" "V" 1.000000)
					( Origin gFrontEnd )
				)
				( attribute "XY" "(-4425,1075)"
					( Origin gFrontEnd )
				)
				( attribute "CHIPS_PART_NAME" "CAP_A"
					( Origin gPackager )
				)
				( attribute "CDS_PART_NAME" "CAP_A_0402V-0.01UF,25V,10%,X7RA"
					( Origin gPackager )
				)
				( objectStatus "C1F22" )
				( pin "a"
					( attribute "PN" "1"
						( Origin gPackager )
					)
					( objectStatus "C1F22.1" )
				)
				( pin "b"
					( attribute "PN" "2"
						( Origin gPackager )
					)
					( objectStatus "C1F22.2" )
				)
			)
			( gate "@baseboard_fab2_lib.baseboard_fab2(sch_1):page78_i2"
				( attribute "BOM_COST" "MEM"
					( Origin gFrontEnd )
				)
				( attribute "CDS_LIB" "dev_discrete"
					( Origin gPackager )
				)
				( attribute "CDS_LOCATION" "C9T7"
					( Origin gPackager )
				)
				( attribute "CDS_SEC" "1"
					( Origin gPackager )
				)
				( attribute "LOCATION" "C9T7"
					( Origin gFrontEnd )
				)
				( attribute "MATERIAL" "X7R"
					( Origin gFrontEnd )
				)
				( attribute "PACK_TYPE" "0402V"
					( Origin gFrontEnd )
				)
				( attribute "PART_NUMBER" "A36096-045"
					( Origin gFrontEnd )
				)
				( attribute "PHYS_PAGE" "78"
					( Origin gFrontEnd )
				)
				( attribute "ROOM" "DDR4_GH_G"
					( Origin gFrontEnd )
				)
				( attribute "ROT" "2"
					( Origin gFrontEnd )
				)
				( attribute "SEC" "1"
					( Origin gPackager )
				)
				( attribute "TOLERANCE" "10%"
					( Origin gFrontEnd )
				)
				( attribute "VALUE" "0.01UF"
					( Origin gFrontEnd )
				)
				( attribute "VER" "1"
					( Origin gFrontEnd )
				)
				( attribute "VOLTAGE" "25V"
					( Units "uVoltage" "V" 1.000000)
					( Origin gFrontEnd )
				)
				( attribute "XY" "(-2675,875)"
					( Origin gFrontEnd )
				)
				( attribute "CHIPS_PART_NAME" "CAP_A"
					( Origin gPackager )
				)
				( attribute "CDS_PART_NAME" "CAP_A_0402V-0.01UF,25V,10%,X7RA"
					( Origin gPackager )
				)
				( objectStatus "C9T7" )
				( pin "a"
					( attribute "PN" "1"
						( Origin gPackager )
					)
					( objectStatus "C9T7.1" )
				)
				( pin "b"
					( attribute "PN" "2"
						( Origin gPackager )
					)
					( objectStatus "C9T7.2" )
				)
			)
			( gate "@baseboard_fab2_lib.baseboard_fab2(sch_1):page78_i13"
				( attribute "BOM_COST" "MEM"
					( Origin gFrontEnd )
				)
				( attribute "CDS_LIB" "mstr_sconn"
					( Origin gPackager )
				)
				( attribute "CDS_LOCATION" "J9T1"
					( Origin gPackager )
				)
				( attribute "CDS_SEC" "1"
					( Origin gPackager )
				)
				( attribute "LOCATION" "J9T1"
					( Origin gFrontEnd )
				)
				( attribute "MATERIAL" "SCONN"
					( Origin gFrontEnd )
				)
				( attribute "PACK_TYPE" "PIP"
					( Origin gFrontEnd )
				)
				( attribute "PART_NUMBER" "H44441-003"
					( Origin gFrontEnd )
				)
				( attribute "PHYS_PAGE" "78"
					( Origin gFrontEnd )
				)
				( attribute "ROOM" "DDR4_GH_G"
					( Origin gFrontEnd )
				)
				( attribute "ROT" "0"
					( Origin gFrontEnd )
				)
				( attribute "SEC" "1"
					( Origin gFrontEnd )
				)
				( attribute "SEC_TYPE" "PIP"
					( Origin gFrontEnd )
				)
				( attribute "VER" "1"
					( Origin gFrontEnd )
				)
				( attribute "XY" "(-625,2575)"
					( Origin gFrontEnd )
				)
				( attribute "CHIPS_PART_NAME" "SCONN288_H44441003"
					( Origin gPackager )
				)
				( attribute "CDS_PART_NAME" "SCONN288_H44441003_PIP-SCONN,HA"
					( Origin gPackager )
				)
				( objectStatus "J9T1" )
				( pin "a0"
					( attribute "PN" "79"
						( Origin gPackager )
					)
					( objectStatus "J9T1.79" )
				)
				( pin "a1"
					( attribute "PN" "72"
						( Origin gPackager )
					)
					( objectStatus "J9T1.72" )
				)
				( pin "a2"
					( attribute "PN" "216"
						( Origin gPackager )
					)
					( objectStatus "J9T1.216" )
				)
				( pin "a3"
					( attribute "PN" "71"
						( Origin gPackager )
					)
					( objectStatus "J9T1.71" )
				)
				( pin "a4"
					( attribute "PN" "214"
						( Origin gPackager )
					)
					( objectStatus "J9T1.214" )
				)
				( pin "a5"
					( attribute "PN" "213"
						( Origin gPackager )
					)
					( objectStatus "J9T1.213" )
				)
				( pin "a6"
					( attribute "PN" "69"
						( Origin gPackager )
					)
					( objectStatus "J9T1.69" )
				)
				( pin "a7"
					( attribute "PN" "211"
						( Origin gPackager )
					)
					( objectStatus "J9T1.211" )
				)
				( pin "a8"
					( attribute "PN" "68"
						( Origin gPackager )
					)
					( objectStatus "J9T1.68" )
				)
				( pin "a9"
					( attribute "PN" "66"
						( Origin gPackager )
					)
					( objectStatus "J9T1.66" )
				)
				( pin "a10"
					( attribute "PN" "225"
						( Origin gPackager )
					)
					( objectStatus "J9T1.225" )
				)
				( pin "a11"
					( attribute "PN" "210"
						( Origin gPackager )
					)
					( objectStatus "J9T1.210" )
				)
				( pin "a12"
					( attribute "PN" "65"
						( Origin gPackager )
					)
					( objectStatus "J9T1.65" )
				)
				( pin "a13"
					( attribute "PN" "232"
						( Origin gPackager )
					)
					( objectStatus "J9T1.232" )
				)
				( pin "a14_we_n"
					( attribute "PN" "228"
						( Origin gPackager )
					)
					( objectStatus "J9T1.228" )
				)
				( pin "a15_cas_n"
					( attribute "PN" "86"
						( Origin gPackager )
					)
					( objectStatus "J9T1.86" )
				)
				( pin "a16_ras_n"
					( attribute "PN" "82"
						( Origin gPackager )
					)
					( objectStatus "J9T1.82" )
				)
				( pin "a17"
					( attribute "PN" "234"
						( Origin gPackager )
					)
					( objectStatus "J9T1.234" )
				)
				( pin "act_n"
					( attribute "PN" "62"
						( Origin gPackager )
					)
					( objectStatus "J9T1.62" )
				)
				( pin "alert_n"
					( attribute "PN" "208"
						( Origin gPackager )
					)
					( objectStatus "J9T1.208" )
				)
				( pin "ba(0)"
					( attribute "PN" "81"
						( Origin gPackager )
					)
					( objectStatus "J9T1.81" )
				)
				( pin "ba(1)"
					( attribute "PN" "224"
						( Origin gPackager )
					)
					( objectStatus "J9T1.224" )
				)
				( pin "bg(0)"
					( attribute "PN" "63"
						( Origin gPackager )
					)
					( objectStatus "J9T1.63" )
				)
				( pin "bg(1)"
					( attribute "PN" "207"
						( Origin gPackager )
					)
					( objectStatus "J9T1.207" )
				)
				( pin "c(2)"
					( attribute "PN" "235"
						( Origin gPackager )
					)
					( objectStatus "J9T1.235" )
				)
				( pin "cb(0)"
					( attribute "PN" "49"
						( Origin gPackager )
					)
					( objectStatus "J9T1.49" )
				)
				( pin "cb(1)"
					( attribute "PN" "194"
						( Origin gPackager )
					)
					( objectStatus "J9T1.194" )
				)
				( pin "cb(2)"
					( attribute "PN" "56"
						( Origin gPackager )
					)
					( objectStatus "J9T1.56" )
				)
				( pin "cb(3)"
					( attribute "PN" "201"
						( Origin gPackager )
					)
					( objectStatus "J9T1.201" )
				)
				( pin "cb(4)"
					( attribute "PN" "47"
						( Origin gPackager )
					)
					( objectStatus "J9T1.47" )
				)
				( pin "cb(5)"
					( attribute "PN" "192"
						( Origin gPackager )
					)
					( objectStatus "J9T1.192" )
				)
				( pin "cb(6)"
					( attribute "PN" "54"
						( Origin gPackager )
					)
					( objectStatus "J9T1.54" )
				)
				( pin "cb(7)"
					( attribute "PN" "199"
						( Origin gPackager )
					)
					( objectStatus "J9T1.199" )
				)
				( pin "ck0n"
					( attribute "PN" "75"
						( Origin gPackager )
					)
					( objectStatus "J9T1.75" )
				)
				( pin "ck0p"
					( attribute "PN" "74"
						( Origin gPackager )
					)
					( objectStatus "J9T1.74" )
				)
				( pin "ck1n"
					( attribute "PN" "219"
						( Origin gPackager )
					)
					( objectStatus "J9T1.219" )
				)
				( pin "ck1p"
					( attribute "PN" "218"
						( Origin gPackager )
					)
					( objectStatus "J9T1.218" )
				)
				( pin "cke(0)"
					( attribute "PN" "60"
						( Origin gPackager )
					)
					( objectStatus "J9T1.60" )
				)
				( pin "cke(1)"
					( attribute "PN" "203"
						( Origin gPackager )
					)
					( objectStatus "J9T1.203" )
				)
				( pin "dq(0)"
					( attribute "PN" "5"
						( Origin gPackager )
					)
					( objectStatus "J9T1.5" )
				)
				( pin "dq(1)"
					( attribute "PN" "150"
						( Origin gPackager )
					)
					( objectStatus "J9T1.150" )
				)
				( pin "dq(2)"
					( attribute "PN" "12"
						( Origin gPackager )
					)
					( objectStatus "J9T1.12" )
				)
				( pin "dq(3)"
					( attribute "PN" "157"
						( Origin gPackager )
					)
					( objectStatus "J9T1.157" )
				)
				( pin "dq(4)"
					( attribute "PN" "3"
						( Origin gPackager )
					)
					( objectStatus "J9T1.3" )
				)
				( pin "dq(5)"
					( attribute "PN" "148"
						( Origin gPackager )
					)
					( objectStatus "J9T1.148" )
				)
				( pin "dq(6)"
					( attribute "PN" "10"
						( Origin gPackager )
					)
					( objectStatus "J9T1.10" )
				)
				( pin "dq(7)"
					( attribute "PN" "155"
						( Origin gPackager )
					)
					( objectStatus "J9T1.155" )
				)
				( pin "dq(8)"
					( attribute "PN" "16"
						( Origin gPackager )
					)
					( objectStatus "J9T1.16" )
				)
				( pin "dq(9)"
					( attribute "PN" "161"
						( Origin gPackager )
					)
					( objectStatus "J9T1.161" )
				)
				( pin "dq(10)"
					( attribute "PN" "23"
						( Origin gPackager )
					)
					( objectStatus "J9T1.23" )
				)
				( pin "dq(11)"
					( attribute "PN" "168"
						( Origin gPackager )
					)
					( objectStatus "J9T1.168" )
				)
				( pin "dq(12)"
					( attribute "PN" "14"
						( Origin gPackager )
					)
					( objectStatus "J9T1.14" )
				)
				( pin "dq(13)"
					( attribute "PN" "159"
						( Origin gPackager )
					)
					( objectStatus "J9T1.159" )
				)
				( pin "dq(14)"
					( attribute "PN" "21"
						( Origin gPackager )
					)
					( objectStatus "J9T1.21" )
				)
				( pin "dq(15)"
					( attribute "PN" "166"
						( Origin gPackager )
					)
					( objectStatus "J9T1.166" )
				)
				( pin "dq(16)"
					( attribute "PN" "27"
						( Origin gPackager )
					)
					( objectStatus "J9T1.27" )
				)
				( pin "dq(17)"
					( attribute "PN" "172"
						( Origin gPackager )
					)
					( objectStatus "J9T1.172" )
				)
				( pin "dq(18)"
					( attribute "PN" "34"
						( Origin gPackager )
					)
					( objectStatus "J9T1.34" )
				)
				( pin "dq(19)"
					( attribute "PN" "179"
						( Origin gPackager )
					)
					( objectStatus "J9T1.179" )
				)
				( pin "dq(20)"
					( attribute "PN" "25"
						( Origin gPackager )
					)
					( objectStatus "J9T1.25" )
				)
				( pin "dq(21)"
					( attribute "PN" "170"
						( Origin gPackager )
					)
					( objectStatus "J9T1.170" )
				)
				( pin "dq(22)"
					( attribute "PN" "32"
						( Origin gPackager )
					)
					( objectStatus "J9T1.32" )
				)
				( pin "dq(23)"
					( attribute "PN" "177"
						( Origin gPackager )
					)
					( objectStatus "J9T1.177" )
				)
				( pin "dq(24)"
					( attribute "PN" "38"
						( Origin gPackager )
					)
					( objectStatus "J9T1.38" )
				)
				( pin "dq(25)"
					( attribute "PN" "183"
						( Origin gPackager )
					)
					( objectStatus "J9T1.183" )
				)
				( pin "dq(26)"
					( attribute "PN" "45"
						( Origin gPackager )
					)
					( objectStatus "J9T1.45" )
				)
				( pin "dq(27)"
					( attribute "PN" "190"
						( Origin gPackager )
					)
					( objectStatus "J9T1.190" )
				)
				( pin "dq(28)"
					( attribute "PN" "36"
						( Origin gPackager )
					)
					( objectStatus "J9T1.36" )
				)
				( pin "dq(29)"
					( attribute "PN" "181"
						( Origin gPackager )
					)
					( objectStatus "J9T1.181" )
				)
				( pin "dq(30)"
					( attribute "PN" "43"
						( Origin gPackager )
					)
					( objectStatus "J9T1.43" )
				)
				( pin "dq(31)"
					( attribute "PN" "188"
						( Origin gPackager )
					)
					( objectStatus "J9T1.188" )
				)
				( pin "dq(32)"
					( attribute "PN" "97"
						( Origin gPackager )
					)
					( objectStatus "J9T1.97" )
				)
				( pin "dq(33)"
					( attribute "PN" "242"
						( Origin gPackager )
					)
					( objectStatus "J9T1.242" )
				)
				( pin "dq(34)"
					( attribute "PN" "104"
						( Origin gPackager )
					)
					( objectStatus "J9T1.104" )
				)
				( pin "dq(35)"
					( attribute "PN" "249"
						( Origin gPackager )
					)
					( objectStatus "J9T1.249" )
				)
				( pin "dq(36)"
					( attribute "PN" "95"
						( Origin gPackager )
					)
					( objectStatus "J9T1.95" )
				)
				( pin "dq(37)"
					( attribute "PN" "240"
						( Origin gPackager )
					)
					( objectStatus "J9T1.240" )
				)
				( pin "dq(38)"
					( attribute "PN" "102"
						( Origin gPackager )
					)
					( objectStatus "J9T1.102" )
				)
				( pin "dq(39)"
					( attribute "PN" "247"
						( Origin gPackager )
					)
					( objectStatus "J9T1.247" )
				)
				( pin "dq(40)"
					( attribute "PN" "108"
						( Origin gPackager )
					)
					( objectStatus "J9T1.108" )
				)
				( pin "dq(41)"
					( attribute "PN" "253"
						( Origin gPackager )
					)
					( objectStatus "J9T1.253" )
				)
				( pin "dq(42)"
					( attribute "PN" "115"
						( Origin gPackager )
					)
					( objectStatus "J9T1.115" )
				)
				( pin "dq(43)"
					( attribute "PN" "260"
						( Origin gPackager )
					)
					( objectStatus "J9T1.260" )
				)
				( pin "dq(44)"
					( attribute "PN" "106"
						( Origin gPackager )
					)
					( objectStatus "J9T1.106" )
				)
				( pin "dq(45)"
					( attribute "PN" "251"
						( Origin gPackager )
					)
					( objectStatus "J9T1.251" )
				)
				( pin "dq(46)"
					( attribute "PN" "113"
						( Origin gPackager )
					)
					( objectStatus "J9T1.113" )
				)
				( pin "dq(47)"
					( attribute "PN" "258"
						( Origin gPackager )
					)
					( objectStatus "J9T1.258" )
				)
				( pin "dq(48)"
					( attribute "PN" "119"
						( Origin gPackager )
					)
					( objectStatus "J9T1.119" )
				)
				( pin "dq(49)"
					( attribute "PN" "264"
						( Origin gPackager )
					)
					( objectStatus "J9T1.264" )
				)
				( pin "dq(50)"
					( attribute "PN" "126"
						( Origin gPackager )
					)
					( objectStatus "J9T1.126" )
				)
				( pin "dq(51)"
					( attribute "PN" "271"
						( Origin gPackager )
					)
					( objectStatus "J9T1.271" )
				)
				( pin "dq(52)"
					( attribute "PN" "117"
						( Origin gPackager )
					)
					( objectStatus "J9T1.117" )
				)
				( pin "dq(53)"
					( attribute "PN" "262"
						( Origin gPackager )
					)
					( objectStatus "J9T1.262" )
				)
				( pin "dq(54)"
					( attribute "PN" "124"
						( Origin gPackager )
					)
					( objectStatus "J9T1.124" )
				)
				( pin "dq(55)"
					( attribute "PN" "269"
						( Origin gPackager )
					)
					( objectStatus "J9T1.269" )
				)
				( pin "dq(56)"
					( attribute "PN" "130"
						( Origin gPackager )
					)
					( objectStatus "J9T1.130" )
				)
				( pin "dq(57)"
					( attribute "PN" "275"
						( Origin gPackager )
					)
					( objectStatus "J9T1.275" )
				)
				( pin "dq(58)"
					( attribute "PN" "137"
						( Origin gPackager )
					)
					( objectStatus "J9T1.137" )
				)
				( pin "dq(59)"
					( attribute "PN" "282"
						( Origin gPackager )
					)
					( objectStatus "J9T1.282" )
				)
				( pin "dq(60)"
					( attribute "PN" "128"
						( Origin gPackager )
					)
					( objectStatus "J9T1.128" )
				)
				( pin "dq(61)"
					( attribute "PN" "273"
						( Origin gPackager )
					)
					( objectStatus "J9T1.273" )
				)
				( pin "dq(62)"
					( attribute "PN" "135"
						( Origin gPackager )
					)
					( objectStatus "J9T1.135" )
				)
				( pin "dq(63)"
					( attribute "PN" "280"
						( Origin gPackager )
					)
					( objectStatus "J9T1.280" )
				)
				( pin "event_n"
					( attribute "PN" "78"
						( Origin gPackager )
					)
					( objectStatus "J9T1.78" )
				)
				( pin "odt(0)"
					( attribute "PN" "87"
						( Origin gPackager )
					)
					( objectStatus "J9T1.87" )
				)
				( pin "odt(1)"
					( attribute "PN" "91"
						( Origin gPackager )
					)
					( objectStatus "J9T1.91" )
				)
				( pin "par"
					( attribute "PN" "222"
						( Origin gPackager )
					)
					( objectStatus "J9T1.222" )
				)
				( pin "reset_n"
					( attribute "PN" "58"
						( Origin gPackager )
					)
					( objectStatus "J9T1.58" )
				)
				( pin "rfu(0)"
					( attribute "PN" "205"
						( Origin gPackager )
					)
					( objectStatus "J9T1.205" )
				)
				( pin "rfu(1)"
					( attribute "PN" "227"
						( Origin gPackager )
					)
					( objectStatus "J9T1.227" )
				)
				( pin "rfu(2)"
					( attribute "PN" "144"
						( Origin gPackager )
					)
					( objectStatus "J9T1.144" )
				)
				( pin "s0_n"
					( attribute "PN" "84"
						( Origin gPackager )
					)
					( objectStatus "J9T1.84" )
				)
				( pin "s1_n"
					( attribute "PN" "89"
						( Origin gPackager )
					)
					( objectStatus "J9T1.89" )
				)
				( pin "s2_n_c(0)"
					( attribute "PN" "93"
						( Origin gPackager )
					)
					( objectStatus "J9T1.93" )
				)
				( pin "s3_n_c(1)"
					( attribute "PN" "237"
						( Origin gPackager )
					)
					( objectStatus "J9T1.237" )
				)
				( pin "sa(0)"
					( attribute "PN" "139"
						( Origin gPackager )
					)
					( objectStatus "J9T1.139" )
				)
				( pin "sa(1)"
					( attribute "PN" "140"
						( Origin gPackager )
					)
					( objectStatus "J9T1.140" )
				)
				( pin "sa(2)"
					( attribute "PN" "238"
						( Origin gPackager )
					)
					( objectStatus "J9T1.238" )
				)
				( pin "save_n_nc"
					( attribute "PN" "230"
						( Origin gPackager )
					)
					( objectStatus "J9T1.230" )
				)
				( pin "scl"
					( attribute "PN" "141"
						( Origin gPackager )
					)
					( objectStatus "J9T1.141" )
				)
				( pin "sda"
					( attribute "PN" "285"
						( Origin gPackager )
					)
					( objectStatus "J9T1.285" )
				)
				( pin "vddspd"
					( attribute "PN" "284"
						( Origin gPackager )
					)
					( objectStatus "J9T1.284" )
				)
				( pin "vrefca"
					( attribute "PN" "146"
						( Origin gPackager )
					)
					( objectStatus "J9T1.146" )
				)
			)
			( gate "@baseboard_fab2_lib.baseboard_fab2(sch_1):page78_i75"
				( attribute "BOM_COST" "MEM"
					( Origin gFrontEnd )
				)
				( attribute "CDS_LIB" "mstr_sconn"
					( Origin gPackager )
				)
				( attribute "CDS_LOCATION" "J9T1"
					( Origin gPackager )
				)
				( attribute "CDS_SEC" "4"
					( Origin gPackager )
				)
				( attribute "LOCATION" "J9T1"
					( Origin gFrontEnd )
				)
				( attribute "MATERIAL" "SCONN"
					( Origin gFrontEnd )
				)
				( attribute "PACK_TYPE" "PIP"
					( Origin gFrontEnd )
				)
				( attribute "PART_NUMBER" "H44441-003"
					( Origin gFrontEnd )
				)
				( attribute "PHYS_PAGE" "78"
					( Origin gFrontEnd )
				)
				( attribute "ROOM" "DDR4_GH_G"
					( Origin gFrontEnd )
				)
				( attribute "ROT" "0"
					( Origin gFrontEnd )
				)
				( attribute "SEC" "4"
					( Origin gFrontEnd )
				)
				( attribute "SEC_TYPE" "PIP"
					( Origin gFrontEnd )
				)
				( attribute "VER" "4"
					( Origin gFrontEnd )
				)
				( attribute "XY" "(1450,1750)"
					( Origin gFrontEnd )
				)
				( attribute "CHIPS_PART_NAME" "SCONN288_H44441003"
					( Origin gPackager )
				)
				( attribute "CDS_PART_NAME" "SCONN288_H44441003_PIP-SCONN,HA"
					( Origin gPackager )
				)
				( objectStatus "J9T1" )
				( pin "\12v\(0)"
					( attribute "PN" "145"
						( Origin gPackager )
					)
					( objectStatus "J9T1.145" )
				)
				( pin "\12v\(1)"
					( attribute "PN" "1"
						( Origin gPackager )
					)
					( objectStatus "J9T1.1" )
				)
				( pin "vdd(0)"
					( attribute "PN" "236"
						( Origin gPackager )
					)
					( objectStatus "J9T1.236" )
				)
				( pin "vdd(1)"
					( attribute "PN" "233"
						( Origin gPackager )
					)
					( objectStatus "J9T1.233" )
				)
				( pin "vdd(2)"
					( attribute "PN" "231"
						( Origin gPackager )
					)
					( objectStatus "J9T1.231" )
				)
				( pin "vdd(3)"
					( attribute "PN" "229"
						( Origin gPackager )
					)
					( objectStatus "J9T1.229" )
				)
				( pin "vdd(4)"
					( attribute "PN" "226"
						( Origin gPackager )
					)
					( objectStatus "J9T1.226" )
				)
				( pin "vdd(5)"
					( attribute "PN" "223"
						( Origin gPackager )
					)
					( objectStatus "J9T1.223" )
				)
				( pin "vdd(6)"
					( attribute "PN" "220"
						( Origin gPackager )
					)
					( objectStatus "J9T1.220" )
				)
				( pin "vdd(7)"
					( attribute "PN" "217"
						( Origin gPackager )
					)
					( objectStatus "J9T1.217" )
				)
				( pin "vdd(8)"
					( attribute "PN" "215"
						( Origin gPackager )
					)
					( objectStatus "J9T1.215" )
				)
				( pin "vdd(9)"
					( attribute "PN" "212"
						( Origin gPackager )
					)
					( objectStatus "J9T1.212" )
				)
				( pin "vdd(10)"
					( attribute "PN" "209"
						( Origin gPackager )
					)
					( objectStatus "J9T1.209" )
				)
				( pin "vdd(11)"
					( attribute "PN" "206"
						( Origin gPackager )
					)
					( objectStatus "J9T1.206" )
				)
				( pin "vdd(12)"
					( attribute "PN" "204"
						( Origin gPackager )
					)
					( objectStatus "J9T1.204" )
				)
				( pin "vdd(13)"
					( attribute "PN" "92"
						( Origin gPackager )
					)
					( objectStatus "J9T1.92" )
				)
				( pin "vdd(14)"
					( attribute "PN" "90"
						( Origin gPackager )
					)
					( objectStatus "J9T1.90" )
				)
				( pin "vdd(15)"
					( attribute "PN" "88"
						( Origin gPackager )
					)
					( objectStatus "J9T1.88" )
				)
				( pin "vdd(16)"
					( attribute "PN" "85"
						( Origin gPackager )
					)
					( objectStatus "J9T1.85" )
				)
				( pin "vdd(17)"
					( attribute "PN" "83"
						( Origin gPackager )
					)
					( objectStatus "J9T1.83" )
				)
				( pin "vdd(18)"
					( attribute "PN" "80"
						( Origin gPackager )
					)
					( objectStatus "J9T1.80" )
				)
				( pin "vdd(19)"
					( attribute "PN" "76"
						( Origin gPackager )
					)
					( objectStatus "J9T1.76" )
				)
				( pin "vdd(20)"
					( attribute "PN" "73"
						( Origin gPackager )
					)
					( objectStatus "J9T1.73" )
				)
				( pin "vdd(21)"
					( attribute "PN" "70"
						( Origin gPackager )
					)
					( objectStatus "J9T1.70" )
				)
				( pin "vdd(22)"
					( attribute "PN" "67"
						( Origin gPackager )
					)
					( objectStatus "J9T1.67" )
				)
				( pin "vdd(23)"
					( attribute "PN" "64"
						( Origin gPackager )
					)
					( objectStatus "J9T1.64" )
				)
				( pin "vdd(24)"
					( attribute "PN" "61"
						( Origin gPackager )
					)
					( objectStatus "J9T1.61" )
				)
				( pin "vdd(25)"
					( attribute "PN" "59"
						( Origin gPackager )
					)
					( objectStatus "J9T1.59" )
				)
				( pin "vpp(0)"
					( attribute "PN" "287"
						( Origin gPackager )
					)
					( objectStatus "J9T1.287" )
				)
				( pin "vpp(1)"
					( attribute "PN" "286"
						( Origin gPackager )
					)
					( objectStatus "J9T1.286" )
				)
				( pin "vpp(2)"
					( attribute "PN" "288"
						( Origin gPackager )
					)
					( objectStatus "J9T1.288" )
				)
				( pin "vpp(3)"
					( attribute "PN" "143"
						( Origin gPackager )
					)
					( objectStatus "J9T1.143" )
				)
				( pin "vpp(4)"
					( attribute "PN" "142"
						( Origin gPackager )
					)
					( objectStatus "J9T1.142" )
				)
				( pin "vtt(0)"
					( attribute "PN" "221"
						( Origin gPackager )
					)
					( objectStatus "J9T1.221" )
				)
				( pin "vtt(1)"
					( attribute "PN" "77"
						( Origin gPackager )
					)
					( objectStatus "J9T1.77" )
				)
			)
			( gate "@baseboard_fab2_lib.baseboard_fab2(sch_1):page78_i120"
				( attribute "BOM_COST" "MEM"
					( Origin gFrontEnd )
				)
				( attribute "CDS_LIB" "mstr_sconn"
					( Origin gPackager )
				)
				( attribute "CDS_LOCATION" "J9T1"
					( Origin gPackager )
				)
				( attribute "CDS_SEC" "2"
					( Origin gPackager )
				)
				( attribute "LOCATION" "J9T1"
					( Origin gFrontEnd )
				)
				( attribute "MATERIAL" "SCONN"
					( Origin gFrontEnd )
				)
				( attribute "PACK_TYPE" "PIP"
					( Origin gFrontEnd )
				)
				( attribute "PART_NUMBER" "H44441-003"
					( Origin gFrontEnd )
				)
				( attribute "PHYS_PAGE" "78"
					( Origin gFrontEnd )
				)
				( attribute "ROOM" "DDR4_GH_G"
					( Origin gFrontEnd )
				)
				( attribute "ROT" "0"
					( Origin gFrontEnd )
				)
				( attribute "SEC" "2"
					( Origin gFrontEnd )
				)
				( attribute "SEC_TYPE" "PIP"
					( Origin gFrontEnd )
				)
				( attribute "VER" "2"
					( Origin gFrontEnd )
				)
				( attribute "XY" "(1750,4000)"
					( Origin gFrontEnd )
				)
				( attribute "CHIPS_PART_NAME" "SCONN288_H44441003"
					( Origin gPackager )
				)
				( attribute "CDS_PART_NAME" "SCONN288_H44441003_PIP-SCONN,HA"
					( Origin gPackager )
				)
				( objectStatus "J9T1" )
				( pin "dqs0n"
					( attribute "PN" "152"
						( Origin gPackager )
					)
					( objectStatus "J9T1.152" )
				)
				( pin "dqs0p"
					( attribute "PN" "153"
						( Origin gPackager )
					)
					( objectStatus "J9T1.153" )
				)
				( pin "dqs1n"
					( attribute "PN" "163"
						( Origin gPackager )
					)
					( objectStatus "J9T1.163" )
				)
				( pin "dqs1p"
					( attribute "PN" "164"
						( Origin gPackager )
					)
					( objectStatus "J9T1.164" )
				)
				( pin "dqs2n"
					( attribute "PN" "174"
						( Origin gPackager )
					)
					( objectStatus "J9T1.174" )
				)
				( pin "dqs2p"
					( attribute "PN" "175"
						( Origin gPackager )
					)
					( objectStatus "J9T1.175" )
				)
				( pin "dqs3n"
					( attribute "PN" "185"
						( Origin gPackager )
					)
					( objectStatus "J9T1.185" )
				)
				( pin "dqs3p"
					( attribute "PN" "186"
						( Origin gPackager )
					)
					( objectStatus "J9T1.186" )
				)
				( pin "dqs4n"
					( attribute "PN" "244"
						( Origin gPackager )
					)
					( objectStatus "J9T1.244" )
				)
				( pin "dqs4p"
					( attribute "PN" "245"
						( Origin gPackager )
					)
					( objectStatus "J9T1.245" )
				)
				( pin "dqs5n"
					( attribute "PN" "255"
						( Origin gPackager )
					)
					( objectStatus "J9T1.255" )
				)
				( pin "dqs5p"
					( attribute "PN" "256"
						( Origin gPackager )
					)
					( objectStatus "J9T1.256" )
				)
				( pin "dqs6n"
					( attribute "PN" "266"
						( Origin gPackager )
					)
					( objectStatus "J9T1.266" )
				)
				( pin "dqs6p"
					( attribute "PN" "267"
						( Origin gPackager )
					)
					( objectStatus "J9T1.267" )
				)
				( pin "dqs7n"
					( attribute "PN" "277"
						( Origin gPackager )
					)
					( objectStatus "J9T1.277" )
				)
				( pin "dqs7p"
					( attribute "PN" "278"
						( Origin gPackager )
					)
					( objectStatus "J9T1.278" )
				)
				( pin "dqs8n"
					( attribute "PN" "196"
						( Origin gPackager )
					)
					( objectStatus "J9T1.196" )
				)
				( pin "dqs8p"
					( attribute "PN" "197"
						( Origin gPackager )
					)
					( objectStatus "J9T1.197" )
				)
				( pin "dqs9n"
					( attribute "PN" "8"
						( Origin gPackager )
					)
					( objectStatus "J9T1.8" )
				)
				( pin "dqs9p"
					( attribute "PN" "7"
						( Origin gPackager )
					)
					( objectStatus "J9T1.7" )
				)
				( pin "dqs10n"
					( attribute "PN" "19"
						( Origin gPackager )
					)
					( objectStatus "J9T1.19" )
				)
				( pin "dqs10p"
					( attribute "PN" "18"
						( Origin gPackager )
					)
					( objectStatus "J9T1.18" )
				)
				( pin "dqs11n"
					( attribute "PN" "30"
						( Origin gPackager )
					)
					( objectStatus "J9T1.30" )
				)
				( pin "dqs11p"
					( attribute "PN" "29"
						( Origin gPackager )
					)
					( objectStatus "J9T1.29" )
				)
				( pin "dqs12n"
					( attribute "PN" "41"
						( Origin gPackager )
					)
					( objectStatus "J9T1.41" )
				)
				( pin "dqs12p"
					( attribute "PN" "40"
						( Origin gPackager )
					)
					( objectStatus "J9T1.40" )
				)
				( pin "dqs13n"
					( attribute "PN" "100"
						( Origin gPackager )
					)
					( objectStatus "J9T1.100" )
				)
				( pin "dqs13p"
					( attribute "PN" "99"
						( Origin gPackager )
					)
					( objectStatus "J9T1.99" )
				)
				( pin "dqs14n"
					( attribute "PN" "111"
						( Origin gPackager )
					)
					( objectStatus "J9T1.111" )
				)
				( pin "dqs14p"
					( attribute "PN" "110"
						( Origin gPackager )
					)
					( objectStatus "J9T1.110" )
				)
				( pin "dqs15n"
					( attribute "PN" "122"
						( Origin gPackager )
					)
					( objectStatus "J9T1.122" )
				)
				( pin "dqs15p"
					( attribute "PN" "121"
						( Origin gPackager )
					)
					( objectStatus "J9T1.121" )
				)
				( pin "dqs16n"
					( attribute "PN" "133"
						( Origin gPackager )
					)
					( objectStatus "J9T1.133" )
				)
				( pin "dqs16p"
					( attribute "PN" "132"
						( Origin gPackager )
					)
					( objectStatus "J9T1.132" )
				)
				( pin "dqs17n"
					( attribute "PN" "52"
						( Origin gPackager )
					)
					( objectStatus "J9T1.52" )
				)
				( pin "dqs17p"
					( attribute "PN" "51"
						( Origin gPackager )
					)
					( objectStatus "J9T1.51" )
				)
			)
			( gate "@baseboard_fab2_lib.baseboard_fab2(sch_1):page78_i144"
				( attribute "BOM_COST" "MEM"
					( Origin gFrontEnd )
				)
				( attribute "CDS_LIB" "mstr_sconn"
					( Origin gPackager )
				)
				( attribute "CDS_LOCATION" "J9T1"
					( Origin gPackager )
				)
				( attribute "CDS_SEC" "3"
					( Origin gPackager )
				)
				( attribute "LOCATION" "J9T1"
					( Origin gFrontEnd )
				)
				( attribute "MATERIAL" "SCONN"
					( Origin gFrontEnd )
				)
				( attribute "PACK_TYPE" "PIP"
					( Origin gFrontEnd )
				)
				( attribute "PART_NUMBER" "H44441-003"
					( Origin gFrontEnd )
				)
				( attribute "PHYS_PAGE" "78"
					( Origin gFrontEnd )
				)
				( attribute "ROOM" "DDR4_GH_G"
					( Origin gFrontEnd )
				)
				( attribute "ROT" "0"
					( Origin gFrontEnd )
				)
				( attribute "SEC" "3"
					( Origin gFrontEnd )
				)
				( attribute "SEC_TYPE" "PIP"
					( Origin gFrontEnd )
				)
				( attribute "VER" "3"
					( Origin gFrontEnd )
				)
				( attribute "XY" "(3550,2000)"
					( Origin gFrontEnd )
				)
				( attribute "CHIPS_PART_NAME" "SCONN288_H44441003"
					( Origin gPackager )
				)
				( attribute "CDS_PART_NAME" "SCONN288_H44441003_PIP-SCONN,HA"
					( Origin gPackager )
				)
				( objectStatus "J9T1" )
				( pin "vss(0)"
					( attribute "PN" "283"
						( Origin gPackager )
					)
					( objectStatus "J9T1.283" )
				)
				( pin "vss(1)"
					( attribute "PN" "281"
						( Origin gPackager )
					)
					( objectStatus "J9T1.281" )
				)
				( pin "vss(2)"
					( attribute "PN" "279"
						( Origin gPackager )
					)
					( objectStatus "J9T1.279" )
				)
				( pin "vss(3)"
					( attribute "PN" "276"
						( Origin gPackager )
					)
					( objectStatus "J9T1.276" )
				)
				( pin "vss(4)"
					( attribute "PN" "274"
						( Origin gPackager )
					)
					( objectStatus "J9T1.274" )
				)
				( pin "vss(5)"
					( attribute "PN" "272"
						( Origin gPackager )
					)
					( objectStatus "J9T1.272" )
				)
				( pin "vss(6)"
					( attribute "PN" "270"
						( Origin gPackager )
					)
					( objectStatus "J9T1.270" )
				)
				( pin "vss(7)"
					( attribute "PN" "268"
						( Origin gPackager )
					)
					( objectStatus "J9T1.268" )
				)
				( pin "vss(8)"
					( attribute "PN" "265"
						( Origin gPackager )
					)
					( objectStatus "J9T1.265" )
				)
				( pin "vss(9)"
					( attribute "PN" "263"
						( Origin gPackager )
					)
					( objectStatus "J9T1.263" )
				)
				( pin "vss(10)"
					( attribute "PN" "261"
						( Origin gPackager )
					)
					( objectStatus "J9T1.261" )
				)
				( pin "vss(11)"
					( attribute "PN" "259"
						( Origin gPackager )
					)
					( objectStatus "J9T1.259" )
				)
				( pin "vss(12)"
					( attribute "PN" "257"
						( Origin gPackager )
					)
					( objectStatus "J9T1.257" )
				)
				( pin "vss(13)"
					( attribute "PN" "254"
						( Origin gPackager )
					)
					( objectStatus "J9T1.254" )
				)
				( pin "vss(14)"
					( attribute "PN" "252"
						( Origin gPackager )
					)
					( objectStatus "J9T1.252" )
				)
				( pin "vss(15)"
					( attribute "PN" "250"
						( Origin gPackager )
					)
					( objectStatus "J9T1.250" )
				)
				( pin "vss(16)"
					( attribute "PN" "248"
						( Origin gPackager )
					)
					( objectStatus "J9T1.248" )
				)
				( pin "vss(17)"
					( attribute "PN" "246"
						( Origin gPackager )
					)
					( objectStatus "J9T1.246" )
				)
				( pin "vss(18)"
					( attribute "PN" "243"
						( Origin gPackager )
					)
					( objectStatus "J9T1.243" )
				)
				( pin "vss(19)"
					( attribute "PN" "241"
						( Origin gPackager )
					)
					( objectStatus "J9T1.241" )
				)
				( pin "vss(20)"
					( attribute "PN" "239"
						( Origin gPackager )
					)
					( objectStatus "J9T1.239" )
				)
				( pin "vss(21)"
					( attribute "PN" "202"
						( Origin gPackager )
					)
					( objectStatus "J9T1.202" )
				)
				( pin "vss(22)"
					( attribute "PN" "200"
						( Origin gPackager )
					)
					( objectStatus "J9T1.200" )
				)
				( pin "vss(23)"
					( attribute "PN" "198"
						( Origin gPackager )
					)
					( objectStatus "J9T1.198" )
				)
				( pin "vss(24)"
					( attribute "PN" "195"
						( Origin gPackager )
					)
					( objectStatus "J9T1.195" )
				)
				( pin "vss(25)"
					( attribute "PN" "193"
						( Origin gPackager )
					)
					( objectStatus "J9T1.193" )
				)
				( pin "vss(26)"
					( attribute "PN" "191"
						( Origin gPackager )
					)
					( objectStatus "J9T1.191" )
				)
				( pin "vss(27)"
					( attribute "PN" "189"
						( Origin gPackager )
					)
					( objectStatus "J9T1.189" )
				)
				( pin "vss(28)"
					( attribute "PN" "187"
						( Origin gPackager )
					)
					( objectStatus "J9T1.187" )
				)
				( pin "vss(29)"
					( attribute "PN" "184"
						( Origin gPackager )
					)
					( objectStatus "J9T1.184" )
				)
				( pin "vss(30)"
					( attribute "PN" "182"
						( Origin gPackager )
					)
					( objectStatus "J9T1.182" )
				)
				( pin "vss(31)"
					( attribute "PN" "180"
						( Origin gPackager )
					)
					( objectStatus "J9T1.180" )
				)
				( pin "vss(32)"
					( attribute "PN" "178"
						( Origin gPackager )
					)
					( objectStatus "J9T1.178" )
				)
				( pin "vss(33)"
					( attribute "PN" "176"
						( Origin gPackager )
					)
					( objectStatus "J9T1.176" )
				)
				( pin "vss(34)"
					( attribute "PN" "173"
						( Origin gPackager )
					)
					( objectStatus "J9T1.173" )
				)
				( pin "vss(35)"
					( attribute "PN" "171"
						( Origin gPackager )
					)
					( objectStatus "J9T1.171" )
				)
				( pin "vss(36)"
					( attribute "PN" "169"
						( Origin gPackager )
					)
					( objectStatus "J9T1.169" )
				)
				( pin "vss(37)"
					( attribute "PN" "167"
						( Origin gPackager )
					)
					( objectStatus "J9T1.167" )
				)
				( pin "vss(38)"
					( attribute "PN" "165"
						( Origin gPackager )
					)
					( objectStatus "J9T1.165" )
				)
				( pin "vss(39)"
					( attribute "PN" "162"
						( Origin gPackager )
					)
					( objectStatus "J9T1.162" )
				)
				( pin "vss(40)"
					( attribute "PN" "160"
						( Origin gPackager )
					)
					( objectStatus "J9T1.160" )
				)
				( pin "vss(41)"
					( attribute "PN" "158"
						( Origin gPackager )
					)
					( objectStatus "J9T1.158" )
				)
				( pin "vss(42)"
					( attribute "PN" "156"
						( Origin gPackager )
					)
					( objectStatus "J9T1.156" )
				)
				( pin "vss(43)"
					( attribute "PN" "154"
						( Origin gPackager )
					)
					( objectStatus "J9T1.154" )
				)
				( pin "vss(44)"
					( attribute "PN" "151"
						( Origin gPackager )
					)
					( objectStatus "J9T1.151" )
				)
				( pin "vss(45)"
					( attribute "PN" "149"
						( Origin gPackager )
					)
					( objectStatus "J9T1.149" )
				)
				( pin "vss(46)"
					( attribute "PN" "147"
						( Origin gPackager )
					)
					( objectStatus "J9T1.147" )
				)
				( pin "vss(47)"
					( attribute "PN" "138"
						( Origin gPackager )
					)
					( objectStatus "J9T1.138" )
				)
				( pin "vss(48)"
					( attribute "PN" "136"
						( Origin gPackager )
					)
					( objectStatus "J9T1.136" )
				)
				( pin "vss(49)"
					( attribute "PN" "134"
						( Origin gPackager )
					)
					( objectStatus "J9T1.134" )
				)
				( pin "vss(50)"
					( attribute "PN" "131"
						( Origin gPackager )
					)
					( objectStatus "J9T1.131" )
				)
				( pin "vss(51)"
					( attribute "PN" "129"
						( Origin gPackager )
					)
					( objectStatus "J9T1.129" )
				)
				( pin "vss(52)"
					( attribute "PN" "127"
						( Origin gPackager )
					)
					( objectStatus "J9T1.127" )
				)
				( pin "vss(53)"
					( attribute "PN" "125"
						( Origin gPackager )
					)
					( objectStatus "J9T1.125" )
				)
				( pin "vss(54)"
					( attribute "PN" "123"
						( Origin gPackager )
					)
					( objectStatus "J9T1.123" )
				)
				( pin "vss(55)"
					( attribute "PN" "120"
						( Origin gPackager )
					)
					( objectStatus "J9T1.120" )
				)
				( pin "vss(56)"
					( attribute "PN" "118"
						( Origin gPackager )
					)
					( objectStatus "J9T1.118" )
				)
				( pin "vss(57)"
					( attribute "PN" "116"
						( Origin gPackager )
					)
					( objectStatus "J9T1.116" )
				)
				( pin "vss(58)"
					( attribute "PN" "114"
						( Origin gPackager )
					)
					( objectStatus "J9T1.114" )
				)
				( pin "vss(59)"
					( attribute "PN" "112"
						( Origin gPackager )
					)
					( objectStatus "J9T1.112" )
				)
				( pin "vss(60)"
					( attribute "PN" "109"
						( Origin gPackager )
					)
					( objectStatus "J9T1.109" )
				)
				( pin "vss(61)"
					( attribute "PN" "107"
						( Origin gPackager )
					)
					( objectStatus "J9T1.107" )
				)
				( pin "vss(62)"
					( attribute "PN" "105"
						( Origin gPackager )
					)
					( objectStatus "J9T1.105" )
				)
				( pin "vss(63)"
					( attribute "PN" "103"
						( Origin gPackager )
					)
					( objectStatus "J9T1.103" )
				)
				( pin "vss(64)"
					( attribute "PN" "101"
						( Origin gPackager )
					)
					( objectStatus "J9T1.101" )
				)
				( pin "vss(65)"
					( attribute "PN" "98"
						( Origin gPackager )
					)
					( objectStatus "J9T1.98" )
				)
				( pin "vss(66)"
					( attribute "PN" "96"
						( Origin gPackager )
					)
					( objectStatus "J9T1.96" )
				)
				( pin "vss(67)"
					( attribute "PN" "94"
						( Origin gPackager )
					)
					( objectStatus "J9T1.94" )
				)
				( pin "vss(68)"
					( attribute "PN" "57"
						( Origin gPackager )
					)
					( objectStatus "J9T1.57" )
				)
				( pin "vss(69)"
					( attribute "PN" "55"
						( Origin gPackager )
					)
					( objectStatus "J9T1.55" )
				)
				( pin "vss(70)"
					( attribute "PN" "53"
						( Origin gPackager )
					)
					( objectStatus "J9T1.53" )
				)
				( pin "vss(71)"
					( attribute "PN" "50"
						( Origin gPackager )
					)
					( objectStatus "J9T1.50" )
				)
				( pin "vss(72)"
					( attribute "PN" "48"
						( Origin gPackager )
					)
					( objectStatus "J9T1.48" )
				)
				( pin "vss(73)"
					( attribute "PN" "46"
						( Origin gPackager )
					)
					( objectStatus "J9T1.46" )
				)
				( pin "vss(74)"
					( attribute "PN" "44"
						( Origin gPackager )
					)
					( objectStatus "J9T1.44" )
				)
				( pin "vss(75)"
					( attribute "PN" "42"
						( Origin gPackager )
					)
					( objectStatus "J9T1.42" )
				)
				( pin "vss(76)"
					( attribute "PN" "39"
						( Origin gPackager )
					)
					( objectStatus "J9T1.39" )
				)
				( pin "vss(77)"
					( attribute "PN" "37"
						( Origin gPackager )
					)
					( objectStatus "J9T1.37" )
				)
				( pin "vss(78)"
					( attribute "PN" "35"
						( Origin gPackager )
					)
					( objectStatus "J9T1.35" )
				)
				( pin "vss(79)"
					( attribute "PN" "33"
						( Origin gPackager )
					)
					( objectStatus "J9T1.33" )
				)
				( pin "vss(80)"
					( attribute "PN" "31"
						( Origin gPackager )
					)
					( objectStatus "J9T1.31" )
				)
				( pin "vss(81)"
					( attribute "PN" "28"
						( Origin gPackager )
					)
					( objectStatus "J9T1.28" )
				)
				( pin "vss(82)"
					( attribute "PN" "26"
						( Origin gPackager )
					)
					( objectStatus "J9T1.26" )
				)
				( pin "vss(83)"
					( attribute "PN" "24"
						( Origin gPackager )
					)
					( objectStatus "J9T1.24" )
				)
				( pin "vss(84)"
					( attribute "PN" "22"
						( Origin gPackager )
					)
					( objectStatus "J9T1.22" )
				)
				( pin "vss(85)"
					( attribute "PN" "20"
						( Origin gPackager )
					)
					( objectStatus "J9T1.20" )
				)
				( pin "vss(86)"
					( attribute "PN" "17"
						( Origin gPackager )
					)
					( objectStatus "J9T1.17" )
				)
				( pin "vss(87)"
					( attribute "PN" "15"
						( Origin gPackager )
					)
					( objectStatus "J9T1.15" )
				)
				( pin "vss(88)"
					( attribute "PN" "13"
						( Origin gPackager )
					)
					( objectStatus "J9T1.13" )
				)
				( pin "vss(89)"
					( attribute "PN" "11"
						( Origin gPackager )
					)
					( objectStatus "J9T1.11" )
				)
				( pin "vss(90)"
					( attribute "PN" "9"
						( Origin gPackager )
					)
					( objectStatus "J9T1.9" )
				)
				( pin "vss(91)"
					( attribute "PN" "6"
						( Origin gPackager )
					)
					( objectStatus "J9T1.6" )
				)
				( pin "vss(92)"
					( attribute "PN" "4"
						( Origin gPackager )
					)
					( objectStatus "J9T1.4" )
				)
				( pin "vss(93)"
					( attribute "PN" "2"
						( Origin gPackager )
					)
					( objectStatus "J9T1.2" )
				)
			)
			( gate "@baseboard_fab2_lib.baseboard_fab2(sch_1):page79_i43"
				( attribute "BOM_COST" "MEM"
					( Origin gFrontEnd )
				)
				( attribute "CDS_LIB" "mstr_sconn"
					( Origin gPackager )
				)
				( attribute "CDS_LOCATION" "J1G2"
					( Origin gPackager )
				)
				( attribute "CDS_SEC" "3"
					( Origin gPackager )
				)
				( attribute "LOCATION" "J1G2"
					( Origin gFrontEnd )
				)
				( attribute "MATERIAL" "SCONN"
					( Origin gFrontEnd )
				)
				( attribute "PACK_TYPE" "PIP"
					( Origin gFrontEnd )
				)
				( attribute "PART_NUMBER" "H44441-004"
					( Origin gFrontEnd )
				)
				( attribute "PHYS_PAGE" "79"
					( Origin gFrontEnd )
				)
				( attribute "ROOM" "DDR4_CH_H"
					( Origin gFrontEnd )
				)
				( attribute "ROT" "0"
					( Origin gFrontEnd )
				)
				( attribute "SEC" "3"
					( Origin gFrontEnd )
				)
				( attribute "SEC_TYPE" "PIP"
					( Origin gFrontEnd )
				)
				( attribute "VER" "3"
					( Origin gFrontEnd )
				)
				( attribute "XY" "(1750,2400)"
					( Origin gFrontEnd )
				)
				( attribute "CHIPS_PART_NAME" "SCONN288_H44441004"
					( Origin gPackager )
				)
				( attribute "CDS_PART_NAME" "SCONN288_H44441004_PIP-SCONN,HA"
					( Origin gPackager )
				)
				( objectStatus "J1G2" )
				( pin "vss(0)"
					( attribute "PN" "283"
						( Origin gPackager )
					)
					( objectStatus "J1G2.283" )
				)
				( pin "vss(1)"
					( attribute "PN" "281"
						( Origin gPackager )
					)
					( objectStatus "J1G2.281" )
				)
				( pin "vss(2)"
					( attribute "PN" "279"
						( Origin gPackager )
					)
					( objectStatus "J1G2.279" )
				)
				( pin "vss(3)"
					( attribute "PN" "276"
						( Origin gPackager )
					)
					( objectStatus "J1G2.276" )
				)
				( pin "vss(4)"
					( attribute "PN" "274"
						( Origin gPackager )
					)
					( objectStatus "J1G2.274" )
				)
				( pin "vss(5)"
					( attribute "PN" "272"
						( Origin gPackager )
					)
					( objectStatus "J1G2.272" )
				)
				( pin "vss(6)"
					( attribute "PN" "270"
						( Origin gPackager )
					)
					( objectStatus "J1G2.270" )
				)
				( pin "vss(7)"
					( attribute "PN" "268"
						( Origin gPackager )
					)
					( objectStatus "J1G2.268" )
				)
				( pin "vss(8)"
					( attribute "PN" "265"
						( Origin gPackager )
					)
					( objectStatus "J1G2.265" )
				)
				( pin "vss(9)"
					( attribute "PN" "263"
						( Origin gPackager )
					)
					( objectStatus "J1G2.263" )
				)
				( pin "vss(10)"
					( attribute "PN" "261"
						( Origin gPackager )
					)
					( objectStatus "J1G2.261" )
				)
				( pin "vss(11)"
					( attribute "PN" "259"
						( Origin gPackager )
					)
					( objectStatus "J1G2.259" )
				)
				( pin "vss(12)"
					( attribute "PN" "257"
						( Origin gPackager )
					)
					( objectStatus "J1G2.257" )
				)
				( pin "vss(13)"
					( attribute "PN" "254"
						( Origin gPackager )
					)
					( objectStatus "J1G2.254" )
				)
				( pin "vss(14)"
					( attribute "PN" "252"
						( Origin gPackager )
					)
					( objectStatus "J1G2.252" )
				)
				( pin "vss(15)"
					( attribute "PN" "250"
						( Origin gPackager )
					)
					( objectStatus "J1G2.250" )
				)
				( pin "vss(16)"
					( attribute "PN" "248"
						( Origin gPackager )
					)
					( objectStatus "J1G2.248" )
				)
				( pin "vss(17)"
					( attribute "PN" "246"
						( Origin gPackager )
					)
					( objectStatus "J1G2.246" )
				)
				( pin "vss(18)"
					( attribute "PN" "243"
						( Origin gPackager )
					)
					( objectStatus "J1G2.243" )
				)
				( pin "vss(19)"
					( attribute "PN" "241"
						( Origin gPackager )
					)
					( objectStatus "J1G2.241" )
				)
				( pin "vss(20)"
					( attribute "PN" "239"
						( Origin gPackager )
					)
					( objectStatus "J1G2.239" )
				)
				( pin "vss(21)"
					( attribute "PN" "202"
						( Origin gPackager )
					)
					( objectStatus "J1G2.202" )
				)
				( pin "vss(22)"
					( attribute "PN" "200"
						( Origin gPackager )
					)
					( objectStatus "J1G2.200" )
				)
				( pin "vss(23)"
					( attribute "PN" "198"
						( Origin gPackager )
					)
					( objectStatus "J1G2.198" )
				)
				( pin "vss(24)"
					( attribute "PN" "195"
						( Origin gPackager )
					)
					( objectStatus "J1G2.195" )
				)
				( pin "vss(25)"
					( attribute "PN" "193"
						( Origin gPackager )
					)
					( objectStatus "J1G2.193" )
				)
				( pin "vss(26)"
					( attribute "PN" "191"
						( Origin gPackager )
					)
					( objectStatus "J1G2.191" )
				)
				( pin "vss(27)"
					( attribute "PN" "189"
						( Origin gPackager )
					)
					( objectStatus "J1G2.189" )
				)
				( pin "vss(28)"
					( attribute "PN" "187"
						( Origin gPackager )
					)
					( objectStatus "J1G2.187" )
				)
				( pin "vss(29)"
					( attribute "PN" "184"
						( Origin gPackager )
					)
					( objectStatus "J1G2.184" )
				)
				( pin "vss(30)"
					( attribute "PN" "182"
						( Origin gPackager )
					)
					( objectStatus "J1G2.182" )
				)
				( pin "vss(31)"
					( attribute "PN" "180"
						( Origin gPackager )
					)
					( objectStatus "J1G2.180" )
				)
				( pin "vss(32)"
					( attribute "PN" "178"
						( Origin gPackager )
					)
					( objectStatus "J1G2.178" )
				)
				( pin "vss(33)"
					( attribute "PN" "176"
						( Origin gPackager )
					)
					( objectStatus "J1G2.176" )
				)
				( pin "vss(34)"
					( attribute "PN" "173"
						( Origin gPackager )
					)
					( objectStatus "J1G2.173" )
				)
				( pin "vss(35)"
					( attribute "PN" "171"
						( Origin gPackager )
					)
					( objectStatus "J1G2.171" )
				)
				( pin "vss(36)"
					( attribute "PN" "169"
						( Origin gPackager )
					)
					( objectStatus "J1G2.169" )
				)
				( pin "vss(37)"
					( attribute "PN" "167"
						( Origin gPackager )
					)
					( objectStatus "J1G2.167" )
				)
				( pin "vss(38)"
					( attribute "PN" "165"
						( Origin gPackager )
					)
					( objectStatus "J1G2.165" )
				)
				( pin "vss(39)"
					( attribute "PN" "162"
						( Origin gPackager )
					)
					( objectStatus "J1G2.162" )
				)
				( pin "vss(40)"
					( attribute "PN" "160"
						( Origin gPackager )
					)
					( objectStatus "J1G2.160" )
				)
				( pin "vss(41)"
					( attribute "PN" "158"
						( Origin gPackager )
					)
					( objectStatus "J1G2.158" )
				)
				( pin "vss(42)"
					( attribute "PN" "156"
						( Origin gPackager )
					)
					( objectStatus "J1G2.156" )
				)
				( pin "vss(43)"
					( attribute "PN" "154"
						( Origin gPackager )
					)
					( objectStatus "J1G2.154" )
				)
				( pin "vss(44)"
					( attribute "PN" "151"
						( Origin gPackager )
					)
					( objectStatus "J1G2.151" )
				)
				( pin "vss(45)"
					( attribute "PN" "149"
						( Origin gPackager )
					)
					( objectStatus "J1G2.149" )
				)
				( pin "vss(46)"
					( attribute "PN" "147"
						( Origin gPackager )
					)
					( objectStatus "J1G2.147" )
				)
				( pin "vss(47)"
					( attribute "PN" "138"
						( Origin gPackager )
					)
					( objectStatus "J1G2.138" )
				)
				( pin "vss(48)"
					( attribute "PN" "136"
						( Origin gPackager )
					)
					( objectStatus "J1G2.136" )
				)
				( pin "vss(49)"
					( attribute "PN" "134"
						( Origin gPackager )
					)
					( objectStatus "J1G2.134" )
				)
				( pin "vss(50)"
					( attribute "PN" "131"
						( Origin gPackager )
					)
					( objectStatus "J1G2.131" )
				)
				( pin "vss(51)"
					( attribute "PN" "129"
						( Origin gPackager )
					)
					( objectStatus "J1G2.129" )
				)
				( pin "vss(52)"
					( attribute "PN" "127"
						( Origin gPackager )
					)
					( objectStatus "J1G2.127" )
				)
				( pin "vss(53)"
					( attribute "PN" "125"
						( Origin gPackager )
					)
					( objectStatus "J1G2.125" )
				)
				( pin "vss(54)"
					( attribute "PN" "123"
						( Origin gPackager )
					)
					( objectStatus "J1G2.123" )
				)
				( pin "vss(55)"
					( attribute "PN" "120"
						( Origin gPackager )
					)
					( objectStatus "J1G2.120" )
				)
				( pin "vss(56)"
					( attribute "PN" "118"
						( Origin gPackager )
					)
					( objectStatus "J1G2.118" )
				)
				( pin "vss(57)"
					( attribute "PN" "116"
						( Origin gPackager )
					)
					( objectStatus "J1G2.116" )
				)
				( pin "vss(58)"
					( attribute "PN" "114"
						( Origin gPackager )
					)
					( objectStatus "J1G2.114" )
				)
				( pin "vss(59)"
					( attribute "PN" "112"
						( Origin gPackager )
					)
					( objectStatus "J1G2.112" )
				)
				( pin "vss(60)"
					( attribute "PN" "109"
						( Origin gPackager )
					)
					( objectStatus "J1G2.109" )
				)
				( pin "vss(61)"
					( attribute "PN" "107"
						( Origin gPackager )
					)
					( objectStatus "J1G2.107" )
				)
				( pin "vss(62)"
					( attribute "PN" "105"
						( Origin gPackager )
					)
					( objectStatus "J1G2.105" )
				)
				( pin "vss(63)"
					( attribute "PN" "103"
						( Origin gPackager )
					)
					( objectStatus "J1G2.103" )
				)
				( pin "vss(64)"
					( attribute "PN" "101"
						( Origin gPackager )
					)
					( objectStatus "J1G2.101" )
				)
				( pin "vss(65)"
					( attribute "PN" "98"
						( Origin gPackager )
					)
					( objectStatus "J1G2.98" )
				)
				( pin "vss(66)"
					( attribute "PN" "96"
						( Origin gPackager )
					)
					( objectStatus "J1G2.96" )
				)
				( pin "vss(67)"
					( attribute "PN" "94"
						( Origin gPackager )
					)
					( objectStatus "J1G2.94" )
				)
				( pin "vss(68)"
					( attribute "PN" "57"
						( Origin gPackager )
					)
					( objectStatus "J1G2.57" )
				)
				( pin "vss(69)"
					( attribute "PN" "55"
						( Origin gPackager )
					)
					( objectStatus "J1G2.55" )
				)
				( pin "vss(70)"
					( attribute "PN" "53"
						( Origin gPackager )
					)
					( objectStatus "J1G2.53" )
				)
				( pin "vss(71)"
					( attribute "PN" "50"
						( Origin gPackager )
					)
					( objectStatus "J1G2.50" )
				)
				( pin "vss(72)"
					( attribute "PN" "48"
						( Origin gPackager )
					)
					( objectStatus "J1G2.48" )
				)
				( pin "vss(73)"
					( attribute "PN" "46"
						( Origin gPackager )
					)
					( objectStatus "J1G2.46" )
				)
				( pin "vss(74)"
					( attribute "PN" "44"
						( Origin gPackager )
					)
					( objectStatus "J1G2.44" )
				)
				( pin "vss(75)"
					( attribute "PN" "42"
						( Origin gPackager )
					)
					( objectStatus "J1G2.42" )
				)
				( pin "vss(76)"
					( attribute "PN" "39"
						( Origin gPackager )
					)
					( objectStatus "J1G2.39" )
				)
				( pin "vss(77)"
					( attribute "PN" "37"
						( Origin gPackager )
					)
					( objectStatus "J1G2.37" )
				)
				( pin "vss(78)"
					( attribute "PN" "35"
						( Origin gPackager )
					)
					( objectStatus "J1G2.35" )
				)
				( pin "vss(79)"
					( attribute "PN" "33"
						( Origin gPackager )
					)
					( objectStatus "J1G2.33" )
				)
				( pin "vss(80)"
					( attribute "PN" "31"
						( Origin gPackager )
					)
					( objectStatus "J1G2.31" )
				)
				( pin "vss(81)"
					( attribute "PN" "28"
						( Origin gPackager )
					)
					( objectStatus "J1G2.28" )
				)
				( pin "vss(82)"
					( attribute "PN" "26"
						( Origin gPackager )
					)
					( objectStatus "J1G2.26" )
				)
				( pin "vss(83)"
					( attribute "PN" "24"
						( Origin gPackager )
					)
					( objectStatus "J1G2.24" )
				)
				( pin "vss(84)"
					( attribute "PN" "22"
						( Origin gPackager )
					)
					( objectStatus "J1G2.22" )
				)
				( pin "vss(85)"
					( attribute "PN" "20"
						( Origin gPackager )
					)
					( objectStatus "J1G2.20" )
				)
				( pin "vss(86)"
					( attribute "PN" "17"
						( Origin gPackager )
					)
					( objectStatus "J1G2.17" )
				)
				( pin "vss(87)"
					( attribute "PN" "15"
						( Origin gPackager )
					)
					( objectStatus "J1G2.15" )
				)
				( pin "vss(88)"
					( attribute "PN" "13"
						( Origin gPackager )
					)
					( objectStatus "J1G2.13" )
				)
				( pin "vss(89)"
					( attribute "PN" "11"
						( Origin gPackager )
					)
					( objectStatus "J1G2.11" )
				)
				( pin "vss(90)"
					( attribute "PN" "9"
						( Origin gPackager )
					)
					( objectStatus "J1G2.9" )
				)
				( pin "vss(91)"
					( attribute "PN" "6"
						( Origin gPackager )
					)
					( objectStatus "J1G2.6" )
				)
				( pin "vss(92)"
					( attribute "PN" "4"
						( Origin gPackager )
					)
					( objectStatus "J1G2.4" )
				)
				( pin "vss(93)"
					( attribute "PN" "2"
						( Origin gPackager )
					)
					( objectStatus "J1G2.2" )
				)
			)
			( gate "@baseboard_fab2_lib.baseboard_fab2(sch_1):page79_i64"
				( attribute "BOM_COST" "MEM"
					( Origin gFrontEnd )
				)
				( attribute "CDS_LIB" "mstr_sconn"
					( Origin gPackager )
				)
				( attribute "CDS_LOCATION" "J1G2"
					( Origin gPackager )
				)
				( attribute "CDS_SEC" "2"
					( Origin gPackager )
				)
				( attribute "LOCATION" "J1G2"
					( Origin gFrontEnd )
				)
				( attribute "MATERIAL" "SCONN"
					( Origin gFrontEnd )
				)
				( attribute "PACK_TYPE" "PIP"
					( Origin gFrontEnd )
				)
				( attribute "PART_NUMBER" "H44441-004"
					( Origin gFrontEnd )
				)
				( attribute "PHYS_PAGE" "79"
					( Origin gFrontEnd )
				)
				( attribute "ROOM" "DDR4_CH_H"
					( Origin gFrontEnd )
				)
				( attribute "ROT" "0"
					( Origin gFrontEnd )
				)
				( attribute "SEC" "2"
					( Origin gFrontEnd )
				)
				( attribute "SEC_TYPE" "PIP"
					( Origin gFrontEnd )
				)
				( attribute "VER" "2"
					( Origin gFrontEnd )
				)
				( attribute "XY" "(-50,4300)"
					( Origin gFrontEnd )
				)
				( attribute "CHIPS_PART_NAME" "SCONN288_H44441004"
					( Origin gPackager )
				)
				( attribute "CDS_PART_NAME" "SCONN288_H44441004_PIP-SCONN,HA"
					( Origin gPackager )
				)
				( objectStatus "J1G2" )
				( pin "dqs0n"
					( attribute "PN" "152"
						( Origin gPackager )
					)
					( objectStatus "J1G2.152" )
				)
				( pin "dqs0p"
					( attribute "PN" "153"
						( Origin gPackager )
					)
					( objectStatus "J1G2.153" )
				)
				( pin "dqs1n"
					( attribute "PN" "163"
						( Origin gPackager )
					)
					( objectStatus "J1G2.163" )
				)
				( pin "dqs1p"
					( attribute "PN" "164"
						( Origin gPackager )
					)
					( objectStatus "J1G2.164" )
				)
				( pin "dqs2n"
					( attribute "PN" "174"
						( Origin gPackager )
					)
					( objectStatus "J1G2.174" )
				)
				( pin "dqs2p"
					( attribute "PN" "175"
						( Origin gPackager )
					)
					( objectStatus "J1G2.175" )
				)
				( pin "dqs3n"
					( attribute "PN" "185"
						( Origin gPackager )
					)
					( objectStatus "J1G2.185" )
				)
				( pin "dqs3p"
					( attribute "PN" "186"
						( Origin gPackager )
					)
					( objectStatus "J1G2.186" )
				)
				( pin "dqs4n"
					( attribute "PN" "244"
						( Origin gPackager )
					)
					( objectStatus "J1G2.244" )
				)
				( pin "dqs4p"
					( attribute "PN" "245"
						( Origin gPackager )
					)
					( objectStatus "J1G2.245" )
				)
				( pin "dqs5n"
					( attribute "PN" "255"
						( Origin gPackager )
					)
					( objectStatus "J1G2.255" )
				)
				( pin "dqs5p"
					( attribute "PN" "256"
						( Origin gPackager )
					)
					( objectStatus "J1G2.256" )
				)
				( pin "dqs6n"
					( attribute "PN" "266"
						( Origin gPackager )
					)
					( objectStatus "J1G2.266" )
				)
				( pin "dqs6p"
					( attribute "PN" "267"
						( Origin gPackager )
					)
					( objectStatus "J1G2.267" )
				)
				( pin "dqs7n"
					( attribute "PN" "277"
						( Origin gPackager )
					)
					( objectStatus "J1G2.277" )
				)
				( pin "dqs7p"
					( attribute "PN" "278"
						( Origin gPackager )
					)
					( objectStatus "J1G2.278" )
				)
				( pin "dqs8n"
					( attribute "PN" "196"
						( Origin gPackager )
					)
					( objectStatus "J1G2.196" )
				)
				( pin "dqs8p"
					( attribute "PN" "197"
						( Origin gPackager )
					)
					( objectStatus "J1G2.197" )
				)
				( pin "dqs9n"
					( attribute "PN" "8"
						( Origin gPackager )
					)
					( objectStatus "J1G2.8" )
				)
				( pin "dqs9p"
					( attribute "PN" "7"
						( Origin gPackager )
					)
					( objectStatus "J1G2.7" )
				)
				( pin "dqs10n"
					( attribute "PN" "19"
						( Origin gPackager )
					)
					( objectStatus "J1G2.19" )
				)
				( pin "dqs10p"
					( attribute "PN" "18"
						( Origin gPackager )
					)
					( objectStatus "J1G2.18" )
				)
				( pin "dqs11n"
					( attribute "PN" "30"
						( Origin gPackager )
					)
					( objectStatus "J1G2.30" )
				)
				( pin "dqs11p"
					( attribute "PN" "29"
						( Origin gPackager )
					)
					( objectStatus "J1G2.29" )
				)
				( pin "dqs12n"
					( attribute "PN" "41"
						( Origin gPackager )
					)
					( objectStatus "J1G2.41" )
				)
				( pin "dqs12p"
					( attribute "PN" "40"
						( Origin gPackager )
					)
					( objectStatus "J1G2.40" )
				)
				( pin "dqs13n"
					( attribute "PN" "100"
						( Origin gPackager )
					)
					( objectStatus "J1G2.100" )
				)
				( pin "dqs13p"
					( attribute "PN" "99"
						( Origin gPackager )
					)
					( objectStatus "J1G2.99" )
				)
				( pin "dqs14n"
					( attribute "PN" "111"
						( Origin gPackager )
					)
					( objectStatus "J1G2.111" )
				)
				( pin "dqs14p"
					( attribute "PN" "110"
						( Origin gPackager )
					)
					( objectStatus "J1G2.110" )
				)
				( pin "dqs15n"
					( attribute "PN" "122"
						( Origin gPackager )
					)
					( objectStatus "J1G2.122" )
				)
				( pin "dqs15p"
					( attribute "PN" "121"
						( Origin gPackager )
					)
					( objectStatus "J1G2.121" )
				)
				( pin "dqs16n"
					( attribute "PN" "133"
						( Origin gPackager )
					)
					( objectStatus "J1G2.133" )
				)
				( pin "dqs16p"
					( attribute "PN" "132"
						( Origin gPackager )
					)
					( objectStatus "J1G2.132" )
				)
				( pin "dqs17n"
					( attribute "PN" "52"
						( Origin gPackager )
					)
					( objectStatus "J1G2.52" )
				)
				( pin "dqs17p"
					( attribute "PN" "51"
						( Origin gPackager )
					)
					( objectStatus "J1G2.51" )
				)
			)
			( gate "@baseboard_fab2_lib.baseboard_fab2(sch_1):page79_i111"
				( attribute "BOM_COST" "MEM"
					( Origin gFrontEnd )
				)
				( attribute "CDS_LIB" "mstr_sconn"
					( Origin gPackager )
				)
				( attribute "CDS_LOCATION" "J1G2"
					( Origin gPackager )
				)
				( attribute "CDS_SEC" "1"
					( Origin gPackager )
				)
				( attribute "LOCATION" "J1G2"
					( Origin gFrontEnd )
				)
				( attribute "MATERIAL" "SCONN"
					( Origin gFrontEnd )
				)
				( attribute "PACK_TYPE" "PIP"
					( Origin gFrontEnd )
				)
				( attribute "PART_NUMBER" "H44441-004"
					( Origin gFrontEnd )
				)
				( attribute "PHYS_PAGE" "79"
					( Origin gFrontEnd )
				)
				( attribute "ROOM" "DDR4_CH_H"
					( Origin gFrontEnd )
				)
				( attribute "ROT" "0"
					( Origin gFrontEnd )
				)
				( attribute "SEC" "1"
					( Origin gFrontEnd )
				)
				( attribute "SEC_TYPE" "PIP"
					( Origin gFrontEnd )
				)
				( attribute "VER" "1"
					( Origin gFrontEnd )
				)
				( attribute "XY" "(-2600,3250)"
					( Origin gFrontEnd )
				)
				( attribute "CHIPS_PART_NAME" "SCONN288_H44441004"
					( Origin gPackager )
				)
				( attribute "CDS_PART_NAME" "SCONN288_H44441004_PIP-SCONN,HA"
					( Origin gPackager )
				)
				( objectStatus "J1G2" )
				( pin "a0"
					( attribute "PN" "79"
						( Origin gPackager )
					)
					( objectStatus "J1G2.79" )
				)
				( pin "a1"
					( attribute "PN" "72"
						( Origin gPackager )
					)
					( objectStatus "J1G2.72" )
				)
				( pin "a2"
					( attribute "PN" "216"
						( Origin gPackager )
					)
					( objectStatus "J1G2.216" )
				)
				( pin "a3"
					( attribute "PN" "71"
						( Origin gPackager )
					)
					( objectStatus "J1G2.71" )
				)
				( pin "a4"
					( attribute "PN" "214"
						( Origin gPackager )
					)
					( objectStatus "J1G2.214" )
				)
				( pin "a5"
					( attribute "PN" "213"
						( Origin gPackager )
					)
					( objectStatus "J1G2.213" )
				)
				( pin "a6"
					( attribute "PN" "69"
						( Origin gPackager )
					)
					( objectStatus "J1G2.69" )
				)
				( pin "a7"
					( attribute "PN" "211"
						( Origin gPackager )
					)
					( objectStatus "J1G2.211" )
				)
				( pin "a8"
					( attribute "PN" "68"
						( Origin gPackager )
					)
					( objectStatus "J1G2.68" )
				)
				( pin "a9"
					( attribute "PN" "66"
						( Origin gPackager )
					)
					( objectStatus "J1G2.66" )
				)
				( pin "a10"
					( attribute "PN" "225"
						( Origin gPackager )
					)
					( objectStatus "J1G2.225" )
				)
				( pin "a11"
					( attribute "PN" "210"
						( Origin gPackager )
					)
					( objectStatus "J1G2.210" )
				)
				( pin "a12"
					( attribute "PN" "65"
						( Origin gPackager )
					)
					( objectStatus "J1G2.65" )
				)
				( pin "a13"
					( attribute "PN" "232"
						( Origin gPackager )
					)
					( objectStatus "J1G2.232" )
				)
				( pin "a14_we_n"
					( attribute "PN" "228"
						( Origin gPackager )
					)
					( objectStatus "J1G2.228" )
				)
				( pin "a15_cas_n"
					( attribute "PN" "86"
						( Origin gPackager )
					)
					( objectStatus "J1G2.86" )
				)
				( pin "a16_ras_n"
					( attribute "PN" "82"
						( Origin gPackager )
					)
					( objectStatus "J1G2.82" )
				)
				( pin "a17"
					( attribute "PN" "234"
						( Origin gPackager )
					)
					( objectStatus "J1G2.234" )
				)
				( pin "act_n"
					( attribute "PN" "62"
						( Origin gPackager )
					)
					( objectStatus "J1G2.62" )
				)
				( pin "alert_n"
					( attribute "PN" "208"
						( Origin gPackager )
					)
					( objectStatus "J1G2.208" )
				)
				( pin "ba(0)"
					( attribute "PN" "81"
						( Origin gPackager )
					)
					( objectStatus "J1G2.81" )
				)
				( pin "ba(1)"
					( attribute "PN" "224"
						( Origin gPackager )
					)
					( objectStatus "J1G2.224" )
				)
				( pin "bg(0)"
					( attribute "PN" "63"
						( Origin gPackager )
					)
					( objectStatus "J1G2.63" )
				)
				( pin "bg(1)"
					( attribute "PN" "207"
						( Origin gPackager )
					)
					( objectStatus "J1G2.207" )
				)
				( pin "c(2)"
					( attribute "PN" "235"
						( Origin gPackager )
					)
					( objectStatus "J1G2.235" )
				)
				( pin "cb(0)"
					( attribute "PN" "49"
						( Origin gPackager )
					)
					( objectStatus "J1G2.49" )
				)
				( pin "cb(1)"
					( attribute "PN" "194"
						( Origin gPackager )
					)
					( objectStatus "J1G2.194" )
				)
				( pin "cb(2)"
					( attribute "PN" "56"
						( Origin gPackager )
					)
					( objectStatus "J1G2.56" )
				)
				( pin "cb(3)"
					( attribute "PN" "201"
						( Origin gPackager )
					)
					( objectStatus "J1G2.201" )
				)
				( pin "cb(4)"
					( attribute "PN" "47"
						( Origin gPackager )
					)
					( objectStatus "J1G2.47" )
				)
				( pin "cb(5)"
					( attribute "PN" "192"
						( Origin gPackager )
					)
					( objectStatus "J1G2.192" )
				)
				( pin "cb(6)"
					( attribute "PN" "54"
						( Origin gPackager )
					)
					( objectStatus "J1G2.54" )
				)
				( pin "cb(7)"
					( attribute "PN" "199"
						( Origin gPackager )
					)
					( objectStatus "J1G2.199" )
				)
				( pin "ck0n"
					( attribute "PN" "75"
						( Origin gPackager )
					)
					( objectStatus "J1G2.75" )
				)
				( pin "ck0p"
					( attribute "PN" "74"
						( Origin gPackager )
					)
					( objectStatus "J1G2.74" )
				)
				( pin "ck1n"
					( attribute "PN" "219"
						( Origin gPackager )
					)
					( objectStatus "J1G2.219" )
				)
				( pin "ck1p"
					( attribute "PN" "218"
						( Origin gPackager )
					)
					( objectStatus "J1G2.218" )
				)
				( pin "cke(0)"
					( attribute "PN" "60"
						( Origin gPackager )
					)
					( objectStatus "J1G2.60" )
				)
				( pin "cke(1)"
					( attribute "PN" "203"
						( Origin gPackager )
					)
					( objectStatus "J1G2.203" )
				)
				( pin "dq(0)"
					( attribute "PN" "5"
						( Origin gPackager )
					)
					( objectStatus "J1G2.5" )
				)
				( pin "dq(1)"
					( attribute "PN" "150"
						( Origin gPackager )
					)
					( objectStatus "J1G2.150" )
				)
				( pin "dq(2)"
					( attribute "PN" "12"
						( Origin gPackager )
					)
					( objectStatus "J1G2.12" )
				)
				( pin "dq(3)"
					( attribute "PN" "157"
						( Origin gPackager )
					)
					( objectStatus "J1G2.157" )
				)
				( pin "dq(4)"
					( attribute "PN" "3"
						( Origin gPackager )
					)
					( objectStatus "J1G2.3" )
				)
				( pin "dq(5)"
					( attribute "PN" "148"
						( Origin gPackager )
					)
					( objectStatus "J1G2.148" )
				)
				( pin "dq(6)"
					( attribute "PN" "10"
						( Origin gPackager )
					)
					( objectStatus "J1G2.10" )
				)
				( pin "dq(7)"
					( attribute "PN" "155"
						( Origin gPackager )
					)
					( objectStatus "J1G2.155" )
				)
				( pin "dq(8)"
					( attribute "PN" "16"
						( Origin gPackager )
					)
					( objectStatus "J1G2.16" )
				)
				( pin "dq(9)"
					( attribute "PN" "161"
						( Origin gPackager )
					)
					( objectStatus "J1G2.161" )
				)
				( pin "dq(10)"
					( attribute "PN" "23"
						( Origin gPackager )
					)
					( objectStatus "J1G2.23" )
				)
				( pin "dq(11)"
					( attribute "PN" "168"
						( Origin gPackager )
					)
					( objectStatus "J1G2.168" )
				)
				( pin "dq(12)"
					( attribute "PN" "14"
						( Origin gPackager )
					)
					( objectStatus "J1G2.14" )
				)
				( pin "dq(13)"
					( attribute "PN" "159"
						( Origin gPackager )
					)
					( objectStatus "J1G2.159" )
				)
				( pin "dq(14)"
					( attribute "PN" "21"
						( Origin gPackager )
					)
					( objectStatus "J1G2.21" )
				)
				( pin "dq(15)"
					( attribute "PN" "166"
						( Origin gPackager )
					)
					( objectStatus "J1G2.166" )
				)
				( pin "dq(16)"
					( attribute "PN" "27"
						( Origin gPackager )
					)
					( objectStatus "J1G2.27" )
				)
				( pin "dq(17)"
					( attribute "PN" "172"
						( Origin gPackager )
					)
					( objectStatus "J1G2.172" )
				)
				( pin "dq(18)"
					( attribute "PN" "34"
						( Origin gPackager )
					)
					( objectStatus "J1G2.34" )
				)
				( pin "dq(19)"
					( attribute "PN" "179"
						( Origin gPackager )
					)
					( objectStatus "J1G2.179" )
				)
				( pin "dq(20)"
					( attribute "PN" "25"
						( Origin gPackager )
					)
					( objectStatus "J1G2.25" )
				)
				( pin "dq(21)"
					( attribute "PN" "170"
						( Origin gPackager )
					)
					( objectStatus "J1G2.170" )
				)
				( pin "dq(22)"
					( attribute "PN" "32"
						( Origin gPackager )
					)
					( objectStatus "J1G2.32" )
				)
				( pin "dq(23)"
					( attribute "PN" "177"
						( Origin gPackager )
					)
					( objectStatus "J1G2.177" )
				)
				( pin "dq(24)"
					( attribute "PN" "38"
						( Origin gPackager )
					)
					( objectStatus "J1G2.38" )
				)
				( pin "dq(25)"
					( attribute "PN" "183"
						( Origin gPackager )
					)
					( objectStatus "J1G2.183" )
				)
				( pin "dq(26)"
					( attribute "PN" "45"
						( Origin gPackager )
					)
					( objectStatus "J1G2.45" )
				)
				( pin "dq(27)"
					( attribute "PN" "190"
						( Origin gPackager )
					)
					( objectStatus "J1G2.190" )
				)
				( pin "dq(28)"
					( attribute "PN" "36"
						( Origin gPackager )
					)
					( objectStatus "J1G2.36" )
				)
				( pin "dq(29)"
					( attribute "PN" "181"
						( Origin gPackager )
					)
					( objectStatus "J1G2.181" )
				)
				( pin "dq(30)"
					( attribute "PN" "43"
						( Origin gPackager )
					)
					( objectStatus "J1G2.43" )
				)
				( pin "dq(31)"
					( attribute "PN" "188"
						( Origin gPackager )
					)
					( objectStatus "J1G2.188" )
				)
				( pin "dq(32)"
					( attribute "PN" "97"
						( Origin gPackager )
					)
					( objectStatus "J1G2.97" )
				)
				( pin "dq(33)"
					( attribute "PN" "242"
						( Origin gPackager )
					)
					( objectStatus "J1G2.242" )
				)
				( pin "dq(34)"
					( attribute "PN" "104"
						( Origin gPackager )
					)
					( objectStatus "J1G2.104" )
				)
				( pin "dq(35)"
					( attribute "PN" "249"
						( Origin gPackager )
					)
					( objectStatus "J1G2.249" )
				)
				( pin "dq(36)"
					( attribute "PN" "95"
						( Origin gPackager )
					)
					( objectStatus "J1G2.95" )
				)
				( pin "dq(37)"
					( attribute "PN" "240"
						( Origin gPackager )
					)
					( objectStatus "J1G2.240" )
				)
				( pin "dq(38)"
					( attribute "PN" "102"
						( Origin gPackager )
					)
					( objectStatus "J1G2.102" )
				)
				( pin "dq(39)"
					( attribute "PN" "247"
						( Origin gPackager )
					)
					( objectStatus "J1G2.247" )
				)
				( pin "dq(40)"
					( attribute "PN" "108"
						( Origin gPackager )
					)
					( objectStatus "J1G2.108" )
				)
				( pin "dq(41)"
					( attribute "PN" "253"
						( Origin gPackager )
					)
					( objectStatus "J1G2.253" )
				)
				( pin "dq(42)"
					( attribute "PN" "115"
						( Origin gPackager )
					)
					( objectStatus "J1G2.115" )
				)
				( pin "dq(43)"
					( attribute "PN" "260"
						( Origin gPackager )
					)
					( objectStatus "J1G2.260" )
				)
				( pin "dq(44)"
					( attribute "PN" "106"
						( Origin gPackager )
					)
					( objectStatus "J1G2.106" )
				)
				( pin "dq(45)"
					( attribute "PN" "251"
						( Origin gPackager )
					)
					( objectStatus "J1G2.251" )
				)
				( pin "dq(46)"
					( attribute "PN" "113"
						( Origin gPackager )
					)
					( objectStatus "J1G2.113" )
				)
				( pin "dq(47)"
					( attribute "PN" "258"
						( Origin gPackager )
					)
					( objectStatus "J1G2.258" )
				)
				( pin "dq(48)"
					( attribute "PN" "119"
						( Origin gPackager )
					)
					( objectStatus "J1G2.119" )
				)
				( pin "dq(49)"
					( attribute "PN" "264"
						( Origin gPackager )
					)
					( objectStatus "J1G2.264" )
				)
				( pin "dq(50)"
					( attribute "PN" "126"
						( Origin gPackager )
					)
					( objectStatus "J1G2.126" )
				)
				( pin "dq(51)"
					( attribute "PN" "271"
						( Origin gPackager )
					)
					( objectStatus "J1G2.271" )
				)
				( pin "dq(52)"
					( attribute "PN" "117"
						( Origin gPackager )
					)
					( objectStatus "J1G2.117" )
				)
				( pin "dq(53)"
					( attribute "PN" "262"
						( Origin gPackager )
					)
					( objectStatus "J1G2.262" )
				)
				( pin "dq(54)"
					( attribute "PN" "124"
						( Origin gPackager )
					)
					( objectStatus "J1G2.124" )
				)
				( pin "dq(55)"
					( attribute "PN" "269"
						( Origin gPackager )
					)
					( objectStatus "J1G2.269" )
				)
				( pin "dq(56)"
					( attribute "PN" "130"
						( Origin gPackager )
					)
					( objectStatus "J1G2.130" )
				)
				( pin "dq(57)"
					( attribute "PN" "275"
						( Origin gPackager )
					)
					( objectStatus "J1G2.275" )
				)
				( pin "dq(58)"
					( attribute "PN" "137"
						( Origin gPackager )
					)
					( objectStatus "J1G2.137" )
				)
				( pin "dq(59)"
					( attribute "PN" "282"
						( Origin gPackager )
					)
					( objectStatus "J1G2.282" )
				)
				( pin "dq(60)"
					( attribute "PN" "128"
						( Origin gPackager )
					)
					( objectStatus "J1G2.128" )
				)
				( pin "dq(61)"
					( attribute "PN" "273"
						( Origin gPackager )
					)
					( objectStatus "J1G2.273" )
				)
				( pin "dq(62)"
					( attribute "PN" "135"
						( Origin gPackager )
					)
					( objectStatus "J1G2.135" )
				)
				( pin "dq(63)"
					( attribute "PN" "280"
						( Origin gPackager )
					)
					( objectStatus "J1G2.280" )
				)
				( pin "event_n"
					( attribute "PN" "78"
						( Origin gPackager )
					)
					( objectStatus "J1G2.78" )
				)
				( pin "odt(0)"
					( attribute "PN" "87"
						( Origin gPackager )
					)
					( objectStatus "J1G2.87" )
				)
				( pin "odt(1)"
					( attribute "PN" "91"
						( Origin gPackager )
					)
					( objectStatus "J1G2.91" )
				)
				( pin "par"
					( attribute "PN" "222"
						( Origin gPackager )
					)
					( objectStatus "J1G2.222" )
				)
				( pin "reset_n"
					( attribute "PN" "58"
						( Origin gPackager )
					)
					( objectStatus "J1G2.58" )
				)
				( pin "rfu(0)"
					( attribute "PN" "205"
						( Origin gPackager )
					)
					( objectStatus "J1G2.205" )
				)
				( pin "rfu(1)"
					( attribute "PN" "227"
						( Origin gPackager )
					)
					( objectStatus "J1G2.227" )
				)
				( pin "rfu(2)"
					( attribute "PN" "144"
						( Origin gPackager )
					)
					( objectStatus "J1G2.144" )
				)
				( pin "s0_n"
					( attribute "PN" "84"
						( Origin gPackager )
					)
					( objectStatus "J1G2.84" )
				)
				( pin "s1_n"
					( attribute "PN" "89"
						( Origin gPackager )
					)
					( objectStatus "J1G2.89" )
				)
				( pin "s2_n_c(0)"
					( attribute "PN" "93"
						( Origin gPackager )
					)
					( objectStatus "J1G2.93" )
				)
				( pin "s3_n_c(1)"
					( attribute "PN" "237"
						( Origin gPackager )
					)
					( objectStatus "J1G2.237" )
				)
				( pin "sa(0)"
					( attribute "PN" "139"
						( Origin gPackager )
					)
					( objectStatus "J1G2.139" )
				)
				( pin "sa(1)"
					( attribute "PN" "140"
						( Origin gPackager )
					)
					( objectStatus "J1G2.140" )
				)
				( pin "sa(2)"
					( attribute "PN" "238"
						( Origin gPackager )
					)
					( objectStatus "J1G2.238" )
				)
				( pin "save_n_nc"
					( attribute "PN" "230"
						( Origin gPackager )
					)
					( objectStatus "J1G2.230" )
				)
				( pin "scl"
					( attribute "PN" "141"
						( Origin gPackager )
					)
					( objectStatus "J1G2.141" )
				)
				( pin "sda"
					( attribute "PN" "285"
						( Origin gPackager )
					)
					( objectStatus "J1G2.285" )
				)
				( pin "vddspd"
					( attribute "PN" "284"
						( Origin gPackager )
					)
					( objectStatus "J1G2.284" )
				)
				( pin "vrefca"
					( attribute "PN" "146"
						( Origin gPackager )
					)
					( objectStatus "J1G2.146" )
				)
			)
			( gate "@baseboard_fab2_lib.baseboard_fab2(sch_1):page79_i169"
				( attribute "BOM_COST" "MEM"
					( Origin gFrontEnd )
				)
				( attribute "CDS_LIB" "mstr_sconn"
					( Origin gPackager )
				)
				( attribute "CDS_LOCATION" "J1G2"
					( Origin gPackager )
				)
				( attribute "CDS_SEC" "4"
					( Origin gPackager )
				)
				( attribute "LOCATION" "J1G2"
					( Origin gFrontEnd )
				)
				( attribute "MATERIAL" "SCONN"
					( Origin gFrontEnd )
				)
				( attribute "PACK_TYPE" "PIP"
					( Origin gFrontEnd )
				)
				( attribute "PART_NUMBER" "H44441-004"
					( Origin gFrontEnd )
				)
				( attribute "PHYS_PAGE" "79"
					( Origin gFrontEnd )
				)
				( attribute "ROOM" "DDR4_CH_H"
					( Origin gFrontEnd )
				)
				( attribute "ROT" "0"
					( Origin gFrontEnd )
				)
				( attribute "SEC" "4"
					( Origin gFrontEnd )
				)
				( attribute "SEC_TYPE" "PIP"
					( Origin gFrontEnd )
				)
				( attribute "VER" "4"
					( Origin gFrontEnd )
				)
				( attribute "XY" "(-450,2000)"
					( Origin gFrontEnd )
				)
				( attribute "CHIPS_PART_NAME" "SCONN288_H44441004"
					( Origin gPackager )
				)
				( attribute "CDS_PART_NAME" "SCONN288_H44441004_PIP-SCONN,HA"
					( Origin gPackager )
				)
				( objectStatus "J1G2" )
				( pin "\12v\(0)"
					( attribute "PN" "145"
						( Origin gPackager )
					)
					( objectStatus "J1G2.145" )
				)
				( pin "\12v\(1)"
					( attribute "PN" "1"
						( Origin gPackager )
					)
					( objectStatus "J1G2.1" )
				)
				( pin "vdd(0)"
					( attribute "PN" "236"
						( Origin gPackager )
					)
					( objectStatus "J1G2.236" )
				)
				( pin "vdd(1)"
					( attribute "PN" "233"
						( Origin gPackager )
					)
					( objectStatus "J1G2.233" )
				)
				( pin "vdd(2)"
					( attribute "PN" "231"
						( Origin gPackager )
					)
					( objectStatus "J1G2.231" )
				)
				( pin "vdd(3)"
					( attribute "PN" "229"
						( Origin gPackager )
					)
					( objectStatus "J1G2.229" )
				)
				( pin "vdd(4)"
					( attribute "PN" "226"
						( Origin gPackager )
					)
					( objectStatus "J1G2.226" )
				)
				( pin "vdd(5)"
					( attribute "PN" "223"
						( Origin gPackager )
					)
					( objectStatus "J1G2.223" )
				)
				( pin "vdd(6)"
					( attribute "PN" "220"
						( Origin gPackager )
					)
					( objectStatus "J1G2.220" )
				)
				( pin "vdd(7)"
					( attribute "PN" "217"
						( Origin gPackager )
					)
					( objectStatus "J1G2.217" )
				)
				( pin "vdd(8)"
					( attribute "PN" "215"
						( Origin gPackager )
					)
					( objectStatus "J1G2.215" )
				)
				( pin "vdd(9)"
					( attribute "PN" "212"
						( Origin gPackager )
					)
					( objectStatus "J1G2.212" )
				)
				( pin "vdd(10)"
					( attribute "PN" "209"
						( Origin gPackager )
					)
					( objectStatus "J1G2.209" )
				)
				( pin "vdd(11)"
					( attribute "PN" "206"
						( Origin gPackager )
					)
					( objectStatus "J1G2.206" )
				)
				( pin "vdd(12)"
					( attribute "PN" "204"
						( Origin gPackager )
					)
					( objectStatus "J1G2.204" )
				)
				( pin "vdd(13)"
					( attribute "PN" "92"
						( Origin gPackager )
					)
					( objectStatus "J1G2.92" )
				)
				( pin "vdd(14)"
					( attribute "PN" "90"
						( Origin gPackager )
					)
					( objectStatus "J1G2.90" )
				)
				( pin "vdd(15)"
					( attribute "PN" "88"
						( Origin gPackager )
					)
					( objectStatus "J1G2.88" )
				)
				( pin "vdd(16)"
					( attribute "PN" "85"
						( Origin gPackager )
					)
					( objectStatus "J1G2.85" )
				)
				( pin "vdd(17)"
					( attribute "PN" "83"
						( Origin gPackager )
					)
					( objectStatus "J1G2.83" )
				)
				( pin "vdd(18)"
					( attribute "PN" "80"
						( Origin gPackager )
					)
					( objectStatus "J1G2.80" )
				)
				( pin "vdd(19)"
					( attribute "PN" "76"
						( Origin gPackager )
					)
					( objectStatus "J1G2.76" )
				)
				( pin "vdd(20)"
					( attribute "PN" "73"
						( Origin gPackager )
					)
					( objectStatus "J1G2.73" )
				)
				( pin "vdd(21)"
					( attribute "PN" "70"
						( Origin gPackager )
					)
					( objectStatus "J1G2.70" )
				)
				( pin "vdd(22)"
					( attribute "PN" "67"
						( Origin gPackager )
					)
					( objectStatus "J1G2.67" )
				)
				( pin "vdd(23)"
					( attribute "PN" "64"
						( Origin gPackager )
					)
					( objectStatus "J1G2.64" )
				)
				( pin "vdd(24)"
					( attribute "PN" "61"
						( Origin gPackager )
					)
					( objectStatus "J1G2.61" )
				)
				( pin "vdd(25)"
					( attribute "PN" "59"
						( Origin gPackager )
					)
					( objectStatus "J1G2.59" )
				)
				( pin "vpp(0)"
					( attribute "PN" "287"
						( Origin gPackager )
					)
					( objectStatus "J1G2.287" )
				)
				( pin "vpp(1)"
					( attribute "PN" "286"
						( Origin gPackager )
					)
					( objectStatus "J1G2.286" )
				)
				( pin "vpp(2)"
					( attribute "PN" "288"
						( Origin gPackager )
					)
					( objectStatus "J1G2.288" )
				)
				( pin "vpp(3)"
					( attribute "PN" "143"
						( Origin gPackager )
					)
					( objectStatus "J1G2.143" )
				)
				( pin "vpp(4)"
					( attribute "PN" "142"
						( Origin gPackager )
					)
					( objectStatus "J1G2.142" )
				)
				( pin "vtt(0)"
					( attribute "PN" "221"
						( Origin gPackager )
					)
					( objectStatus "J1G2.221" )
				)
				( pin "vtt(1)"
					( attribute "PN" "77"
						( Origin gPackager )
					)
					( objectStatus "J1G2.77" )
				)
			)
			( gate "@baseboard_fab2_lib.baseboard_fab2(sch_1):page79_i178"
				( attribute "BOM_COST" "MEM"
					( Origin gFrontEnd )
				)
				( attribute "CDS_LIB" "dev_discrete"
					( Origin gPackager )
				)
				( attribute "CDS_LOCATION" "C9U7"
					( Origin gPackager )
				)
				( attribute "CDS_SEC" "1"
					( Origin gPackager )
				)
				( attribute "LOCATION" "C9U7"
					( Origin gFrontEnd )
				)
				( attribute "MATERIAL" "X7R"
					( Origin gFrontEnd )
				)
				( attribute "PACK_TYPE" "0402V"
					( Origin gFrontEnd )
				)
				( attribute "PART_NUMBER" "A36096-045"
					( Origin gFrontEnd )
				)
				( attribute "PHYS_PAGE" "79"
					( Origin gFrontEnd )
				)
				( attribute "ROOM" "DDR4_CH_J"
					( Origin gFrontEnd )
				)
				( attribute "ROT" "2"
					( Origin gFrontEnd )
				)
				( attribute "SEC" "1"
					( Origin gPackager )
				)
				( attribute "TOLERANCE" "10%"
					( Origin gFrontEnd )
				)
				( attribute "VALUE" "0.01UF"
					( Origin gFrontEnd )
				)
				( attribute "VER" "1"
					( Origin gFrontEnd )
				)
				( attribute "VOLTAGE" "25V"
					( Units "uVoltage" "V" 1.000000)
					( Origin gFrontEnd )
				)
				( attribute "XY" "(-4600,1550)"
					( Origin gFrontEnd )
				)
				( attribute "CHIPS_PART_NAME" "CAP_A"
					( Origin gPackager )
				)
				( attribute "CDS_PART_NAME" "CAP_A_0402V-0.01UF,25V,10%,X7RA"
					( Origin gPackager )
				)
				( objectStatus "C9U7" )
				( pin "a"
					( attribute "PN" "1"
						( Origin gPackager )
					)
					( objectStatus "C9U7.1" )
				)
				( pin "b"
					( attribute "PN" "2"
						( Origin gPackager )
					)
					( objectStatus "C9U7.2" )
				)
			)
			( gate "@baseboard_fab2_lib.baseboard_fab2(sch_1):page80_i3"
				( attribute "BOM_COST" "MEM"
					( Origin gFrontEnd )
				)
				( attribute "CDS_LIB" "dev_discrete"
					( Origin gPackager )
				)
				( attribute "CDS_LOCATION" "C1G10"
					( Origin gPackager )
				)
				( attribute "CDS_SEC" "1"
					( Origin gPackager )
				)
				( attribute "LOCATION" "C1G10"
					( Origin gFrontEnd )
				)
				( attribute "MATERIAL" "X7R"
					( Origin gFrontEnd )
				)
				( attribute "PACK_TYPE" "0402V"
					( Origin gFrontEnd )
				)
				( attribute "PART_NUMBER" "A36096-045"
					( Origin gFrontEnd )
				)
				( attribute "PHYS_PAGE" "80"
					( Origin gFrontEnd )
				)
				( attribute "ROOM" "DDR4_GH_G"
					( Origin gFrontEnd )
				)
				( attribute "ROT" "2"
					( Origin gFrontEnd )
				)
				( attribute "SEC" "1"
					( Origin gPackager )
				)
				( attribute "TOLERANCE" "10%"
					( Origin gFrontEnd )
				)
				( attribute "VALUE" "0.01UF"
					( Origin gFrontEnd )
				)
				( attribute "VER" "1"
					( Origin gFrontEnd )
				)
				( attribute "VOLTAGE" "25V"
					( Units "uVoltage" "V" 1.000000)
					( Origin gFrontEnd )
				)
				( attribute "XY" "(-7225,1000)"
					( Origin gFrontEnd )
				)
				( attribute "CHIPS_PART_NAME" "CAP_A"
					( Origin gPackager )
				)
				( attribute "CDS_PART_NAME" "CAP_A_0402V-0.01UF,25V,10%,X7RA"
					( Origin gPackager )
				)
				( objectStatus "C1G10" )
				( pin "a"
					( attribute "PN" "1"
						( Origin gPackager )
					)
					( objectStatus "C1G10.1" )
				)
				( pin "b"
					( attribute "PN" "2"
						( Origin gPackager )
					)
					( objectStatus "C1G10.2" )
				)
			)
			( gate "@baseboard_fab2_lib.baseboard_fab2(sch_1):page80_i24"
				( attribute "BOM_COST" "MEM"
					( Origin gFrontEnd )
				)
				( attribute "CDS_LIB" "mstr_sconn"
					( Origin gPackager )
				)
				( attribute "CDS_LOCATION" "J9U1"
					( Origin gPackager )
				)
				( attribute "CDS_SEC" "1"
					( Origin gPackager )
				)
				( attribute "LOCATION" "J9U1"
					( Origin gFrontEnd )
				)
				( attribute "MATERIAL" "SCONN"
					( Origin gFrontEnd )
				)
				( attribute "PACK_TYPE" "PIP"
					( Origin gFrontEnd )
				)
				( attribute "PART_NUMBER" "H44441-003"
					( Origin gFrontEnd )
				)
				( attribute "PHYS_PAGE" "80"
					( Origin gFrontEnd )
				)
				( attribute "ROOM" "DDR4_GH_H"
					( Origin gFrontEnd )
				)
				( attribute "ROT" "0"
					( Origin gFrontEnd )
				)
				( attribute "SEC" "1"
					( Origin gFrontEnd )
				)
				( attribute "SEC_TYPE" "PIP"
					( Origin gFrontEnd )
				)
				( attribute "VER" "1"
					( Origin gFrontEnd )
				)
				( attribute "XY" "(-5225,2700)"
					( Origin gFrontEnd )
				)
				( attribute "CHIPS_PART_NAME" "SCONN288_H44441003"
					( Origin gPackager )
				)
				( attribute "CDS_PART_NAME" "SCONN288_H44441003_PIP-SCONN,HA"
					( Origin gPackager )
				)
				( objectStatus "J9U1" )
				( pin "a0"
					( attribute "PN" "79"
						( Origin gPackager )
					)
					( objectStatus "J9U1.79" )
				)
				( pin "a1"
					( attribute "PN" "72"
						( Origin gPackager )
					)
					( objectStatus "J9U1.72" )
				)
				( pin "a2"
					( attribute "PN" "216"
						( Origin gPackager )
					)
					( objectStatus "J9U1.216" )
				)
				( pin "a3"
					( attribute "PN" "71"
						( Origin gPackager )
					)
					( objectStatus "J9U1.71" )
				)
				( pin "a4"
					( attribute "PN" "214"
						( Origin gPackager )
					)
					( objectStatus "J9U1.214" )
				)
				( pin "a5"
					( attribute "PN" "213"
						( Origin gPackager )
					)
					( objectStatus "J9U1.213" )
				)
				( pin "a6"
					( attribute "PN" "69"
						( Origin gPackager )
					)
					( objectStatus "J9U1.69" )
				)
				( pin "a7"
					( attribute "PN" "211"
						( Origin gPackager )
					)
					( objectStatus "J9U1.211" )
				)
				( pin "a8"
					( attribute "PN" "68"
						( Origin gPackager )
					)
					( objectStatus "J9U1.68" )
				)
				( pin "a9"
					( attribute "PN" "66"
						( Origin gPackager )
					)
					( objectStatus "J9U1.66" )
				)
				( pin "a10"
					( attribute "PN" "225"
						( Origin gPackager )
					)
					( objectStatus "J9U1.225" )
				)
				( pin "a11"
					( attribute "PN" "210"
						( Origin gPackager )
					)
					( objectStatus "J9U1.210" )
				)
				( pin "a12"
					( attribute "PN" "65"
						( Origin gPackager )
					)
					( objectStatus "J9U1.65" )
				)
				( pin "a13"
					( attribute "PN" "232"
						( Origin gPackager )
					)
					( objectStatus "J9U1.232" )
				)
				( pin "a14_we_n"
					( attribute "PN" "228"
						( Origin gPackager )
					)
					( objectStatus "J9U1.228" )
				)
				( pin "a15_cas_n"
					( attribute "PN" "86"
						( Origin gPackager )
					)
					( objectStatus "J9U1.86" )
				)
				( pin "a16_ras_n"
					( attribute "PN" "82"
						( Origin gPackager )
					)
					( objectStatus "J9U1.82" )
				)
				( pin "a17"
					( attribute "PN" "234"
						( Origin gPackager )
					)
					( objectStatus "J9U1.234" )
				)
				( pin "act_n"
					( attribute "PN" "62"
						( Origin gPackager )
					)
					( objectStatus "J9U1.62" )
				)
				( pin "alert_n"
					( attribute "PN" "208"
						( Origin gPackager )
					)
					( objectStatus "J9U1.208" )
				)
				( pin "ba(0)"
					( attribute "PN" "81"
						( Origin gPackager )
					)
					( objectStatus "J9U1.81" )
				)
				( pin "ba(1)"
					( attribute "PN" "224"
						( Origin gPackager )
					)
					( objectStatus "J9U1.224" )
				)
				( pin "bg(0)"
					( attribute "PN" "63"
						( Origin gPackager )
					)
					( objectStatus "J9U1.63" )
				)
				( pin "bg(1)"
					( attribute "PN" "207"
						( Origin gPackager )
					)
					( objectStatus "J9U1.207" )
				)
				( pin "c(2)"
					( attribute "PN" "235"
						( Origin gPackager )
					)
					( objectStatus "J9U1.235" )
				)
				( pin "cb(0)"
					( attribute "PN" "49"
						( Origin gPackager )
					)
					( objectStatus "J9U1.49" )
				)
				( pin "cb(1)"
					( attribute "PN" "194"
						( Origin gPackager )
					)
					( objectStatus "J9U1.194" )
				)
				( pin "cb(2)"
					( attribute "PN" "56"
						( Origin gPackager )
					)
					( objectStatus "J9U1.56" )
				)
				( pin "cb(3)"
					( attribute "PN" "201"
						( Origin gPackager )
					)
					( objectStatus "J9U1.201" )
				)
				( pin "cb(4)"
					( attribute "PN" "47"
						( Origin gPackager )
					)
					( objectStatus "J9U1.47" )
				)
				( pin "cb(5)"
					( attribute "PN" "192"
						( Origin gPackager )
					)
					( objectStatus "J9U1.192" )
				)
				( pin "cb(6)"
					( attribute "PN" "54"
						( Origin gPackager )
					)
					( objectStatus "J9U1.54" )
				)
				( pin "cb(7)"
					( attribute "PN" "199"
						( Origin gPackager )
					)
					( objectStatus "J9U1.199" )
				)
				( pin "ck0n"
					( attribute "PN" "75"
						( Origin gPackager )
					)
					( objectStatus "J9U1.75" )
				)
				( pin "ck0p"
					( attribute "PN" "74"
						( Origin gPackager )
					)
					( objectStatus "J9U1.74" )
				)
				( pin "ck1n"
					( attribute "PN" "219"
						( Origin gPackager )
					)
					( objectStatus "J9U1.219" )
				)
				( pin "ck1p"
					( attribute "PN" "218"
						( Origin gPackager )
					)
					( objectStatus "J9U1.218" )
				)
				( pin "cke(0)"
					( attribute "PN" "60"
						( Origin gPackager )
					)
					( objectStatus "J9U1.60" )
				)
				( pin "cke(1)"
					( attribute "PN" "203"
						( Origin gPackager )
					)
					( objectStatus "J9U1.203" )
				)
				( pin "dq(0)"
					( attribute "PN" "5"
						( Origin gPackager )
					)
					( objectStatus "J9U1.5" )
				)
				( pin "dq(1)"
					( attribute "PN" "150"
						( Origin gPackager )
					)
					( objectStatus "J9U1.150" )
				)
				( pin "dq(2)"
					( attribute "PN" "12"
						( Origin gPackager )
					)
					( objectStatus "J9U1.12" )
				)
				( pin "dq(3)"
					( attribute "PN" "157"
						( Origin gPackager )
					)
					( objectStatus "J9U1.157" )
				)
				( pin "dq(4)"
					( attribute "PN" "3"
						( Origin gPackager )
					)
					( objectStatus "J9U1.3" )
				)
				( pin "dq(5)"
					( attribute "PN" "148"
						( Origin gPackager )
					)
					( objectStatus "J9U1.148" )
				)
				( pin "dq(6)"
					( attribute "PN" "10"
						( Origin gPackager )
					)
					( objectStatus "J9U1.10" )
				)
				( pin "dq(7)"
					( attribute "PN" "155"
						( Origin gPackager )
					)
					( objectStatus "J9U1.155" )
				)
				( pin "dq(8)"
					( attribute "PN" "16"
						( Origin gPackager )
					)
					( objectStatus "J9U1.16" )
				)
				( pin "dq(9)"
					( attribute "PN" "161"
						( Origin gPackager )
					)
					( objectStatus "J9U1.161" )
				)
				( pin "dq(10)"
					( attribute "PN" "23"
						( Origin gPackager )
					)
					( objectStatus "J9U1.23" )
				)
				( pin "dq(11)"
					( attribute "PN" "168"
						( Origin gPackager )
					)
					( objectStatus "J9U1.168" )
				)
				( pin "dq(12)"
					( attribute "PN" "14"
						( Origin gPackager )
					)
					( objectStatus "J9U1.14" )
				)
				( pin "dq(13)"
					( attribute "PN" "159"
						( Origin gPackager )
					)
					( objectStatus "J9U1.159" )
				)
				( pin "dq(14)"
					( attribute "PN" "21"
						( Origin gPackager )
					)
					( objectStatus "J9U1.21" )
				)
				( pin "dq(15)"
					( attribute "PN" "166"
						( Origin gPackager )
					)
					( objectStatus "J9U1.166" )
				)
				( pin "dq(16)"
					( attribute "PN" "27"
						( Origin gPackager )
					)
					( objectStatus "J9U1.27" )
				)
				( pin "dq(17)"
					( attribute "PN" "172"
						( Origin gPackager )
					)
					( objectStatus "J9U1.172" )
				)
				( pin "dq(18)"
					( attribute "PN" "34"
						( Origin gPackager )
					)
					( objectStatus "J9U1.34" )
				)
				( pin "dq(19)"
					( attribute "PN" "179"
						( Origin gPackager )
					)
					( objectStatus "J9U1.179" )
				)
				( pin "dq(20)"
					( attribute "PN" "25"
						( Origin gPackager )
					)
					( objectStatus "J9U1.25" )
				)
				( pin "dq(21)"
					( attribute "PN" "170"
						( Origin gPackager )
					)
					( objectStatus "J9U1.170" )
				)
				( pin "dq(22)"
					( attribute "PN" "32"
						( Origin gPackager )
					)
					( objectStatus "J9U1.32" )
				)
				( pin "dq(23)"
					( attribute "PN" "177"
						( Origin gPackager )
					)
					( objectStatus "J9U1.177" )
				)
				( pin "dq(24)"
					( attribute "PN" "38"
						( Origin gPackager )
					)
					( objectStatus "J9U1.38" )
				)
				( pin "dq(25)"
					( attribute "PN" "183"
						( Origin gPackager )
					)
					( objectStatus "J9U1.183" )
				)
				( pin "dq(26)"
					( attribute "PN" "45"
						( Origin gPackager )
					)
					( objectStatus "J9U1.45" )
				)
				( pin "dq(27)"
					( attribute "PN" "190"
						( Origin gPackager )
					)
					( objectStatus "J9U1.190" )
				)
				( pin "dq(28)"
					( attribute "PN" "36"
						( Origin gPackager )
					)
					( objectStatus "J9U1.36" )
				)
				( pin "dq(29)"
					( attribute "PN" "181"
						( Origin gPackager )
					)
					( objectStatus "J9U1.181" )
				)
				( pin "dq(30)"
					( attribute "PN" "43"
						( Origin gPackager )
					)
					( objectStatus "J9U1.43" )
				)
				( pin "dq(31)"
					( attribute "PN" "188"
						( Origin gPackager )
					)
					( objectStatus "J9U1.188" )
				)
				( pin "dq(32)"
					( attribute "PN" "97"
						( Origin gPackager )
					)
					( objectStatus "J9U1.97" )
				)
				( pin "dq(33)"
					( attribute "PN" "242"
						( Origin gPackager )
					)
					( objectStatus "J9U1.242" )
				)
				( pin "dq(34)"
					( attribute "PN" "104"
						( Origin gPackager )
					)
					( objectStatus "J9U1.104" )
				)
				( pin "dq(35)"
					( attribute "PN" "249"
						( Origin gPackager )
					)
					( objectStatus "J9U1.249" )
				)
				( pin "dq(36)"
					( attribute "PN" "95"
						( Origin gPackager )
					)
					( objectStatus "J9U1.95" )
				)
				( pin "dq(37)"
					( attribute "PN" "240"
						( Origin gPackager )
					)
					( objectStatus "J9U1.240" )
				)
				( pin "dq(38)"
					( attribute "PN" "102"
						( Origin gPackager )
					)
					( objectStatus "J9U1.102" )
				)
				( pin "dq(39)"
					( attribute "PN" "247"
						( Origin gPackager )
					)
					( objectStatus "J9U1.247" )
				)
				( pin "dq(40)"
					( attribute "PN" "108"
						( Origin gPackager )
					)
					( objectStatus "J9U1.108" )
				)
				( pin "dq(41)"
					( attribute "PN" "253"
						( Origin gPackager )
					)
					( objectStatus "J9U1.253" )
				)
				( pin "dq(42)"
					( attribute "PN" "115"
						( Origin gPackager )
					)
					( objectStatus "J9U1.115" )
				)
				( pin "dq(43)"
					( attribute "PN" "260"
						( Origin gPackager )
					)
					( objectStatus "J9U1.260" )
				)
				( pin "dq(44)"
					( attribute "PN" "106"
						( Origin gPackager )
					)
					( objectStatus "J9U1.106" )
				)
				( pin "dq(45)"
					( attribute "PN" "251"
						( Origin gPackager )
					)
					( objectStatus "J9U1.251" )
				)
				( pin "dq(46)"
					( attribute "PN" "113"
						( Origin gPackager )
					)
					( objectStatus "J9U1.113" )
				)
				( pin "dq(47)"
					( attribute "PN" "258"
						( Origin gPackager )
					)
					( objectStatus "J9U1.258" )
				)
				( pin "dq(48)"
					( attribute "PN" "119"
						( Origin gPackager )
					)
					( objectStatus "J9U1.119" )
				)
				( pin "dq(49)"
					( attribute "PN" "264"
						( Origin gPackager )
					)
					( objectStatus "J9U1.264" )
				)
				( pin "dq(50)"
					( attribute "PN" "126"
						( Origin gPackager )
					)
					( objectStatus "J9U1.126" )
				)
				( pin "dq(51)"
					( attribute "PN" "271"
						( Origin gPackager )
					)
					( objectStatus "J9U1.271" )
				)
				( pin "dq(52)"
					( attribute "PN" "117"
						( Origin gPackager )
					)
					( objectStatus "J9U1.117" )
				)
				( pin "dq(53)"
					( attribute "PN" "262"
						( Origin gPackager )
					)
					( objectStatus "J9U1.262" )
				)
				( pin "dq(54)"
					( attribute "PN" "124"
						( Origin gPackager )
					)
					( objectStatus "J9U1.124" )
				)
				( pin "dq(55)"
					( attribute "PN" "269"
						( Origin gPackager )
					)
					( objectStatus "J9U1.269" )
				)
				( pin "dq(56)"
					( attribute "PN" "130"
						( Origin gPackager )
					)
					( objectStatus "J9U1.130" )
				)
				( pin "dq(57)"
					( attribute "PN" "275"
						( Origin gPackager )
					)
					( objectStatus "J9U1.275" )
				)
				( pin "dq(58)"
					( attribute "PN" "137"
						( Origin gPackager )
					)
					( objectStatus "J9U1.137" )
				)
				( pin "dq(59)"
					( attribute "PN" "282"
						( Origin gPackager )
					)
					( objectStatus "J9U1.282" )
				)
				( pin "dq(60)"
					( attribute "PN" "128"
						( Origin gPackager )
					)
					( objectStatus "J9U1.128" )
				)
				( pin "dq(61)"
					( attribute "PN" "273"
						( Origin gPackager )
					)
					( objectStatus "J9U1.273" )
				)
				( pin "dq(62)"
					( attribute "PN" "135"
						( Origin gPackager )
					)
					( objectStatus "J9U1.135" )
				)
				( pin "dq(63)"
					( attribute "PN" "280"
						( Origin gPackager )
					)
					( objectStatus "J9U1.280" )
				)
				( pin "event_n"
					( attribute "PN" "78"
						( Origin gPackager )
					)
					( objectStatus "J9U1.78" )
				)
				( pin "odt(0)"
					( attribute "PN" "87"
						( Origin gPackager )
					)
					( objectStatus "J9U1.87" )
				)
				( pin "odt(1)"
					( attribute "PN" "91"
						( Origin gPackager )
					)
					( objectStatus "J9U1.91" )
				)
				( pin "par"
					( attribute "PN" "222"
						( Origin gPackager )
					)
					( objectStatus "J9U1.222" )
				)
				( pin "reset_n"
					( attribute "PN" "58"
						( Origin gPackager )
					)
					( objectStatus "J9U1.58" )
				)
				( pin "rfu(0)"
					( attribute "PN" "205"
						( Origin gPackager )
					)
					( objectStatus "J9U1.205" )
				)
				( pin "rfu(1)"
					( attribute "PN" "227"
						( Origin gPackager )
					)
					( objectStatus "J9U1.227" )
				)
				( pin "rfu(2)"
					( attribute "PN" "144"
						( Origin gPackager )
					)
					( objectStatus "J9U1.144" )
				)
				( pin "s0_n"
					( attribute "PN" "84"
						( Origin gPackager )
					)
					( objectStatus "J9U1.84" )
				)
				( pin "s1_n"
					( attribute "PN" "89"
						( Origin gPackager )
					)
					( objectStatus "J9U1.89" )
				)
				( pin "s2_n_c(0)"
					( attribute "PN" "93"
						( Origin gPackager )
					)
					( objectStatus "J9U1.93" )
				)
				( pin "s3_n_c(1)"
					( attribute "PN" "237"
						( Origin gPackager )
					)
					( objectStatus "J9U1.237" )
				)
				( pin "sa(0)"
					( attribute "PN" "139"
						( Origin gPackager )
					)
					( objectStatus "J9U1.139" )
				)
				( pin "sa(1)"
					( attribute "PN" "140"
						( Origin gPackager )
					)
					( objectStatus "J9U1.140" )
				)
				( pin "sa(2)"
					( attribute "PN" "238"
						( Origin gPackager )
					)
					( objectStatus "J9U1.238" )
				)
				( pin "save_n_nc"
					( attribute "PN" "230"
						( Origin gPackager )
					)
					( objectStatus "J9U1.230" )
				)
				( pin "scl"
					( attribute "PN" "141"
						( Origin gPackager )
					)
					( objectStatus "J9U1.141" )
				)
				( pin "sda"
					( attribute "PN" "285"
						( Origin gPackager )
					)
					( objectStatus "J9U1.285" )
				)
				( pin "vddspd"
					( attribute "PN" "284"
						( Origin gPackager )
					)
					( objectStatus "J9U1.284" )
				)
				( pin "vrefca"
					( attribute "PN" "146"
						( Origin gPackager )
					)
					( objectStatus "J9U1.146" )
				)
			)
			( gate "@baseboard_fab2_lib.baseboard_fab2(sch_1):page80_i56"
				( attribute "BOM_COST" "MEM"
					( Origin gFrontEnd )
				)
				( attribute "CDS_LIB" "mstr_sconn"
					( Origin gPackager )
				)
				( attribute "CDS_LOCATION" "J9U1"
					( Origin gPackager )
				)
				( attribute "CDS_SEC" "4"
					( Origin gPackager )
				)
				( attribute "LOCATION" "J9U1"
					( Origin gFrontEnd )
				)
				( attribute "MATERIAL" "SCONN"
					( Origin gFrontEnd )
				)
				( attribute "PACK_TYPE" "PIP"
					( Origin gFrontEnd )
				)
				( attribute "PART_NUMBER" "H44441-003"
					( Origin gFrontEnd )
				)
				( attribute "PHYS_PAGE" "80"
					( Origin gFrontEnd )
				)
				( attribute "ROOM" "DDR4_GH_H"
					( Origin gFrontEnd )
				)
				( attribute "ROT" "0"
					( Origin gFrontEnd )
				)
				( attribute "SEC" "4"
					( Origin gFrontEnd )
				)
				( attribute "SEC_TYPE" "PIP"
					( Origin gFrontEnd )
				)
				( attribute "VER" "4"
					( Origin gFrontEnd )
				)
				( attribute "XY" "(-3075,1450)"
					( Origin gFrontEnd )
				)
				( attribute "CHIPS_PART_NAME" "SCONN288_H44441003"
					( Origin gPackager )
				)
				( attribute "CDS_PART_NAME" "SCONN288_H44441003_PIP-SCONN,HA"
					( Origin gPackager )
				)
				( objectStatus "J9U1" )
				( pin "\12v\(0)"
					( attribute "PN" "145"
						( Origin gPackager )
					)
					( objectStatus "J9U1.145" )
				)
				( pin "\12v\(1)"
					( attribute "PN" "1"
						( Origin gPackager )
					)
					( objectStatus "J9U1.1" )
				)
				( pin "vdd(0)"
					( attribute "PN" "236"
						( Origin gPackager )
					)
					( objectStatus "J9U1.236" )
				)
				( pin "vdd(1)"
					( attribute "PN" "233"
						( Origin gPackager )
					)
					( objectStatus "J9U1.233" )
				)
				( pin "vdd(2)"
					( attribute "PN" "231"
						( Origin gPackager )
					)
					( objectStatus "J9U1.231" )
				)
				( pin "vdd(3)"
					( attribute "PN" "229"
						( Origin gPackager )
					)
					( objectStatus "J9U1.229" )
				)
				( pin "vdd(4)"
					( attribute "PN" "226"
						( Origin gPackager )
					)
					( objectStatus "J9U1.226" )
				)
				( pin "vdd(5)"
					( attribute "PN" "223"
						( Origin gPackager )
					)
					( objectStatus "J9U1.223" )
				)
				( pin "vdd(6)"
					( attribute "PN" "220"
						( Origin gPackager )
					)
					( objectStatus "J9U1.220" )
				)
				( pin "vdd(7)"
					( attribute "PN" "217"
						( Origin gPackager )
					)
					( objectStatus "J9U1.217" )
				)
				( pin "vdd(8)"
					( attribute "PN" "215"
						( Origin gPackager )
					)
					( objectStatus "J9U1.215" )
				)
				( pin "vdd(9)"
					( attribute "PN" "212"
						( Origin gPackager )
					)
					( objectStatus "J9U1.212" )
				)
				( pin "vdd(10)"
					( attribute "PN" "209"
						( Origin gPackager )
					)
					( objectStatus "J9U1.209" )
				)
				( pin "vdd(11)"
					( attribute "PN" "206"
						( Origin gPackager )
					)
					( objectStatus "J9U1.206" )
				)
				( pin "vdd(12)"
					( attribute "PN" "204"
						( Origin gPackager )
					)
					( objectStatus "J9U1.204" )
				)
				( pin "vdd(13)"
					( attribute "PN" "92"
						( Origin gPackager )
					)
					( objectStatus "J9U1.92" )
				)
				( pin "vdd(14)"
					( attribute "PN" "90"
						( Origin gPackager )
					)
					( objectStatus "J9U1.90" )
				)
				( pin "vdd(15)"
					( attribute "PN" "88"
						( Origin gPackager )
					)
					( objectStatus "J9U1.88" )
				)
				( pin "vdd(16)"
					( attribute "PN" "85"
						( Origin gPackager )
					)
					( objectStatus "J9U1.85" )
				)
				( pin "vdd(17)"
					( attribute "PN" "83"
						( Origin gPackager )
					)
					( objectStatus "J9U1.83" )
				)
				( pin "vdd(18)"
					( attribute "PN" "80"
						( Origin gPackager )
					)
					( objectStatus "J9U1.80" )
				)
				( pin "vdd(19)"
					( attribute "PN" "76"
						( Origin gPackager )
					)
					( objectStatus "J9U1.76" )
				)
				( pin "vdd(20)"
					( attribute "PN" "73"
						( Origin gPackager )
					)
					( objectStatus "J9U1.73" )
				)
				( pin "vdd(21)"
					( attribute "PN" "70"
						( Origin gPackager )
					)
					( objectStatus "J9U1.70" )
				)
				( pin "vdd(22)"
					( attribute "PN" "67"
						( Origin gPackager )
					)
					( objectStatus "J9U1.67" )
				)
				( pin "vdd(23)"
					( attribute "PN" "64"
						( Origin gPackager )
					)
					( objectStatus "J9U1.64" )
				)
				( pin "vdd(24)"
					( attribute "PN" "61"
						( Origin gPackager )
					)
					( objectStatus "J9U1.61" )
				)
				( pin "vdd(25)"
					( attribute "PN" "59"
						( Origin gPackager )
					)
					( objectStatus "J9U1.59" )
				)
				( pin "vpp(0)"
					( attribute "PN" "287"
						( Origin gPackager )
					)
					( objectStatus "J9U1.287" )
				)
				( pin "vpp(1)"
					( attribute "PN" "286"
						( Origin gPackager )
					)
					( objectStatus "J9U1.286" )
				)
				( pin "vpp(2)"
					( attribute "PN" "288"
						( Origin gPackager )
					)
					( objectStatus "J9U1.288" )
				)
				( pin "vpp(3)"
					( attribute "PN" "143"
						( Origin gPackager )
					)
					( objectStatus "J9U1.143" )
				)
				( pin "vpp(4)"
					( attribute "PN" "142"
						( Origin gPackager )
					)
					( objectStatus "J9U1.142" )
				)
				( pin "vtt(0)"
					( attribute "PN" "221"
						( Origin gPackager )
					)
					( objectStatus "J9U1.221" )
				)
				( pin "vtt(1)"
					( attribute "PN" "77"
						( Origin gPackager )
					)
					( objectStatus "J9U1.77" )
				)
			)
			( gate "@baseboard_fab2_lib.baseboard_fab2(sch_1):page80_i101"
				( attribute "BOM_COST" "MEM"
					( Origin gFrontEnd )
				)
				( attribute "CDS_LIB" "mstr_sconn"
					( Origin gPackager )
				)
				( attribute "CDS_LOCATION" "J9U1"
					( Origin gPackager )
				)
				( attribute "CDS_SEC" "2"
					( Origin gPackager )
				)
				( attribute "LOCATION" "J9U1"
					( Origin gFrontEnd )
				)
				( attribute "MATERIAL" "SCONN"
					( Origin gFrontEnd )
				)
				( attribute "PACK_TYPE" "PIP"
					( Origin gFrontEnd )
				)
				( attribute "PART_NUMBER" "H44441-003"
					( Origin gFrontEnd )
				)
				( attribute "PHYS_PAGE" "80"
					( Origin gFrontEnd )
				)
				( attribute "ROOM" "DDR4_GH_H"
					( Origin gFrontEnd )
				)
				( attribute "ROT" "0"
					( Origin gFrontEnd )
				)
				( attribute "SEC" "2"
					( Origin gFrontEnd )
				)
				( attribute "SEC_TYPE" "PIP"
					( Origin gFrontEnd )
				)
				( attribute "VER" "2"
					( Origin gFrontEnd )
				)
				( attribute "XY" "(-2675,3750)"
					( Origin gFrontEnd )
				)
				( attribute "CHIPS_PART_NAME" "SCONN288_H44441003"
					( Origin gPackager )
				)
				( attribute "CDS_PART_NAME" "SCONN288_H44441003_PIP-SCONN,HA"
					( Origin gPackager )
				)
				( objectStatus "J9U1" )
				( pin "dqs0n"
					( attribute "PN" "152"
						( Origin gPackager )
					)
					( objectStatus "J9U1.152" )
				)
				( pin "dqs0p"
					( attribute "PN" "153"
						( Origin gPackager )
					)
					( objectStatus "J9U1.153" )
				)
				( pin "dqs1n"
					( attribute "PN" "163"
						( Origin gPackager )
					)
					( objectStatus "J9U1.163" )
				)
				( pin "dqs1p"
					( attribute "PN" "164"
						( Origin gPackager )
					)
					( objectStatus "J9U1.164" )
				)
				( pin "dqs2n"
					( attribute "PN" "174"
						( Origin gPackager )
					)
					( objectStatus "J9U1.174" )
				)
				( pin "dqs2p"
					( attribute "PN" "175"
						( Origin gPackager )
					)
					( objectStatus "J9U1.175" )
				)
				( pin "dqs3n"
					( attribute "PN" "185"
						( Origin gPackager )
					)
					( objectStatus "J9U1.185" )
				)
				( pin "dqs3p"
					( attribute "PN" "186"
						( Origin gPackager )
					)
					( objectStatus "J9U1.186" )
				)
				( pin "dqs4n"
					( attribute "PN" "244"
						( Origin gPackager )
					)
					( objectStatus "J9U1.244" )
				)
				( pin "dqs4p"
					( attribute "PN" "245"
						( Origin gPackager )
					)
					( objectStatus "J9U1.245" )
				)
				( pin "dqs5n"
					( attribute "PN" "255"
						( Origin gPackager )
					)
					( objectStatus "J9U1.255" )
				)
				( pin "dqs5p"
					( attribute "PN" "256"
						( Origin gPackager )
					)
					( objectStatus "J9U1.256" )
				)
				( pin "dqs6n"
					( attribute "PN" "266"
						( Origin gPackager )
					)
					( objectStatus "J9U1.266" )
				)
				( pin "dqs6p"
					( attribute "PN" "267"
						( Origin gPackager )
					)
					( objectStatus "J9U1.267" )
				)
				( pin "dqs7n"
					( attribute "PN" "277"
						( Origin gPackager )
					)
					( objectStatus "J9U1.277" )
				)
				( pin "dqs7p"
					( attribute "PN" "278"
						( Origin gPackager )
					)
					( objectStatus "J9U1.278" )
				)
				( pin "dqs8n"
					( attribute "PN" "196"
						( Origin gPackager )
					)
					( objectStatus "J9U1.196" )
				)
				( pin "dqs8p"
					( attribute "PN" "197"
						( Origin gPackager )
					)
					( objectStatus "J9U1.197" )
				)
				( pin "dqs9n"
					( attribute "PN" "8"
						( Origin gPackager )
					)
					( objectStatus "J9U1.8" )
				)
				( pin "dqs9p"
					( attribute "PN" "7"
						( Origin gPackager )
					)
					( objectStatus "J9U1.7" )
				)
				( pin "dqs10n"
					( attribute "PN" "19"
						( Origin gPackager )
					)
					( objectStatus "J9U1.19" )
				)
				( pin "dqs10p"
					( attribute "PN" "18"
						( Origin gPackager )
					)
					( objectStatus "J9U1.18" )
				)
				( pin "dqs11n"
					( attribute "PN" "30"
						( Origin gPackager )
					)
					( objectStatus "J9U1.30" )
				)
				( pin "dqs11p"
					( attribute "PN" "29"
						( Origin gPackager )
					)
					( objectStatus "J9U1.29" )
				)
				( pin "dqs12n"
					( attribute "PN" "41"
						( Origin gPackager )
					)
					( objectStatus "J9U1.41" )
				)
				( pin "dqs12p"
					( attribute "PN" "40"
						( Origin gPackager )
					)
					( objectStatus "J9U1.40" )
				)
				( pin "dqs13n"
					( attribute "PN" "100"
						( Origin gPackager )
					)
					( objectStatus "J9U1.100" )
				)
				( pin "dqs13p"
					( attribute "PN" "99"
						( Origin gPackager )
					)
					( objectStatus "J9U1.99" )
				)
				( pin "dqs14n"
					( attribute "PN" "111"
						( Origin gPackager )
					)
					( objectStatus "J9U1.111" )
				)
				( pin "dqs14p"
					( attribute "PN" "110"
						( Origin gPackager )
					)
					( objectStatus "J9U1.110" )
				)
				( pin "dqs15n"
					( attribute "PN" "122"
						( Origin gPackager )
					)
					( objectStatus "J9U1.122" )
				)
				( pin "dqs15p"
					( attribute "PN" "121"
						( Origin gPackager )
					)
					( objectStatus "J9U1.121" )
				)
				( pin "dqs16n"
					( attribute "PN" "133"
						( Origin gPackager )
					)
					( objectStatus "J9U1.133" )
				)
				( pin "dqs16p"
					( attribute "PN" "132"
						( Origin gPackager )
					)
					( objectStatus "J9U1.132" )
				)
				( pin "dqs17n"
					( attribute "PN" "52"
						( Origin gPackager )
					)
					( objectStatus "J9U1.52" )
				)
				( pin "dqs17p"
					( attribute "PN" "51"
						( Origin gPackager )
					)
					( objectStatus "J9U1.51" )
				)
			)
			( gate "@baseboard_fab2_lib.baseboard_fab2(sch_1):page80_i138"
				( attribute "BOM_COST" "MEM"
					( Origin gFrontEnd )
				)
				( attribute "CDS_LIB" "mstr_sconn"
					( Origin gPackager )
				)
				( attribute "CDS_LOCATION" "J9U1"
					( Origin gPackager )
				)
				( attribute "CDS_SEC" "3"
					( Origin gPackager )
				)
				( attribute "LOCATION" "J9U1"
					( Origin gFrontEnd )
				)
				( attribute "MATERIAL" "SCONN"
					( Origin gFrontEnd )
				)
				( attribute "PACK_TYPE" "PIP"
					( Origin gFrontEnd )
				)
				( attribute "PART_NUMBER" "H44441-003"
					( Origin gFrontEnd )
				)
				( attribute "PHYS_PAGE" "80"
					( Origin gFrontEnd )
				)
				( attribute "ROOM" "DDR4_GH_H"
					( Origin gFrontEnd )
				)
				( attribute "ROT" "0"
					( Origin gFrontEnd )
				)
				( attribute "SEC" "3"
					( Origin gFrontEnd )
				)
				( attribute "SEC_TYPE" "PIP"
					( Origin gFrontEnd )
				)
				( attribute "VER" "3"
					( Origin gFrontEnd )
				)
				( attribute "XY" "(-875,1850)"
					( Origin gFrontEnd )
				)
				( attribute "CHIPS_PART_NAME" "SCONN288_H44441003"
					( Origin gPackager )
				)
				( attribute "CDS_PART_NAME" "SCONN288_H44441003_PIP-SCONN,HA"
					( Origin gPackager )
				)
				( objectStatus "J9U1" )
				( pin "vss(0)"
					( attribute "PN" "283"
						( Origin gPackager )
					)
					( objectStatus "J9U1.283" )
				)
				( pin "vss(1)"
					( attribute "PN" "281"
						( Origin gPackager )
					)
					( objectStatus "J9U1.281" )
				)
				( pin "vss(2)"
					( attribute "PN" "279"
						( Origin gPackager )
					)
					( objectStatus "J9U1.279" )
				)
				( pin "vss(3)"
					( attribute "PN" "276"
						( Origin gPackager )
					)
					( objectStatus "J9U1.276" )
				)
				( pin "vss(4)"
					( attribute "PN" "274"
						( Origin gPackager )
					)
					( objectStatus "J9U1.274" )
				)
				( pin "vss(5)"
					( attribute "PN" "272"
						( Origin gPackager )
					)
					( objectStatus "J9U1.272" )
				)
				( pin "vss(6)"
					( attribute "PN" "270"
						( Origin gPackager )
					)
					( objectStatus "J9U1.270" )
				)
				( pin "vss(7)"
					( attribute "PN" "268"
						( Origin gPackager )
					)
					( objectStatus "J9U1.268" )
				)
				( pin "vss(8)"
					( attribute "PN" "265"
						( Origin gPackager )
					)
					( objectStatus "J9U1.265" )
				)
				( pin "vss(9)"
					( attribute "PN" "263"
						( Origin gPackager )
					)
					( objectStatus "J9U1.263" )
				)
				( pin "vss(10)"
					( attribute "PN" "261"
						( Origin gPackager )
					)
					( objectStatus "J9U1.261" )
				)
				( pin "vss(11)"
					( attribute "PN" "259"
						( Origin gPackager )
					)
					( objectStatus "J9U1.259" )
				)
				( pin "vss(12)"
					( attribute "PN" "257"
						( Origin gPackager )
					)
					( objectStatus "J9U1.257" )
				)
				( pin "vss(13)"
					( attribute "PN" "254"
						( Origin gPackager )
					)
					( objectStatus "J9U1.254" )
				)
				( pin "vss(14)"
					( attribute "PN" "252"
						( Origin gPackager )
					)
					( objectStatus "J9U1.252" )
				)
				( pin "vss(15)"
					( attribute "PN" "250"
						( Origin gPackager )
					)
					( objectStatus "J9U1.250" )
				)
				( pin "vss(16)"
					( attribute "PN" "248"
						( Origin gPackager )
					)
					( objectStatus "J9U1.248" )
				)
				( pin "vss(17)"
					( attribute "PN" "246"
						( Origin gPackager )
					)
					( objectStatus "J9U1.246" )
				)
				( pin "vss(18)"
					( attribute "PN" "243"
						( Origin gPackager )
					)
					( objectStatus "J9U1.243" )
				)
				( pin "vss(19)"
					( attribute "PN" "241"
						( Origin gPackager )
					)
					( objectStatus "J9U1.241" )
				)
				( pin "vss(20)"
					( attribute "PN" "239"
						( Origin gPackager )
					)
					( objectStatus "J9U1.239" )
				)
				( pin "vss(21)"
					( attribute "PN" "202"
						( Origin gPackager )
					)
					( objectStatus "J9U1.202" )
				)
				( pin "vss(22)"
					( attribute "PN" "200"
						( Origin gPackager )
					)
					( objectStatus "J9U1.200" )
				)
				( pin "vss(23)"
					( attribute "PN" "198"
						( Origin gPackager )
					)
					( objectStatus "J9U1.198" )
				)
				( pin "vss(24)"
					( attribute "PN" "195"
						( Origin gPackager )
					)
					( objectStatus "J9U1.195" )
				)
				( pin "vss(25)"
					( attribute "PN" "193"
						( Origin gPackager )
					)
					( objectStatus "J9U1.193" )
				)
				( pin "vss(26)"
					( attribute "PN" "191"
						( Origin gPackager )
					)
					( objectStatus "J9U1.191" )
				)
				( pin "vss(27)"
					( attribute "PN" "189"
						( Origin gPackager )
					)
					( objectStatus "J9U1.189" )
				)
				( pin "vss(28)"
					( attribute "PN" "187"
						( Origin gPackager )
					)
					( objectStatus "J9U1.187" )
				)
				( pin "vss(29)"
					( attribute "PN" "184"
						( Origin gPackager )
					)
					( objectStatus "J9U1.184" )
				)
				( pin "vss(30)"
					( attribute "PN" "182"
						( Origin gPackager )
					)
					( objectStatus "J9U1.182" )
				)
				( pin "vss(31)"
					( attribute "PN" "180"
						( Origin gPackager )
					)
					( objectStatus "J9U1.180" )
				)
				( pin "vss(32)"
					( attribute "PN" "178"
						( Origin gPackager )
					)
					( objectStatus "J9U1.178" )
				)
				( pin "vss(33)"
					( attribute "PN" "176"
						( Origin gPackager )
					)
					( objectStatus "J9U1.176" )
				)
				( pin "vss(34)"
					( attribute "PN" "173"
						( Origin gPackager )
					)
					( objectStatus "J9U1.173" )
				)
				( pin "vss(35)"
					( attribute "PN" "171"
						( Origin gPackager )
					)
					( objectStatus "J9U1.171" )
				)
				( pin "vss(36)"
					( attribute "PN" "169"
						( Origin gPackager )
					)
					( objectStatus "J9U1.169" )
				)
				( pin "vss(37)"
					( attribute "PN" "167"
						( Origin gPackager )
					)
					( objectStatus "J9U1.167" )
				)
				( pin "vss(38)"
					( attribute "PN" "165"
						( Origin gPackager )
					)
					( objectStatus "J9U1.165" )
				)
				( pin "vss(39)"
					( attribute "PN" "162"
						( Origin gPackager )
					)
					( objectStatus "J9U1.162" )
				)
				( pin "vss(40)"
					( attribute "PN" "160"
						( Origin gPackager )
					)
					( objectStatus "J9U1.160" )
				)
				( pin "vss(41)"
					( attribute "PN" "158"
						( Origin gPackager )
					)
					( objectStatus "J9U1.158" )
				)
				( pin "vss(42)"
					( attribute "PN" "156"
						( Origin gPackager )
					)
					( objectStatus "J9U1.156" )
				)
				( pin "vss(43)"
					( attribute "PN" "154"
						( Origin gPackager )
					)
					( objectStatus "J9U1.154" )
				)
				( pin "vss(44)"
					( attribute "PN" "151"
						( Origin gPackager )
					)
					( objectStatus "J9U1.151" )
				)
				( pin "vss(45)"
					( attribute "PN" "149"
						( Origin gPackager )
					)
					( objectStatus "J9U1.149" )
				)
				( pin "vss(46)"
					( attribute "PN" "147"
						( Origin gPackager )
					)
					( objectStatus "J9U1.147" )
				)
				( pin "vss(47)"
					( attribute "PN" "138"
						( Origin gPackager )
					)
					( objectStatus "J9U1.138" )
				)
				( pin "vss(48)"
					( attribute "PN" "136"
						( Origin gPackager )
					)
					( objectStatus "J9U1.136" )
				)
				( pin "vss(49)"
					( attribute "PN" "134"
						( Origin gPackager )
					)
					( objectStatus "J9U1.134" )
				)
				( pin "vss(50)"
					( attribute "PN" "131"
						( Origin gPackager )
					)
					( objectStatus "J9U1.131" )
				)
				( pin "vss(51)"
					( attribute "PN" "129"
						( Origin gPackager )
					)
					( objectStatus "J9U1.129" )
				)
				( pin "vss(52)"
					( attribute "PN" "127"
						( Origin gPackager )
					)
					( objectStatus "J9U1.127" )
				)
				( pin "vss(53)"
					( attribute "PN" "125"
						( Origin gPackager )
					)
					( objectStatus "J9U1.125" )
				)
				( pin "vss(54)"
					( attribute "PN" "123"
						( Origin gPackager )
					)
					( objectStatus "J9U1.123" )
				)
				( pin "vss(55)"
					( attribute "PN" "120"
						( Origin gPackager )
					)
					( objectStatus "J9U1.120" )
				)
				( pin "vss(56)"
					( attribute "PN" "118"
						( Origin gPackager )
					)
					( objectStatus "J9U1.118" )
				)
				( pin "vss(57)"
					( attribute "PN" "116"
						( Origin gPackager )
					)
					( objectStatus "J9U1.116" )
				)
				( pin "vss(58)"
					( attribute "PN" "114"
						( Origin gPackager )
					)
					( objectStatus "J9U1.114" )
				)
				( pin "vss(59)"
					( attribute "PN" "112"
						( Origin gPackager )
					)
					( objectStatus "J9U1.112" )
				)
				( pin "vss(60)"
					( attribute "PN" "109"
						( Origin gPackager )
					)
					( objectStatus "J9U1.109" )
				)
				( pin "vss(61)"
					( attribute "PN" "107"
						( Origin gPackager )
					)
					( objectStatus "J9U1.107" )
				)
				( pin "vss(62)"
					( attribute "PN" "105"
						( Origin gPackager )
					)
					( objectStatus "J9U1.105" )
				)
				( pin "vss(63)"
					( attribute "PN" "103"
						( Origin gPackager )
					)
					( objectStatus "J9U1.103" )
				)
				( pin "vss(64)"
					( attribute "PN" "101"
						( Origin gPackager )
					)
					( objectStatus "J9U1.101" )
				)
				( pin "vss(65)"
					( attribute "PN" "98"
						( Origin gPackager )
					)
					( objectStatus "J9U1.98" )
				)
				( pin "vss(66)"
					( attribute "PN" "96"
						( Origin gPackager )
					)
					( objectStatus "J9U1.96" )
				)
				( pin "vss(67)"
					( attribute "PN" "94"
						( Origin gPackager )
					)
					( objectStatus "J9U1.94" )
				)
				( pin "vss(68)"
					( attribute "PN" "57"
						( Origin gPackager )
					)
					( objectStatus "J9U1.57" )
				)
				( pin "vss(69)"
					( attribute "PN" "55"
						( Origin gPackager )
					)
					( objectStatus "J9U1.55" )
				)
				( pin "vss(70)"
					( attribute "PN" "53"
						( Origin gPackager )
					)
					( objectStatus "J9U1.53" )
				)
				( pin "vss(71)"
					( attribute "PN" "50"
						( Origin gPackager )
					)
					( objectStatus "J9U1.50" )
				)
				( pin "vss(72)"
					( attribute "PN" "48"
						( Origin gPackager )
					)
					( objectStatus "J9U1.48" )
				)
				( pin "vss(73)"
					( attribute "PN" "46"
						( Origin gPackager )
					)
					( objectStatus "J9U1.46" )
				)
				( pin "vss(74)"
					( attribute "PN" "44"
						( Origin gPackager )
					)
					( objectStatus "J9U1.44" )
				)
				( pin "vss(75)"
					( attribute "PN" "42"
						( Origin gPackager )
					)
					( objectStatus "J9U1.42" )
				)
				( pin "vss(76)"
					( attribute "PN" "39"
						( Origin gPackager )
					)
					( objectStatus "J9U1.39" )
				)
				( pin "vss(77)"
					( attribute "PN" "37"
						( Origin gPackager )
					)
					( objectStatus "J9U1.37" )
				)
				( pin "vss(78)"
					( attribute "PN" "35"
						( Origin gPackager )
					)
					( objectStatus "J9U1.35" )
				)
				( pin "vss(79)"
					( attribute "PN" "33"
						( Origin gPackager )
					)
					( objectStatus "J9U1.33" )
				)
				( pin "vss(80)"
					( attribute "PN" "31"
						( Origin gPackager )
					)
					( objectStatus "J9U1.31" )
				)
				( pin "vss(81)"
					( attribute "PN" "28"
						( Origin gPackager )
					)
					( objectStatus "J9U1.28" )
				)
				( pin "vss(82)"
					( attribute "PN" "26"
						( Origin gPackager )
					)
					( objectStatus "J9U1.26" )
				)
				( pin "vss(83)"
					( attribute "PN" "24"
						( Origin gPackager )
					)
					( objectStatus "J9U1.24" )
				)
				( pin "vss(84)"
					( attribute "PN" "22"
						( Origin gPackager )
					)
					( objectStatus "J9U1.22" )
				)
				( pin "vss(85)"
					( attribute "PN" "20"
						( Origin gPackager )
					)
					( objectStatus "J9U1.20" )
				)
				( pin "vss(86)"
					( attribute "PN" "17"
						( Origin gPackager )
					)
					( objectStatus "J9U1.17" )
				)
				( pin "vss(87)"
					( attribute "PN" "15"
						( Origin gPackager )
					)
					( objectStatus "J9U1.15" )
				)
				( pin "vss(88)"
					( attribute "PN" "13"
						( Origin gPackager )
					)
					( objectStatus "J9U1.13" )
				)
				( pin "vss(89)"
					( attribute "PN" "11"
						( Origin gPackager )
					)
					( objectStatus "J9U1.11" )
				)
				( pin "vss(90)"
					( attribute "PN" "9"
						( Origin gPackager )
					)
					( objectStatus "J9U1.9" )
				)
				( pin "vss(91)"
					( attribute "PN" "6"
						( Origin gPackager )
					)
					( objectStatus "J9U1.6" )
				)
				( pin "vss(92)"
					( attribute "PN" "4"
						( Origin gPackager )
					)
					( objectStatus "J9U1.4" )
				)
				( pin "vss(93)"
					( attribute "PN" "2"
						( Origin gPackager )
					)
					( objectStatus "J9U1.2" )
				)
			)
			( gate "@baseboard_fab2_lib.baseboard_fab2(sch_1):page81_i67"
				( attribute "BOM_COST" "MEM"
					( Origin gFrontEnd )
				)
				( attribute "CDS_LIB" "mstr_sconn"
					( Origin gPackager )
				)
				( attribute "CDS_LOCATION" "J1G3"
					( Origin gPackager )
				)
				( attribute "CDS_SEC" "2"
					( Origin gPackager )
				)
				( attribute "LOCATION" "J1G3"
					( Origin gFrontEnd )
				)
				( attribute "MATERIAL" "SCONN"
					( Origin gFrontEnd )
				)
				( attribute "PACK_TYPE" "PIP"
					( Origin gFrontEnd )
				)
				( attribute "PART_NUMBER" "H44441-004"
					( Origin gFrontEnd )
				)
				( attribute "PHYS_PAGE" "81"
					( Origin gFrontEnd )
				)
				( attribute "ROOM" "DDR4_CH_J"
					( Origin gFrontEnd )
				)
				( attribute "ROT" "0"
					( Origin gFrontEnd )
				)
				( attribute "SEC" "2"
					( Origin gFrontEnd )
				)
				( attribute "SEC_TYPE" "PIP"
					( Origin gFrontEnd )
				)
				( attribute "VER" "2"
					( Origin gFrontEnd )
				)
				( attribute "XY" "(-50,4300)"
					( Origin gFrontEnd )
				)
				( attribute "CHIPS_PART_NAME" "SCONN288_H44441004"
					( Origin gPackager )
				)
				( attribute "CDS_PART_NAME" "SCONN288_H44441004_PIP-SCONN,HA"
					( Origin gPackager )
				)
				( objectStatus "J1G3" )
				( pin "dqs0n"
					( attribute "PN" "152"
						( Origin gPackager )
					)
					( objectStatus "J1G3.152" )
				)
				( pin "dqs0p"
					( attribute "PN" "153"
						( Origin gPackager )
					)
					( objectStatus "J1G3.153" )
				)
				( pin "dqs1n"
					( attribute "PN" "163"
						( Origin gPackager )
					)
					( objectStatus "J1G3.163" )
				)
				( pin "dqs1p"
					( attribute "PN" "164"
						( Origin gPackager )
					)
					( objectStatus "J1G3.164" )
				)
				( pin "dqs2n"
					( attribute "PN" "174"
						( Origin gPackager )
					)
					( objectStatus "J1G3.174" )
				)
				( pin "dqs2p"
					( attribute "PN" "175"
						( Origin gPackager )
					)
					( objectStatus "J1G3.175" )
				)
				( pin "dqs3n"
					( attribute "PN" "185"
						( Origin gPackager )
					)
					( objectStatus "J1G3.185" )
				)
				( pin "dqs3p"
					( attribute "PN" "186"
						( Origin gPackager )
					)
					( objectStatus "J1G3.186" )
				)
				( pin "dqs4n"
					( attribute "PN" "244"
						( Origin gPackager )
					)
					( objectStatus "J1G3.244" )
				)
				( pin "dqs4p"
					( attribute "PN" "245"
						( Origin gPackager )
					)
					( objectStatus "J1G3.245" )
				)
				( pin "dqs5n"
					( attribute "PN" "255"
						( Origin gPackager )
					)
					( objectStatus "J1G3.255" )
				)
				( pin "dqs5p"
					( attribute "PN" "256"
						( Origin gPackager )
					)
					( objectStatus "J1G3.256" )
				)
				( pin "dqs6n"
					( attribute "PN" "266"
						( Origin gPackager )
					)
					( objectStatus "J1G3.266" )
				)
				( pin "dqs6p"
					( attribute "PN" "267"
						( Origin gPackager )
					)
					( objectStatus "J1G3.267" )
				)
				( pin "dqs7n"
					( attribute "PN" "277"
						( Origin gPackager )
					)
					( objectStatus "J1G3.277" )
				)
				( pin "dqs7p"
					( attribute "PN" "278"
						( Origin gPackager )
					)
					( objectStatus "J1G3.278" )
				)
				( pin "dqs8n"
					( attribute "PN" "196"
						( Origin gPackager )
					)
					( objectStatus "J1G3.196" )
				)
				( pin "dqs8p"
					( attribute "PN" "197"
						( Origin gPackager )
					)
					( objectStatus "J1G3.197" )
				)
				( pin "dqs9n"
					( attribute "PN" "8"
						( Origin gPackager )
					)
					( objectStatus "J1G3.8" )
				)
				( pin "dqs9p"
					( attribute "PN" "7"
						( Origin gPackager )
					)
					( objectStatus "J1G3.7" )
				)
				( pin "dqs10n"
					( attribute "PN" "19"
						( Origin gPackager )
					)
					( objectStatus "J1G3.19" )
				)
				( pin "dqs10p"
					( attribute "PN" "18"
						( Origin gPackager )
					)
					( objectStatus "J1G3.18" )
				)
				( pin "dqs11n"
					( attribute "PN" "30"
						( Origin gPackager )
					)
					( objectStatus "J1G3.30" )
				)
				( pin "dqs11p"
					( attribute "PN" "29"
						( Origin gPackager )
					)
					( objectStatus "J1G3.29" )
				)
				( pin "dqs12n"
					( attribute "PN" "41"
						( Origin gPackager )
					)
					( objectStatus "J1G3.41" )
				)
				( pin "dqs12p"
					( attribute "PN" "40"
						( Origin gPackager )
					)
					( objectStatus "J1G3.40" )
				)
				( pin "dqs13n"
					( attribute "PN" "100"
						( Origin gPackager )
					)
					( objectStatus "J1G3.100" )
				)
				( pin "dqs13p"
					( attribute "PN" "99"
						( Origin gPackager )
					)
					( objectStatus "J1G3.99" )
				)
				( pin "dqs14n"
					( attribute "PN" "111"
						( Origin gPackager )
					)
					( objectStatus "J1G3.111" )
				)
				( pin "dqs14p"
					( attribute "PN" "110"
						( Origin gPackager )
					)
					( objectStatus "J1G3.110" )
				)
				( pin "dqs15n"
					( attribute "PN" "122"
						( Origin gPackager )
					)
					( objectStatus "J1G3.122" )
				)
				( pin "dqs15p"
					( attribute "PN" "121"
						( Origin gPackager )
					)
					( objectStatus "J1G3.121" )
				)
				( pin "dqs16n"
					( attribute "PN" "133"
						( Origin gPackager )
					)
					( objectStatus "J1G3.133" )
				)
				( pin "dqs16p"
					( attribute "PN" "132"
						( Origin gPackager )
					)
					( objectStatus "J1G3.132" )
				)
				( pin "dqs17n"
					( attribute "PN" "52"
						( Origin gPackager )
					)
					( objectStatus "J1G3.52" )
				)
				( pin "dqs17p"
					( attribute "PN" "51"
						( Origin gPackager )
					)
					( objectStatus "J1G3.51" )
				)
			)
			( gate "@baseboard_fab2_lib.baseboard_fab2(sch_1):page81_i169"
				( attribute "BOM_COST" "MEM"
					( Origin gFrontEnd )
				)
				( attribute "CDS_LIB" "mstr_sconn"
					( Origin gPackager )
				)
				( attribute "CDS_LOCATION" "J1G3"
					( Origin gPackager )
				)
				( attribute "CDS_SEC" "4"
					( Origin gPackager )
				)
				( attribute "LOCATION" "J1G3"
					( Origin gFrontEnd )
				)
				( attribute "MATERIAL" "SCONN"
					( Origin gFrontEnd )
				)
				( attribute "PACK_TYPE" "PIP"
					( Origin gFrontEnd )
				)
				( attribute "PART_NUMBER" "H44441-004"
					( Origin gFrontEnd )
				)
				( attribute "PHYS_PAGE" "81"
					( Origin gFrontEnd )
				)
				( attribute "ROOM" "DDR4_CH_J"
					( Origin gFrontEnd )
				)
				( attribute "ROT" "0"
					( Origin gFrontEnd )
				)
				( attribute "SEC" "4"
					( Origin gFrontEnd )
				)
				( attribute "SEC_TYPE" "PIP"
					( Origin gFrontEnd )
				)
				( attribute "VER" "4"
					( Origin gFrontEnd )
				)
				( attribute "XY" "(-350,2000)"
					( Origin gFrontEnd )
				)
				( attribute "CHIPS_PART_NAME" "SCONN288_H44441004"
					( Origin gPackager )
				)
				( attribute "CDS_PART_NAME" "SCONN288_H44441004_PIP-SCONN,HA"
					( Origin gPackager )
				)
				( objectStatus "J1G3" )
				( pin "\12v\(0)"
					( attribute "PN" "145"
						( Origin gPackager )
					)
					( objectStatus "J1G3.145" )
				)
				( pin "\12v\(1)"
					( attribute "PN" "1"
						( Origin gPackager )
					)
					( objectStatus "J1G3.1" )
				)
				( pin "vdd(0)"
					( attribute "PN" "236"
						( Origin gPackager )
					)
					( objectStatus "J1G3.236" )
				)
				( pin "vdd(1)"
					( attribute "PN" "233"
						( Origin gPackager )
					)
					( objectStatus "J1G3.233" )
				)
				( pin "vdd(2)"
					( attribute "PN" "231"
						( Origin gPackager )
					)
					( objectStatus "J1G3.231" )
				)
				( pin "vdd(3)"
					( attribute "PN" "229"
						( Origin gPackager )
					)
					( objectStatus "J1G3.229" )
				)
				( pin "vdd(4)"
					( attribute "PN" "226"
						( Origin gPackager )
					)
					( objectStatus "J1G3.226" )
				)
				( pin "vdd(5)"
					( attribute "PN" "223"
						( Origin gPackager )
					)
					( objectStatus "J1G3.223" )
				)
				( pin "vdd(6)"
					( attribute "PN" "220"
						( Origin gPackager )
					)
					( objectStatus "J1G3.220" )
				)
				( pin "vdd(7)"
					( attribute "PN" "217"
						( Origin gPackager )
					)
					( objectStatus "J1G3.217" )
				)
				( pin "vdd(8)"
					( attribute "PN" "215"
						( Origin gPackager )
					)
					( objectStatus "J1G3.215" )
				)
				( pin "vdd(9)"
					( attribute "PN" "212"
						( Origin gPackager )
					)
					( objectStatus "J1G3.212" )
				)
				( pin "vdd(10)"
					( attribute "PN" "209"
						( Origin gPackager )
					)
					( objectStatus "J1G3.209" )
				)
				( pin "vdd(11)"
					( attribute "PN" "206"
						( Origin gPackager )
					)
					( objectStatus "J1G3.206" )
				)
				( pin "vdd(12)"
					( attribute "PN" "204"
						( Origin gPackager )
					)
					( objectStatus "J1G3.204" )
				)
				( pin "vdd(13)"
					( attribute "PN" "92"
						( Origin gPackager )
					)
					( objectStatus "J1G3.92" )
				)
				( pin "vdd(14)"
					( attribute "PN" "90"
						( Origin gPackager )
					)
					( objectStatus "J1G3.90" )
				)
				( pin "vdd(15)"
					( attribute "PN" "88"
						( Origin gPackager )
					)
					( objectStatus "J1G3.88" )
				)
				( pin "vdd(16)"
					( attribute "PN" "85"
						( Origin gPackager )
					)
					( objectStatus "J1G3.85" )
				)
				( pin "vdd(17)"
					( attribute "PN" "83"
						( Origin gPackager )
					)
					( objectStatus "J1G3.83" )
				)
				( pin "vdd(18)"
					( attribute "PN" "80"
						( Origin gPackager )
					)
					( objectStatus "J1G3.80" )
				)
				( pin "vdd(19)"
					( attribute "PN" "76"
						( Origin gPackager )
					)
					( objectStatus "J1G3.76" )
				)
				( pin "vdd(20)"
					( attribute "PN" "73"
						( Origin gPackager )
					)
					( objectStatus "J1G3.73" )
				)
				( pin "vdd(21)"
					( attribute "PN" "70"
						( Origin gPackager )
					)
					( objectStatus "J1G3.70" )
				)
				( pin "vdd(22)"
					( attribute "PN" "67"
						( Origin gPackager )
					)
					( objectStatus "J1G3.67" )
				)
				( pin "vdd(23)"
					( attribute "PN" "64"
						( Origin gPackager )
					)
					( objectStatus "J1G3.64" )
				)
				( pin "vdd(24)"
					( attribute "PN" "61"
						( Origin gPackager )
					)
					( objectStatus "J1G3.61" )
				)
				( pin "vdd(25)"
					( attribute "PN" "59"
						( Origin gPackager )
					)
					( objectStatus "J1G3.59" )
				)
				( pin "vpp(0)"
					( attribute "PN" "287"
						( Origin gPackager )
					)
					( objectStatus "J1G3.287" )
				)
				( pin "vpp(1)"
					( attribute "PN" "286"
						( Origin gPackager )
					)
					( objectStatus "J1G3.286" )
				)
				( pin "vpp(2)"
					( attribute "PN" "288"
						( Origin gPackager )
					)
					( objectStatus "J1G3.288" )
				)
				( pin "vpp(3)"
					( attribute "PN" "143"
						( Origin gPackager )
					)
					( objectStatus "J1G3.143" )
				)
				( pin "vpp(4)"
					( attribute "PN" "142"
						( Origin gPackager )
					)
					( objectStatus "J1G3.142" )
				)
				( pin "vtt(0)"
					( attribute "PN" "221"
						( Origin gPackager )
					)
					( objectStatus "J1G3.221" )
				)
				( pin "vtt(1)"
					( attribute "PN" "77"
						( Origin gPackager )
					)
					( objectStatus "J1G3.77" )
				)
			)
			( gate "@baseboard_fab2_lib.baseboard_fab2(sch_1):page81_i178"
				( attribute "BOM_COST" "MEM"
					( Origin gFrontEnd )
				)
				( attribute "CDS_LIB" "dev_discrete"
					( Origin gPackager )
				)
				( attribute "CDS_LOCATION" "C9U10"
					( Origin gPackager )
				)
				( attribute "CDS_SEC" "1"
					( Origin gPackager )
				)
				( attribute "LOCATION" "C9U10"
					( Origin gFrontEnd )
				)
				( attribute "MATERIAL" "X7R"
					( Origin gFrontEnd )
				)
				( attribute "PACK_TYPE" "0402V"
					( Origin gFrontEnd )
				)
				( attribute "PART_NUMBER" "A36096-045"
					( Origin gFrontEnd )
				)
				( attribute "PHYS_PAGE" "81"
					( Origin gFrontEnd )
				)
				( attribute "ROOM" "DDR4_CH_J"
					( Origin gFrontEnd )
				)
				( attribute "ROT" "2"
					( Origin gFrontEnd )
				)
				( attribute "SEC" "1"
					( Origin gPackager )
				)
				( attribute "TOLERANCE" "10%"
					( Origin gFrontEnd )
				)
				( attribute "VALUE" "0.01UF"
					( Origin gFrontEnd )
				)
				( attribute "VER" "1"
					( Origin gFrontEnd )
				)
				( attribute "VOLTAGE" "25V"
					( Units "uVoltage" "V" 1.000000)
					( Origin gFrontEnd )
				)
				( attribute "XY" "(-4550,1450)"
					( Origin gFrontEnd )
				)
				( attribute "CHIPS_PART_NAME" "CAP_A"
					( Origin gPackager )
				)
				( attribute "CDS_PART_NAME" "CAP_A_0402V-0.01UF,25V,10%,X7RA"
					( Origin gPackager )
				)
				( objectStatus "C9U10" )
				( pin "a"
					( attribute "PN" "1"
						( Origin gPackager )
					)
					( objectStatus "C9U10.1" )
				)
				( pin "b"
					( attribute "PN" "2"
						( Origin gPackager )
					)
					( objectStatus "C9U10.2" )
				)
			)
			( gate "@baseboard_fab2_lib.baseboard_fab2(sch_1):page81_i185"
				( attribute "BOM_COST" "MEM"
					( Origin gFrontEnd )
				)
				( attribute "CDS_LIB" "mstr_sconn"
					( Origin gPackager )
				)
				( attribute "CDS_LOCATION" "J1G3"
					( Origin gPackager )
				)
				( attribute "CDS_SEC" "3"
					( Origin gPackager )
				)
				( attribute "LOCATION" "J1G3"
					( Origin gFrontEnd )
				)
				( attribute "MATERIAL" "SCONN"
					( Origin gFrontEnd )
				)
				( attribute "PACK_TYPE" "PIP"
					( Origin gFrontEnd )
				)
				( attribute "PART_NUMBER" "H44441-004"
					( Origin gFrontEnd )
				)
				( attribute "PHYS_PAGE" "81"
					( Origin gFrontEnd )
				)
				( attribute "ROOM" "DDR4_CH_J"
					( Origin gFrontEnd )
				)
				( attribute "ROT" "0"
					( Origin gFrontEnd )
				)
				( attribute "SEC" "3"
					( Origin gFrontEnd )
				)
				( attribute "SEC_TYPE" "PIP"
					( Origin gFrontEnd )
				)
				( attribute "VER" "3"
					( Origin gFrontEnd )
				)
				( attribute "XY" "(1750,2400)"
					( Origin gFrontEnd )
				)
				( attribute "CHIPS_PART_NAME" "SCONN288_H44441004"
					( Origin gPackager )
				)
				( attribute "CDS_PART_NAME" "SCONN288_H44441004_PIP-SCONN,HA"
					( Origin gPackager )
				)
				( objectStatus "J1G3" )
				( pin "vss(0)"
					( attribute "PN" "283"
						( Origin gPackager )
					)
					( objectStatus "J1G3.283" )
				)
				( pin "vss(1)"
					( attribute "PN" "281"
						( Origin gPackager )
					)
					( objectStatus "J1G3.281" )
				)
				( pin "vss(2)"
					( attribute "PN" "279"
						( Origin gPackager )
					)
					( objectStatus "J1G3.279" )
				)
				( pin "vss(3)"
					( attribute "PN" "276"
						( Origin gPackager )
					)
					( objectStatus "J1G3.276" )
				)
				( pin "vss(4)"
					( attribute "PN" "274"
						( Origin gPackager )
					)
					( objectStatus "J1G3.274" )
				)
				( pin "vss(5)"
					( attribute "PN" "272"
						( Origin gPackager )
					)
					( objectStatus "J1G3.272" )
				)
				( pin "vss(6)"
					( attribute "PN" "270"
						( Origin gPackager )
					)
					( objectStatus "J1G3.270" )
				)
				( pin "vss(7)"
					( attribute "PN" "268"
						( Origin gPackager )
					)
					( objectStatus "J1G3.268" )
				)
				( pin "vss(8)"
					( attribute "PN" "265"
						( Origin gPackager )
					)
					( objectStatus "J1G3.265" )
				)
				( pin "vss(9)"
					( attribute "PN" "263"
						( Origin gPackager )
					)
					( objectStatus "J1G3.263" )
				)
				( pin "vss(10)"
					( attribute "PN" "261"
						( Origin gPackager )
					)
					( objectStatus "J1G3.261" )
				)
				( pin "vss(11)"
					( attribute "PN" "259"
						( Origin gPackager )
					)
					( objectStatus "J1G3.259" )
				)
				( pin "vss(12)"
					( attribute "PN" "257"
						( Origin gPackager )
					)
					( objectStatus "J1G3.257" )
				)
				( pin "vss(13)"
					( attribute "PN" "254"
						( Origin gPackager )
					)
					( objectStatus "J1G3.254" )
				)
				( pin "vss(14)"
					( attribute "PN" "252"
						( Origin gPackager )
					)
					( objectStatus "J1G3.252" )
				)
				( pin "vss(15)"
					( attribute "PN" "250"
						( Origin gPackager )
					)
					( objectStatus "J1G3.250" )
				)
				( pin "vss(16)"
					( attribute "PN" "248"
						( Origin gPackager )
					)
					( objectStatus "J1G3.248" )
				)
				( pin "vss(17)"
					( attribute "PN" "246"
						( Origin gPackager )
					)
					( objectStatus "J1G3.246" )
				)
				( pin "vss(18)"
					( attribute "PN" "243"
						( Origin gPackager )
					)
					( objectStatus "J1G3.243" )
				)
				( pin "vss(19)"
					( attribute "PN" "241"
						( Origin gPackager )
					)
					( objectStatus "J1G3.241" )
				)
				( pin "vss(20)"
					( attribute "PN" "239"
						( Origin gPackager )
					)
					( objectStatus "J1G3.239" )
				)
				( pin "vss(21)"
					( attribute "PN" "202"
						( Origin gPackager )
					)
					( objectStatus "J1G3.202" )
				)
				( pin "vss(22)"
					( attribute "PN" "200"
						( Origin gPackager )
					)
					( objectStatus "J1G3.200" )
				)
				( pin "vss(23)"
					( attribute "PN" "198"
						( Origin gPackager )
					)
					( objectStatus "J1G3.198" )
				)
				( pin "vss(24)"
					( attribute "PN" "195"
						( Origin gPackager )
					)
					( objectStatus "J1G3.195" )
				)
				( pin "vss(25)"
					( attribute "PN" "193"
						( Origin gPackager )
					)
					( objectStatus "J1G3.193" )
				)
				( pin "vss(26)"
					( attribute "PN" "191"
						( Origin gPackager )
					)
					( objectStatus "J1G3.191" )
				)
				( pin "vss(27)"
					( attribute "PN" "189"
						( Origin gPackager )
					)
					( objectStatus "J1G3.189" )
				)
				( pin "vss(28)"
					( attribute "PN" "187"
						( Origin gPackager )
					)
					( objectStatus "J1G3.187" )
				)
				( pin "vss(29)"
					( attribute "PN" "184"
						( Origin gPackager )
					)
					( objectStatus "J1G3.184" )
				)
				( pin "vss(30)"
					( attribute "PN" "182"
						( Origin gPackager )
					)
					( objectStatus "J1G3.182" )
				)
				( pin "vss(31)"
					( attribute "PN" "180"
						( Origin gPackager )
					)
					( objectStatus "J1G3.180" )
				)
				( pin "vss(32)"
					( attribute "PN" "178"
						( Origin gPackager )
					)
					( objectStatus "J1G3.178" )
				)
				( pin "vss(33)"
					( attribute "PN" "176"
						( Origin gPackager )
					)
					( objectStatus "J1G3.176" )
				)
				( pin "vss(34)"
					( attribute "PN" "173"
						( Origin gPackager )
					)
					( objectStatus "J1G3.173" )
				)
				( pin "vss(35)"
					( attribute "PN" "171"
						( Origin gPackager )
					)
					( objectStatus "J1G3.171" )
				)
				( pin "vss(36)"
					( attribute "PN" "169"
						( Origin gPackager )
					)
					( objectStatus "J1G3.169" )
				)
				( pin "vss(37)"
					( attribute "PN" "167"
						( Origin gPackager )
					)
					( objectStatus "J1G3.167" )
				)
				( pin "vss(38)"
					( attribute "PN" "165"
						( Origin gPackager )
					)
					( objectStatus "J1G3.165" )
				)
				( pin "vss(39)"
					( attribute "PN" "162"
						( Origin gPackager )
					)
					( objectStatus "J1G3.162" )
				)
				( pin "vss(40)"
					( attribute "PN" "160"
						( Origin gPackager )
					)
					( objectStatus "J1G3.160" )
				)
				( pin "vss(41)"
					( attribute "PN" "158"
						( Origin gPackager )
					)
					( objectStatus "J1G3.158" )
				)
				( pin "vss(42)"
					( attribute "PN" "156"
						( Origin gPackager )
					)
					( objectStatus "J1G3.156" )
				)
				( pin "vss(43)"
					( attribute "PN" "154"
						( Origin gPackager )
					)
					( objectStatus "J1G3.154" )
				)
				( pin "vss(44)"
					( attribute "PN" "151"
						( Origin gPackager )
					)
					( objectStatus "J1G3.151" )
				)
				( pin "vss(45)"
					( attribute "PN" "149"
						( Origin gPackager )
					)
					( objectStatus "J1G3.149" )
				)
				( pin "vss(46)"
					( attribute "PN" "147"
						( Origin gPackager )
					)
					( objectStatus "J1G3.147" )
				)
				( pin "vss(47)"
					( attribute "PN" "138"
						( Origin gPackager )
					)
					( objectStatus "J1G3.138" )
				)
				( pin "vss(48)"
					( attribute "PN" "136"
						( Origin gPackager )
					)
					( objectStatus "J1G3.136" )
				)
				( pin "vss(49)"
					( attribute "PN" "134"
						( Origin gPackager )
					)
					( objectStatus "J1G3.134" )
				)
				( pin "vss(50)"
					( attribute "PN" "131"
						( Origin gPackager )
					)
					( objectStatus "J1G3.131" )
				)
				( pin "vss(51)"
					( attribute "PN" "129"
						( Origin gPackager )
					)
					( objectStatus "J1G3.129" )
				)
				( pin "vss(52)"
					( attribute "PN" "127"
						( Origin gPackager )
					)
					( objectStatus "J1G3.127" )
				)
				( pin "vss(53)"
					( attribute "PN" "125"
						( Origin gPackager )
					)
					( objectStatus "J1G3.125" )
				)
				( pin "vss(54)"
					( attribute "PN" "123"
						( Origin gPackager )
					)
					( objectStatus "J1G3.123" )
				)
				( pin "vss(55)"
					( attribute "PN" "120"
						( Origin gPackager )
					)
					( objectStatus "J1G3.120" )
				)
				( pin "vss(56)"
					( attribute "PN" "118"
						( Origin gPackager )
					)
					( objectStatus "J1G3.118" )
				)
				( pin "vss(57)"
					( attribute "PN" "116"
						( Origin gPackager )
					)
					( objectStatus "J1G3.116" )
				)
				( pin "vss(58)"
					( attribute "PN" "114"
						( Origin gPackager )
					)
					( objectStatus "J1G3.114" )
				)
				( pin "vss(59)"
					( attribute "PN" "112"
						( Origin gPackager )
					)
					( objectStatus "J1G3.112" )
				)
				( pin "vss(60)"
					( attribute "PN" "109"
						( Origin gPackager )
					)
					( objectStatus "J1G3.109" )
				)
				( pin "vss(61)"
					( attribute "PN" "107"
						( Origin gPackager )
					)
					( objectStatus "J1G3.107" )
				)
				( pin "vss(62)"
					( attribute "PN" "105"
						( Origin gPackager )
					)
					( objectStatus "J1G3.105" )
				)
				( pin "vss(63)"
					( attribute "PN" "103"
						( Origin gPackager )
					)
					( objectStatus "J1G3.103" )
				)
				( pin "vss(64)"
					( attribute "PN" "101"
						( Origin gPackager )
					)
					( objectStatus "J1G3.101" )
				)
				( pin "vss(65)"
					( attribute "PN" "98"
						( Origin gPackager )
					)
					( objectStatus "J1G3.98" )
				)
				( pin "vss(66)"
					( attribute "PN" "96"
						( Origin gPackager )
					)
					( objectStatus "J1G3.96" )
				)
				( pin "vss(67)"
					( attribute "PN" "94"
						( Origin gPackager )
					)
					( objectStatus "J1G3.94" )
				)
				( pin "vss(68)"
					( attribute "PN" "57"
						( Origin gPackager )
					)
					( objectStatus "J1G3.57" )
				)
				( pin "vss(69)"
					( attribute "PN" "55"
						( Origin gPackager )
					)
					( objectStatus "J1G3.55" )
				)
				( pin "vss(70)"
					( attribute "PN" "53"
						( Origin gPackager )
					)
					( objectStatus "J1G3.53" )
				)
				( pin "vss(71)"
					( attribute "PN" "50"
						( Origin gPackager )
					)
					( objectStatus "J1G3.50" )
				)
				( pin "vss(72)"
					( attribute "PN" "48"
						( Origin gPackager )
					)
					( objectStatus "J1G3.48" )
				)
				( pin "vss(73)"
					( attribute "PN" "46"
						( Origin gPackager )
					)
					( objectStatus "J1G3.46" )
				)
				( pin "vss(74)"
					( attribute "PN" "44"
						( Origin gPackager )
					)
					( objectStatus "J1G3.44" )
				)
				( pin "vss(75)"
					( attribute "PN" "42"
						( Origin gPackager )
					)
					( objectStatus "J1G3.42" )
				)
				( pin "vss(76)"
					( attribute "PN" "39"
						( Origin gPackager )
					)
					( objectStatus "J1G3.39" )
				)
				( pin "vss(77)"
					( attribute "PN" "37"
						( Origin gPackager )
					)
					( objectStatus "J1G3.37" )
				)
				( pin "vss(78)"
					( attribute "PN" "35"
						( Origin gPackager )
					)
					( objectStatus "J1G3.35" )
				)
				( pin "vss(79)"
					( attribute "PN" "33"
						( Origin gPackager )
					)
					( objectStatus "J1G3.33" )
				)
				( pin "vss(80)"
					( attribute "PN" "31"
						( Origin gPackager )
					)
					( objectStatus "J1G3.31" )
				)
				( pin "vss(81)"
					( attribute "PN" "28"
						( Origin gPackager )
					)
					( objectStatus "J1G3.28" )
				)
				( pin "vss(82)"
					( attribute "PN" "26"
						( Origin gPackager )
					)
					( objectStatus "J1G3.26" )
				)
				( pin "vss(83)"
					( attribute "PN" "24"
						( Origin gPackager )
					)
					( objectStatus "J1G3.24" )
				)
				( pin "vss(84)"
					( attribute "PN" "22"
						( Origin gPackager )
					)
					( objectStatus "J1G3.22" )
				)
				( pin "vss(85)"
					( attribute "PN" "20"
						( Origin gPackager )
					)
					( objectStatus "J1G3.20" )
				)
				( pin "vss(86)"
					( attribute "PN" "17"
						( Origin gPackager )
					)
					( objectStatus "J1G3.17" )
				)
				( pin "vss(87)"
					( attribute "PN" "15"
						( Origin gPackager )
					)
					( objectStatus "J1G3.15" )
				)
				( pin "vss(88)"
					( attribute "PN" "13"
						( Origin gPackager )
					)
					( objectStatus "J1G3.13" )
				)
				( pin "vss(89)"
					( attribute "PN" "11"
						( Origin gPackager )
					)
					( objectStatus "J1G3.11" )
				)
				( pin "vss(90)"
					( attribute "PN" "9"
						( Origin gPackager )
					)
					( objectStatus "J1G3.9" )
				)
				( pin "vss(91)"
					( attribute "PN" "6"
						( Origin gPackager )
					)
					( objectStatus "J1G3.6" )
				)
				( pin "vss(92)"
					( attribute "PN" "4"
						( Origin gPackager )
					)
					( objectStatus "J1G3.4" )
				)
				( pin "vss(93)"
					( attribute "PN" "2"
						( Origin gPackager )
					)
					( objectStatus "J1G3.2" )
				)
			)
			( gate "@baseboard_fab2_lib.baseboard_fab2(sch_1):page81_i186"
				( attribute "BOM_COST" "MEM"
					( Origin gFrontEnd )
				)
				( attribute "CDS_LIB" "mstr_sconn"
					( Origin gPackager )
				)
				( attribute "CDS_LOCATION" "J1G3"
					( Origin gPackager )
				)
				( attribute "CDS_SEC" "1"
					( Origin gPackager )
				)
				( attribute "LOCATION" "J1G3"
					( Origin gFrontEnd )
				)
				( attribute "MATERIAL" "SCONN"
					( Origin gFrontEnd )
				)
				( attribute "PACK_TYPE" "PIP"
					( Origin gFrontEnd )
				)
				( attribute "PART_NUMBER" "H44441-004"
					( Origin gFrontEnd )
				)
				( attribute "PHYS_PAGE" "81"
					( Origin gFrontEnd )
				)
				( attribute "ROOM" "DDR4_CH_J"
					( Origin gFrontEnd )
				)
				( attribute "ROT" "0"
					( Origin gFrontEnd )
				)
				( attribute "SEC" "1"
					( Origin gFrontEnd )
				)
				( attribute "SEC_TYPE" "PIP"
					( Origin gFrontEnd )
				)
				( attribute "VER" "1"
					( Origin gFrontEnd )
				)
				( attribute "XY" "(-2550,3150)"
					( Origin gFrontEnd )
				)
				( attribute "CHIPS_PART_NAME" "SCONN288_H44441004"
					( Origin gPackager )
				)
				( attribute "CDS_PART_NAME" "SCONN288_H44441004_PIP-SCONN,HA"
					( Origin gPackager )
				)
				( objectStatus "J1G3" )
				( pin "a0"
					( attribute "PN" "79"
						( Origin gPackager )
					)
					( objectStatus "J1G3.79" )
				)
				( pin "a1"
					( attribute "PN" "72"
						( Origin gPackager )
					)
					( objectStatus "J1G3.72" )
				)
				( pin "a2"
					( attribute "PN" "216"
						( Origin gPackager )
					)
					( objectStatus "J1G3.216" )
				)
				( pin "a3"
					( attribute "PN" "71"
						( Origin gPackager )
					)
					( objectStatus "J1G3.71" )
				)
				( pin "a4"
					( attribute "PN" "214"
						( Origin gPackager )
					)
					( objectStatus "J1G3.214" )
				)
				( pin "a5"
					( attribute "PN" "213"
						( Origin gPackager )
					)
					( objectStatus "J1G3.213" )
				)
				( pin "a6"
					( attribute "PN" "69"
						( Origin gPackager )
					)
					( objectStatus "J1G3.69" )
				)
				( pin "a7"
					( attribute "PN" "211"
						( Origin gPackager )
					)
					( objectStatus "J1G3.211" )
				)
				( pin "a8"
					( attribute "PN" "68"
						( Origin gPackager )
					)
					( objectStatus "J1G3.68" )
				)
				( pin "a9"
					( attribute "PN" "66"
						( Origin gPackager )
					)
					( objectStatus "J1G3.66" )
				)
				( pin "a10"
					( attribute "PN" "225"
						( Origin gPackager )
					)
					( objectStatus "J1G3.225" )
				)
				( pin "a11"
					( attribute "PN" "210"
						( Origin gPackager )
					)
					( objectStatus "J1G3.210" )
				)
				( pin "a12"
					( attribute "PN" "65"
						( Origin gPackager )
					)
					( objectStatus "J1G3.65" )
				)
				( pin "a13"
					( attribute "PN" "232"
						( Origin gPackager )
					)
					( objectStatus "J1G3.232" )
				)
				( pin "a14_we_n"
					( attribute "PN" "228"
						( Origin gPackager )
					)
					( objectStatus "J1G3.228" )
				)
				( pin "a15_cas_n"
					( attribute "PN" "86"
						( Origin gPackager )
					)
					( objectStatus "J1G3.86" )
				)
				( pin "a16_ras_n"
					( attribute "PN" "82"
						( Origin gPackager )
					)
					( objectStatus "J1G3.82" )
				)
				( pin "a17"
					( attribute "PN" "234"
						( Origin gPackager )
					)
					( objectStatus "J1G3.234" )
				)
				( pin "act_n"
					( attribute "PN" "62"
						( Origin gPackager )
					)
					( objectStatus "J1G3.62" )
				)
				( pin "alert_n"
					( attribute "PN" "208"
						( Origin gPackager )
					)
					( objectStatus "J1G3.208" )
				)
				( pin "ba(0)"
					( attribute "PN" "81"
						( Origin gPackager )
					)
					( objectStatus "J1G3.81" )
				)
				( pin "ba(1)"
					( attribute "PN" "224"
						( Origin gPackager )
					)
					( objectStatus "J1G3.224" )
				)
				( pin "bg(0)"
					( attribute "PN" "63"
						( Origin gPackager )
					)
					( objectStatus "J1G3.63" )
				)
				( pin "bg(1)"
					( attribute "PN" "207"
						( Origin gPackager )
					)
					( objectStatus "J1G3.207" )
				)
				( pin "c(2)"
					( attribute "PN" "235"
						( Origin gPackager )
					)
					( objectStatus "J1G3.235" )
				)
				( pin "cb(0)"
					( attribute "PN" "49"
						( Origin gPackager )
					)
					( objectStatus "J1G3.49" )
				)
				( pin "cb(1)"
					( attribute "PN" "194"
						( Origin gPackager )
					)
					( objectStatus "J1G3.194" )
				)
				( pin "cb(2)"
					( attribute "PN" "56"
						( Origin gPackager )
					)
					( objectStatus "J1G3.56" )
				)
				( pin "cb(3)"
					( attribute "PN" "201"
						( Origin gPackager )
					)
					( objectStatus "J1G3.201" )
				)
				( pin "cb(4)"
					( attribute "PN" "47"
						( Origin gPackager )
					)
					( objectStatus "J1G3.47" )
				)
				( pin "cb(5)"
					( attribute "PN" "192"
						( Origin gPackager )
					)
					( objectStatus "J1G3.192" )
				)
				( pin "cb(6)"
					( attribute "PN" "54"
						( Origin gPackager )
					)
					( objectStatus "J1G3.54" )
				)
				( pin "cb(7)"
					( attribute "PN" "199"
						( Origin gPackager )
					)
					( objectStatus "J1G3.199" )
				)
				( pin "ck0n"
					( attribute "PN" "75"
						( Origin gPackager )
					)
					( objectStatus "J1G3.75" )
				)
				( pin "ck0p"
					( attribute "PN" "74"
						( Origin gPackager )
					)
					( objectStatus "J1G3.74" )
				)
				( pin "ck1n"
					( attribute "PN" "219"
						( Origin gPackager )
					)
					( objectStatus "J1G3.219" )
				)
				( pin "ck1p"
					( attribute "PN" "218"
						( Origin gPackager )
					)
					( objectStatus "J1G3.218" )
				)
				( pin "cke(0)"
					( attribute "PN" "60"
						( Origin gPackager )
					)
					( objectStatus "J1G3.60" )
				)
				( pin "cke(1)"
					( attribute "PN" "203"
						( Origin gPackager )
					)
					( objectStatus "J1G3.203" )
				)
				( pin "dq(0)"
					( attribute "PN" "5"
						( Origin gPackager )
					)
					( objectStatus "J1G3.5" )
				)
				( pin "dq(1)"
					( attribute "PN" "150"
						( Origin gPackager )
					)
					( objectStatus "J1G3.150" )
				)
				( pin "dq(2)"
					( attribute "PN" "12"
						( Origin gPackager )
					)
					( objectStatus "J1G3.12" )
				)
				( pin "dq(3)"
					( attribute "PN" "157"
						( Origin gPackager )
					)
					( objectStatus "J1G3.157" )
				)
				( pin "dq(4)"
					( attribute "PN" "3"
						( Origin gPackager )
					)
					( objectStatus "J1G3.3" )
				)
				( pin "dq(5)"
					( attribute "PN" "148"
						( Origin gPackager )
					)
					( objectStatus "J1G3.148" )
				)
				( pin "dq(6)"
					( attribute "PN" "10"
						( Origin gPackager )
					)
					( objectStatus "J1G3.10" )
				)
				( pin "dq(7)"
					( attribute "PN" "155"
						( Origin gPackager )
					)
					( objectStatus "J1G3.155" )
				)
				( pin "dq(8)"
					( attribute "PN" "16"
						( Origin gPackager )
					)
					( objectStatus "J1G3.16" )
				)
				( pin "dq(9)"
					( attribute "PN" "161"
						( Origin gPackager )
					)
					( objectStatus "J1G3.161" )
				)
				( pin "dq(10)"
					( attribute "PN" "23"
						( Origin gPackager )
					)
					( objectStatus "J1G3.23" )
				)
				( pin "dq(11)"
					( attribute "PN" "168"
						( Origin gPackager )
					)
					( objectStatus "J1G3.168" )
				)
				( pin "dq(12)"
					( attribute "PN" "14"
						( Origin gPackager )
					)
					( objectStatus "J1G3.14" )
				)
				( pin "dq(13)"
					( attribute "PN" "159"
						( Origin gPackager )
					)
					( objectStatus "J1G3.159" )
				)
				( pin "dq(14)"
					( attribute "PN" "21"
						( Origin gPackager )
					)
					( objectStatus "J1G3.21" )
				)
				( pin "dq(15)"
					( attribute "PN" "166"
						( Origin gPackager )
					)
					( objectStatus "J1G3.166" )
				)
				( pin "dq(16)"
					( attribute "PN" "27"
						( Origin gPackager )
					)
					( objectStatus "J1G3.27" )
				)
				( pin "dq(17)"
					( attribute "PN" "172"
						( Origin gPackager )
					)
					( objectStatus "J1G3.172" )
				)
				( pin "dq(18)"
					( attribute "PN" "34"
						( Origin gPackager )
					)
					( objectStatus "J1G3.34" )
				)
				( pin "dq(19)"
					( attribute "PN" "179"
						( Origin gPackager )
					)
					( objectStatus "J1G3.179" )
				)
				( pin "dq(20)"
					( attribute "PN" "25"
						( Origin gPackager )
					)
					( objectStatus "J1G3.25" )
				)
				( pin "dq(21)"
					( attribute "PN" "170"
						( Origin gPackager )
					)
					( objectStatus "J1G3.170" )
				)
				( pin "dq(22)"
					( attribute "PN" "32"
						( Origin gPackager )
					)
					( objectStatus "J1G3.32" )
				)
				( pin "dq(23)"
					( attribute "PN" "177"
						( Origin gPackager )
					)
					( objectStatus "J1G3.177" )
				)
				( pin "dq(24)"
					( attribute "PN" "38"
						( Origin gPackager )
					)
					( objectStatus "J1G3.38" )
				)
				( pin "dq(25)"
					( attribute "PN" "183"
						( Origin gPackager )
					)
					( objectStatus "J1G3.183" )
				)
				( pin "dq(26)"
					( attribute "PN" "45"
						( Origin gPackager )
					)
					( objectStatus "J1G3.45" )
				)
				( pin "dq(27)"
					( attribute "PN" "190"
						( Origin gPackager )
					)
					( objectStatus "J1G3.190" )
				)
				( pin "dq(28)"
					( attribute "PN" "36"
						( Origin gPackager )
					)
					( objectStatus "J1G3.36" )
				)
				( pin "dq(29)"
					( attribute "PN" "181"
						( Origin gPackager )
					)
					( objectStatus "J1G3.181" )
				)
				( pin "dq(30)"
					( attribute "PN" "43"
						( Origin gPackager )
					)
					( objectStatus "J1G3.43" )
				)
				( pin "dq(31)"
					( attribute "PN" "188"
						( Origin gPackager )
					)
					( objectStatus "J1G3.188" )
				)
				( pin "dq(32)"
					( attribute "PN" "97"
						( Origin gPackager )
					)
					( objectStatus "J1G3.97" )
				)
				( pin "dq(33)"
					( attribute "PN" "242"
						( Origin gPackager )
					)
					( objectStatus "J1G3.242" )
				)
				( pin "dq(34)"
					( attribute "PN" "104"
						( Origin gPackager )
					)
					( objectStatus "J1G3.104" )
				)
				( pin "dq(35)"
					( attribute "PN" "249"
						( Origin gPackager )
					)
					( objectStatus "J1G3.249" )
				)
				( pin "dq(36)"
					( attribute "PN" "95"
						( Origin gPackager )
					)
					( objectStatus "J1G3.95" )
				)
				( pin "dq(37)"
					( attribute "PN" "240"
						( Origin gPackager )
					)
					( objectStatus "J1G3.240" )
				)
				( pin "dq(38)"
					( attribute "PN" "102"
						( Origin gPackager )
					)
					( objectStatus "J1G3.102" )
				)
				( pin "dq(39)"
					( attribute "PN" "247"
						( Origin gPackager )
					)
					( objectStatus "J1G3.247" )
				)
				( pin "dq(40)"
					( attribute "PN" "108"
						( Origin gPackager )
					)
					( objectStatus "J1G3.108" )
				)
				( pin "dq(41)"
					( attribute "PN" "253"
						( Origin gPackager )
					)
					( objectStatus "J1G3.253" )
				)
				( pin "dq(42)"
					( attribute "PN" "115"
						( Origin gPackager )
					)
					( objectStatus "J1G3.115" )
				)
				( pin "dq(43)"
					( attribute "PN" "260"
						( Origin gPackager )
					)
					( objectStatus "J1G3.260" )
				)
				( pin "dq(44)"
					( attribute "PN" "106"
						( Origin gPackager )
					)
					( objectStatus "J1G3.106" )
				)
				( pin "dq(45)"
					( attribute "PN" "251"
						( Origin gPackager )
					)
					( objectStatus "J1G3.251" )
				)
				( pin "dq(46)"
					( attribute "PN" "113"
						( Origin gPackager )
					)
					( objectStatus "J1G3.113" )
				)
				( pin "dq(47)"
					( attribute "PN" "258"
						( Origin gPackager )
					)
					( objectStatus "J1G3.258" )
				)
				( pin "dq(48)"
					( attribute "PN" "119"
						( Origin gPackager )
					)
					( objectStatus "J1G3.119" )
				)
				( pin "dq(49)"
					( attribute "PN" "264"
						( Origin gPackager )
					)
					( objectStatus "J1G3.264" )
				)
				( pin "dq(50)"
					( attribute "PN" "126"
						( Origin gPackager )
					)
					( objectStatus "J1G3.126" )
				)
				( pin "dq(51)"
					( attribute "PN" "271"
						( Origin gPackager )
					)
					( objectStatus "J1G3.271" )
				)
				( pin "dq(52)"
					( attribute "PN" "117"
						( Origin gPackager )
					)
					( objectStatus "J1G3.117" )
				)
				( pin "dq(53)"
					( attribute "PN" "262"
						( Origin gPackager )
					)
					( objectStatus "J1G3.262" )
				)
				( pin "dq(54)"
					( attribute "PN" "124"
						( Origin gPackager )
					)
					( objectStatus "J1G3.124" )
				)
				( pin "dq(55)"
					( attribute "PN" "269"
						( Origin gPackager )
					)
					( objectStatus "J1G3.269" )
				)
				( pin "dq(56)"
					( attribute "PN" "130"
						( Origin gPackager )
					)
					( objectStatus "J1G3.130" )
				)
				( pin "dq(57)"
					( attribute "PN" "275"
						( Origin gPackager )
					)
					( objectStatus "J1G3.275" )
				)
				( pin "dq(58)"
					( attribute "PN" "137"
						( Origin gPackager )
					)
					( objectStatus "J1G3.137" )
				)
				( pin "dq(59)"
					( attribute "PN" "282"
						( Origin gPackager )
					)
					( objectStatus "J1G3.282" )
				)
				( pin "dq(60)"
					( attribute "PN" "128"
						( Origin gPackager )
					)
					( objectStatus "J1G3.128" )
				)
				( pin "dq(61)"
					( attribute "PN" "273"
						( Origin gPackager )
					)
					( objectStatus "J1G3.273" )
				)
				( pin "dq(62)"
					( attribute "PN" "135"
						( Origin gPackager )
					)
					( objectStatus "J1G3.135" )
				)
				( pin "dq(63)"
					( attribute "PN" "280"
						( Origin gPackager )
					)
					( objectStatus "J1G3.280" )
				)
				( pin "event_n"
					( attribute "PN" "78"
						( Origin gPackager )
					)
					( objectStatus "J1G3.78" )
				)
				( pin "odt(0)"
					( attribute "PN" "87"
						( Origin gPackager )
					)
					( objectStatus "J1G3.87" )
				)
				( pin "odt(1)"
					( attribute "PN" "91"
						( Origin gPackager )
					)
					( objectStatus "J1G3.91" )
				)
				( pin "par"
					( attribute "PN" "222"
						( Origin gPackager )
					)
					( objectStatus "J1G3.222" )
				)
				( pin "reset_n"
					( attribute "PN" "58"
						( Origin gPackager )
					)
					( objectStatus "J1G3.58" )
				)
				( pin "rfu(0)"
					( attribute "PN" "205"
						( Origin gPackager )
					)
					( objectStatus "J1G3.205" )
				)
				( pin "rfu(1)"
					( attribute "PN" "227"
						( Origin gPackager )
					)
					( objectStatus "J1G3.227" )
				)
				( pin "rfu(2)"
					( attribute "PN" "144"
						( Origin gPackager )
					)
					( objectStatus "J1G3.144" )
				)
				( pin "s0_n"
					( attribute "PN" "84"
						( Origin gPackager )
					)
					( objectStatus "J1G3.84" )
				)
				( pin "s1_n"
					( attribute "PN" "89"
						( Origin gPackager )
					)
					( objectStatus "J1G3.89" )
				)
				( pin "s2_n_c(0)"
					( attribute "PN" "93"
						( Origin gPackager )
					)
					( objectStatus "J1G3.93" )
				)
				( pin "s3_n_c(1)"
					( attribute "PN" "237"
						( Origin gPackager )
					)
					( objectStatus "J1G3.237" )
				)
				( pin "sa(0)"
					( attribute "PN" "139"
						( Origin gPackager )
					)
					( objectStatus "J1G3.139" )
				)
				( pin "sa(1)"
					( attribute "PN" "140"
						( Origin gPackager )
					)
					( objectStatus "J1G3.140" )
				)
				( pin "sa(2)"
					( attribute "PN" "238"
						( Origin gPackager )
					)
					( objectStatus "J1G3.238" )
				)
				( pin "save_n_nc"
					( attribute "PN" "230"
						( Origin gPackager )
					)
					( objectStatus "J1G3.230" )
				)
				( pin "scl"
					( attribute "PN" "141"
						( Origin gPackager )
					)
					( objectStatus "J1G3.141" )
				)
				( pin "sda"
					( attribute "PN" "285"
						( Origin gPackager )
					)
					( objectStatus "J1G3.285" )
				)
				( pin "vddspd"
					( attribute "PN" "284"
						( Origin gPackager )
					)
					( objectStatus "J1G3.284" )
				)
				( pin "vrefca"
					( attribute "PN" "146"
						( Origin gPackager )
					)
					( objectStatus "J1G3.146" )
				)
			)
			( gate "@baseboard_fab2_lib.baseboard_fab2(sch_1):page82_i64"
				( attribute "BOM_COST" "MEM"
					( Origin gFrontEnd )
				)
				( attribute "CDS_LIB" "mstr_sconn"
					( Origin gPackager )
				)
				( attribute "CDS_LOCATION" "J9U2"
					( Origin gPackager )
				)
				( attribute "CDS_SEC" "2"
					( Origin gPackager )
				)
				( attribute "LOCATION" "J9U2"
					( Origin gFrontEnd )
				)
				( attribute "MATERIAL" "SCONN"
					( Origin gFrontEnd )
				)
				( attribute "PACK_TYPE" "PIP"
					( Origin gFrontEnd )
				)
				( attribute "PART_NUMBER" "H44441-003"
					( Origin gFrontEnd )
				)
				( attribute "PHYS_PAGE" "82"
					( Origin gFrontEnd )
				)
				( attribute "ROOM" "DDR4_CH_J"
					( Origin gFrontEnd )
				)
				( attribute "ROT" "0"
					( Origin gFrontEnd )
				)
				( attribute "SEC" "2"
					( Origin gFrontEnd )
				)
				( attribute "SEC_TYPE" "PIP"
					( Origin gFrontEnd )
				)
				( attribute "VER" "2"
					( Origin gFrontEnd )
				)
				( attribute "XY" "(-50,4300)"
					( Origin gFrontEnd )
				)
				( attribute "CHIPS_PART_NAME" "SCONN288_H44441003"
					( Origin gPackager )
				)
				( attribute "CDS_PART_NAME" "SCONN288_H44441003_PIP-SCONN,HA"
					( Origin gPackager )
				)
				( objectStatus "J9U2" )
				( pin "dqs0n"
					( attribute "PN" "152"
						( Origin gPackager )
					)
					( objectStatus "J9U2.152" )
				)
				( pin "dqs0p"
					( attribute "PN" "153"
						( Origin gPackager )
					)
					( objectStatus "J9U2.153" )
				)
				( pin "dqs1n"
					( attribute "PN" "163"
						( Origin gPackager )
					)
					( objectStatus "J9U2.163" )
				)
				( pin "dqs1p"
					( attribute "PN" "164"
						( Origin gPackager )
					)
					( objectStatus "J9U2.164" )
				)
				( pin "dqs2n"
					( attribute "PN" "174"
						( Origin gPackager )
					)
					( objectStatus "J9U2.174" )
				)
				( pin "dqs2p"
					( attribute "PN" "175"
						( Origin gPackager )
					)
					( objectStatus "J9U2.175" )
				)
				( pin "dqs3n"
					( attribute "PN" "185"
						( Origin gPackager )
					)
					( objectStatus "J9U2.185" )
				)
				( pin "dqs3p"
					( attribute "PN" "186"
						( Origin gPackager )
					)
					( objectStatus "J9U2.186" )
				)
				( pin "dqs4n"
					( attribute "PN" "244"
						( Origin gPackager )
					)
					( objectStatus "J9U2.244" )
				)
				( pin "dqs4p"
					( attribute "PN" "245"
						( Origin gPackager )
					)
					( objectStatus "J9U2.245" )
				)
				( pin "dqs5n"
					( attribute "PN" "255"
						( Origin gPackager )
					)
					( objectStatus "J9U2.255" )
				)
				( pin "dqs5p"
					( attribute "PN" "256"
						( Origin gPackager )
					)
					( objectStatus "J9U2.256" )
				)
				( pin "dqs6n"
					( attribute "PN" "266"
						( Origin gPackager )
					)
					( objectStatus "J9U2.266" )
				)
				( pin "dqs6p"
					( attribute "PN" "267"
						( Origin gPackager )
					)
					( objectStatus "J9U2.267" )
				)
				( pin "dqs7n"
					( attribute "PN" "277"
						( Origin gPackager )
					)
					( objectStatus "J9U2.277" )
				)
				( pin "dqs7p"
					( attribute "PN" "278"
						( Origin gPackager )
					)
					( objectStatus "J9U2.278" )
				)
				( pin "dqs8n"
					( attribute "PN" "196"
						( Origin gPackager )
					)
					( objectStatus "J9U2.196" )
				)
				( pin "dqs8p"
					( attribute "PN" "197"
						( Origin gPackager )
					)
					( objectStatus "J9U2.197" )
				)
				( pin "dqs9n"
					( attribute "PN" "8"
						( Origin gPackager )
					)
					( objectStatus "J9U2.8" )
				)
				( pin "dqs9p"
					( attribute "PN" "7"
						( Origin gPackager )
					)
					( objectStatus "J9U2.7" )
				)
				( pin "dqs10n"
					( attribute "PN" "19"
						( Origin gPackager )
					)
					( objectStatus "J9U2.19" )
				)
				( pin "dqs10p"
					( attribute "PN" "18"
						( Origin gPackager )
					)
					( objectStatus "J9U2.18" )
				)
				( pin "dqs11n"
					( attribute "PN" "30"
						( Origin gPackager )
					)
					( objectStatus "J9U2.30" )
				)
				( pin "dqs11p"
					( attribute "PN" "29"
						( Origin gPackager )
					)
					( objectStatus "J9U2.29" )
				)
				( pin "dqs12n"
					( attribute "PN" "41"
						( Origin gPackager )
					)
					( objectStatus "J9U2.41" )
				)
				( pin "dqs12p"
					( attribute "PN" "40"
						( Origin gPackager )
					)
					( objectStatus "J9U2.40" )
				)
				( pin "dqs13n"
					( attribute "PN" "100"
						( Origin gPackager )
					)
					( objectStatus "J9U2.100" )
				)
				( pin "dqs13p"
					( attribute "PN" "99"
						( Origin gPackager )
					)
					( objectStatus "J9U2.99" )
				)
				( pin "dqs14n"
					( attribute "PN" "111"
						( Origin gPackager )
					)
					( objectStatus "J9U2.111" )
				)
				( pin "dqs14p"
					( attribute "PN" "110"
						( Origin gPackager )
					)
					( objectStatus "J9U2.110" )
				)
				( pin "dqs15n"
					( attribute "PN" "122"
						( Origin gPackager )
					)
					( objectStatus "J9U2.122" )
				)
				( pin "dqs15p"
					( attribute "PN" "121"
						( Origin gPackager )
					)
					( objectStatus "J9U2.121" )
				)
				( pin "dqs16n"
					( attribute "PN" "133"
						( Origin gPackager )
					)
					( objectStatus "J9U2.133" )
				)
				( pin "dqs16p"
					( attribute "PN" "132"
						( Origin gPackager )
					)
					( objectStatus "J9U2.132" )
				)
				( pin "dqs17n"
					( attribute "PN" "52"
						( Origin gPackager )
					)
					( objectStatus "J9U2.52" )
				)
				( pin "dqs17p"
					( attribute "PN" "51"
						( Origin gPackager )
					)
					( objectStatus "J9U2.51" )
				)
			)
			( gate "@baseboard_fab2_lib.baseboard_fab2(sch_1):page82_i171"
				( attribute "BOM_COST" "MEM"
					( Origin gFrontEnd )
				)
				( attribute "CDS_LIB" "mstr_sconn"
					( Origin gPackager )
				)
				( attribute "CDS_LOCATION" "J9U2"
					( Origin gPackager )
				)
				( attribute "CDS_SEC" "4"
					( Origin gPackager )
				)
				( attribute "LOCATION" "J9U2"
					( Origin gFrontEnd )
				)
				( attribute "MATERIAL" "SCONN"
					( Origin gFrontEnd )
				)
				( attribute "PACK_TYPE" "PIP"
					( Origin gFrontEnd )
				)
				( attribute "PART_NUMBER" "H44441-003"
					( Origin gFrontEnd )
				)
				( attribute "PHYS_PAGE" "82"
					( Origin gFrontEnd )
				)
				( attribute "ROOM" "DDR4_CH_J"
					( Origin gFrontEnd )
				)
				( attribute "ROT" "0"
					( Origin gFrontEnd )
				)
				( attribute "SEC" "4"
					( Origin gFrontEnd )
				)
				( attribute "SEC_TYPE" "PIP"
					( Origin gFrontEnd )
				)
				( attribute "VER" "4"
					( Origin gFrontEnd )
				)
				( attribute "XY" "(-350,2050)"
					( Origin gFrontEnd )
				)
				( attribute "CHIPS_PART_NAME" "SCONN288_H44441003"
					( Origin gPackager )
				)
				( attribute "CDS_PART_NAME" "SCONN288_H44441003_PIP-SCONN,HA"
					( Origin gPackager )
				)
				( objectStatus "J9U2" )
				( pin "\12v\(0)"
					( attribute "PN" "145"
						( Origin gPackager )
					)
					( objectStatus "J9U2.145" )
				)
				( pin "\12v\(1)"
					( attribute "PN" "1"
						( Origin gPackager )
					)
					( objectStatus "J9U2.1" )
				)
				( pin "vdd(0)"
					( attribute "PN" "236"
						( Origin gPackager )
					)
					( objectStatus "J9U2.236" )
				)
				( pin "vdd(1)"
					( attribute "PN" "233"
						( Origin gPackager )
					)
					( objectStatus "J9U2.233" )
				)
				( pin "vdd(2)"
					( attribute "PN" "231"
						( Origin gPackager )
					)
					( objectStatus "J9U2.231" )
				)
				( pin "vdd(3)"
					( attribute "PN" "229"
						( Origin gPackager )
					)
					( objectStatus "J9U2.229" )
				)
				( pin "vdd(4)"
					( attribute "PN" "226"
						( Origin gPackager )
					)
					( objectStatus "J9U2.226" )
				)
				( pin "vdd(5)"
					( attribute "PN" "223"
						( Origin gPackager )
					)
					( objectStatus "J9U2.223" )
				)
				( pin "vdd(6)"
					( attribute "PN" "220"
						( Origin gPackager )
					)
					( objectStatus "J9U2.220" )
				)
				( pin "vdd(7)"
					( attribute "PN" "217"
						( Origin gPackager )
					)
					( objectStatus "J9U2.217" )
				)
				( pin "vdd(8)"
					( attribute "PN" "215"
						( Origin gPackager )
					)
					( objectStatus "J9U2.215" )
				)
				( pin "vdd(9)"
					( attribute "PN" "212"
						( Origin gPackager )
					)
					( objectStatus "J9U2.212" )
				)
				( pin "vdd(10)"
					( attribute "PN" "209"
						( Origin gPackager )
					)
					( objectStatus "J9U2.209" )
				)
				( pin "vdd(11)"
					( attribute "PN" "206"
						( Origin gPackager )
					)
					( objectStatus "J9U2.206" )
				)
				( pin "vdd(12)"
					( attribute "PN" "204"
						( Origin gPackager )
					)
					( objectStatus "J9U2.204" )
				)
				( pin "vdd(13)"
					( attribute "PN" "92"
						( Origin gPackager )
					)
					( objectStatus "J9U2.92" )
				)
				( pin "vdd(14)"
					( attribute "PN" "90"
						( Origin gPackager )
					)
					( objectStatus "J9U2.90" )
				)
				( pin "vdd(15)"
					( attribute "PN" "88"
						( Origin gPackager )
					)
					( objectStatus "J9U2.88" )
				)
				( pin "vdd(16)"
					( attribute "PN" "85"
						( Origin gPackager )
					)
					( objectStatus "J9U2.85" )
				)
				( pin "vdd(17)"
					( attribute "PN" "83"
						( Origin gPackager )
					)
					( objectStatus "J9U2.83" )
				)
				( pin "vdd(18)"
					( attribute "PN" "80"
						( Origin gPackager )
					)
					( objectStatus "J9U2.80" )
				)
				( pin "vdd(19)"
					( attribute "PN" "76"
						( Origin gPackager )
					)
					( objectStatus "J9U2.76" )
				)
				( pin "vdd(20)"
					( attribute "PN" "73"
						( Origin gPackager )
					)
					( objectStatus "J9U2.73" )
				)
				( pin "vdd(21)"
					( attribute "PN" "70"
						( Origin gPackager )
					)
					( objectStatus "J9U2.70" )
				)
				( pin "vdd(22)"
					( attribute "PN" "67"
						( Origin gPackager )
					)
					( objectStatus "J9U2.67" )
				)
				( pin "vdd(23)"
					( attribute "PN" "64"
						( Origin gPackager )
					)
					( objectStatus "J9U2.64" )
				)
				( pin "vdd(24)"
					( attribute "PN" "61"
						( Origin gPackager )
					)
					( objectStatus "J9U2.61" )
				)
				( pin "vdd(25)"
					( attribute "PN" "59"
						( Origin gPackager )
					)
					( objectStatus "J9U2.59" )
				)
				( pin "vpp(0)"
					( attribute "PN" "287"
						( Origin gPackager )
					)
					( objectStatus "J9U2.287" )
				)
				( pin "vpp(1)"
					( attribute "PN" "286"
						( Origin gPackager )
					)
					( objectStatus "J9U2.286" )
				)
				( pin "vpp(2)"
					( attribute "PN" "288"
						( Origin gPackager )
					)
					( objectStatus "J9U2.288" )
				)
				( pin "vpp(3)"
					( attribute "PN" "143"
						( Origin gPackager )
					)
					( objectStatus "J9U2.143" )
				)
				( pin "vpp(4)"
					( attribute "PN" "142"
						( Origin gPackager )
					)
					( objectStatus "J9U2.142" )
				)
				( pin "vtt(0)"
					( attribute "PN" "221"
						( Origin gPackager )
					)
					( objectStatus "J9U2.221" )
				)
				( pin "vtt(1)"
					( attribute "PN" "77"
						( Origin gPackager )
					)
					( objectStatus "J9U2.77" )
				)
			)
			( gate "@baseboard_fab2_lib.baseboard_fab2(sch_1):page82_i180"
				( attribute "BOM_COST" "MEM"
					( Origin gFrontEnd )
				)
				( attribute "CDS_LIB" "dev_discrete"
					( Origin gPackager )
				)
				( attribute "CDS_LOCATION" "C1G19"
					( Origin gPackager )
				)
				( attribute "CDS_SEC" "1"
					( Origin gPackager )
				)
				( attribute "LOCATION" "C1G19"
					( Origin gFrontEnd )
				)
				( attribute "MATERIAL" "X7R"
					( Origin gFrontEnd )
				)
				( attribute "PACK_TYPE" "0402V"
					( Origin gFrontEnd )
				)
				( attribute "PART_NUMBER" "A36096-045"
					( Origin gFrontEnd )
				)
				( attribute "PHYS_PAGE" "82"
					( Origin gFrontEnd )
				)
				( attribute "ROOM" "DDR4_CH_J"
					( Origin gFrontEnd )
				)
				( attribute "ROT" "2"
					( Origin gFrontEnd )
				)
				( attribute "SEC" "1"
					( Origin gPackager )
				)
				( attribute "TOLERANCE" "10%"
					( Origin gFrontEnd )
				)
				( attribute "VALUE" "0.01UF"
					( Origin gFrontEnd )
				)
				( attribute "VER" "1"
					( Origin gFrontEnd )
				)
				( attribute "VOLTAGE" "25V"
					( Units "uVoltage" "V" 1.000000)
					( Origin gFrontEnd )
				)
				( attribute "XY" "(-4500,1450)"
					( Origin gFrontEnd )
				)
				( attribute "CHIPS_PART_NAME" "CAP_A"
					( Origin gPackager )
				)
				( attribute "CDS_PART_NAME" "CAP_A_0402V-0.01UF,25V,10%,X7RA"
					( Origin gPackager )
				)
				( objectStatus "C1G19" )
				( pin "a"
					( attribute "PN" "1"
						( Origin gPackager )
					)
					( objectStatus "C1G19.1" )
				)
				( pin "b"
					( attribute "PN" "2"
						( Origin gPackager )
					)
					( objectStatus "C1G19.2" )
				)
			)
			( gate "@baseboard_fab2_lib.baseboard_fab2(sch_1):page82_i187"
				( attribute "BOM_COST" "MEM"
					( Origin gFrontEnd )
				)
				( attribute "CDS_LIB" "mstr_sconn"
					( Origin gPackager )
				)
				( attribute "CDS_LOCATION" "J9U2"
					( Origin gPackager )
				)
				( attribute "CDS_SEC" "1"
					( Origin gPackager )
				)
				( attribute "LOCATION" "J9U2"
					( Origin gFrontEnd )
				)
				( attribute "MATERIAL" "SCONN"
					( Origin gFrontEnd )
				)
				( attribute "PACK_TYPE" "PIP"
					( Origin gFrontEnd )
				)
				( attribute "PART_NUMBER" "H44441-003"
					( Origin gFrontEnd )
				)
				( attribute "PHYS_PAGE" "82"
					( Origin gFrontEnd )
				)
				( attribute "ROOM" "DDR4_CH_J"
					( Origin gFrontEnd )
				)
				( attribute "ROT" "0"
					( Origin gFrontEnd )
				)
				( attribute "SEC" "1"
					( Origin gFrontEnd )
				)
				( attribute "SEC_TYPE" "PIP"
					( Origin gFrontEnd )
				)
				( attribute "VER" "1"
					( Origin gFrontEnd )
				)
				( attribute "XY" "(-2500,3150)"
					( Origin gFrontEnd )
				)
				( attribute "CHIPS_PART_NAME" "SCONN288_H44441003"
					( Origin gPackager )
				)
				( attribute "CDS_PART_NAME" "SCONN288_H44441003_PIP-SCONN,HA"
					( Origin gPackager )
				)
				( objectStatus "J9U2" )
				( pin "a0"
					( attribute "PN" "79"
						( Origin gPackager )
					)
					( objectStatus "J9U2.79" )
				)
				( pin "a1"
					( attribute "PN" "72"
						( Origin gPackager )
					)
					( objectStatus "J9U2.72" )
				)
				( pin "a2"
					( attribute "PN" "216"
						( Origin gPackager )
					)
					( objectStatus "J9U2.216" )
				)
				( pin "a3"
					( attribute "PN" "71"
						( Origin gPackager )
					)
					( objectStatus "J9U2.71" )
				)
				( pin "a4"
					( attribute "PN" "214"
						( Origin gPackager )
					)
					( objectStatus "J9U2.214" )
				)
				( pin "a5"
					( attribute "PN" "213"
						( Origin gPackager )
					)
					( objectStatus "J9U2.213" )
				)
				( pin "a6"
					( attribute "PN" "69"
						( Origin gPackager )
					)
					( objectStatus "J9U2.69" )
				)
				( pin "a7"
					( attribute "PN" "211"
						( Origin gPackager )
					)
					( objectStatus "J9U2.211" )
				)
				( pin "a8"
					( attribute "PN" "68"
						( Origin gPackager )
					)
					( objectStatus "J9U2.68" )
				)
				( pin "a9"
					( attribute "PN" "66"
						( Origin gPackager )
					)
					( objectStatus "J9U2.66" )
				)
				( pin "a10"
					( attribute "PN" "225"
						( Origin gPackager )
					)
					( objectStatus "J9U2.225" )
				)
				( pin "a11"
					( attribute "PN" "210"
						( Origin gPackager )
					)
					( objectStatus "J9U2.210" )
				)
				( pin "a12"
					( attribute "PN" "65"
						( Origin gPackager )
					)
					( objectStatus "J9U2.65" )
				)
				( pin "a13"
					( attribute "PN" "232"
						( Origin gPackager )
					)
					( objectStatus "J9U2.232" )
				)
				( pin "a14_we_n"
					( attribute "PN" "228"
						( Origin gPackager )
					)
					( objectStatus "J9U2.228" )
				)
				( pin "a15_cas_n"
					( attribute "PN" "86"
						( Origin gPackager )
					)
					( objectStatus "J9U2.86" )
				)
				( pin "a16_ras_n"
					( attribute "PN" "82"
						( Origin gPackager )
					)
					( objectStatus "J9U2.82" )
				)
				( pin "a17"
					( attribute "PN" "234"
						( Origin gPackager )
					)
					( objectStatus "J9U2.234" )
				)
				( pin "act_n"
					( attribute "PN" "62"
						( Origin gPackager )
					)
					( objectStatus "J9U2.62" )
				)
				( pin "alert_n"
					( attribute "PN" "208"
						( Origin gPackager )
					)
					( objectStatus "J9U2.208" )
				)
				( pin "ba(0)"
					( attribute "PN" "81"
						( Origin gPackager )
					)
					( objectStatus "J9U2.81" )
				)
				( pin "ba(1)"
					( attribute "PN" "224"
						( Origin gPackager )
					)
					( objectStatus "J9U2.224" )
				)
				( pin "bg(0)"
					( attribute "PN" "63"
						( Origin gPackager )
					)
					( objectStatus "J9U2.63" )
				)
				( pin "bg(1)"
					( attribute "PN" "207"
						( Origin gPackager )
					)
					( objectStatus "J9U2.207" )
				)
				( pin "c(2)"
					( attribute "PN" "235"
						( Origin gPackager )
					)
					( objectStatus "J9U2.235" )
				)
				( pin "cb(0)"
					( attribute "PN" "49"
						( Origin gPackager )
					)
					( objectStatus "J9U2.49" )
				)
				( pin "cb(1)"
					( attribute "PN" "194"
						( Origin gPackager )
					)
					( objectStatus "J9U2.194" )
				)
				( pin "cb(2)"
					( attribute "PN" "56"
						( Origin gPackager )
					)
					( objectStatus "J9U2.56" )
				)
				( pin "cb(3)"
					( attribute "PN" "201"
						( Origin gPackager )
					)
					( objectStatus "J9U2.201" )
				)
				( pin "cb(4)"
					( attribute "PN" "47"
						( Origin gPackager )
					)
					( objectStatus "J9U2.47" )
				)
				( pin "cb(5)"
					( attribute "PN" "192"
						( Origin gPackager )
					)
					( objectStatus "J9U2.192" )
				)
				( pin "cb(6)"
					( attribute "PN" "54"
						( Origin gPackager )
					)
					( objectStatus "J9U2.54" )
				)
				( pin "cb(7)"
					( attribute "PN" "199"
						( Origin gPackager )
					)
					( objectStatus "J9U2.199" )
				)
				( pin "ck0n"
					( attribute "PN" "75"
						( Origin gPackager )
					)
					( objectStatus "J9U2.75" )
				)
				( pin "ck0p"
					( attribute "PN" "74"
						( Origin gPackager )
					)
					( objectStatus "J9U2.74" )
				)
				( pin "ck1n"
					( attribute "PN" "219"
						( Origin gPackager )
					)
					( objectStatus "J9U2.219" )
				)
				( pin "ck1p"
					( attribute "PN" "218"
						( Origin gPackager )
					)
					( objectStatus "J9U2.218" )
				)
				( pin "cke(0)"
					( attribute "PN" "60"
						( Origin gPackager )
					)
					( objectStatus "J9U2.60" )
				)
				( pin "cke(1)"
					( attribute "PN" "203"
						( Origin gPackager )
					)
					( objectStatus "J9U2.203" )
				)
				( pin "dq(0)"
					( attribute "PN" "5"
						( Origin gPackager )
					)
					( objectStatus "J9U2.5" )
				)
				( pin "dq(1)"
					( attribute "PN" "150"
						( Origin gPackager )
					)
					( objectStatus "J9U2.150" )
				)
				( pin "dq(2)"
					( attribute "PN" "12"
						( Origin gPackager )
					)
					( objectStatus "J9U2.12" )
				)
				( pin "dq(3)"
					( attribute "PN" "157"
						( Origin gPackager )
					)
					( objectStatus "J9U2.157" )
				)
				( pin "dq(4)"
					( attribute "PN" "3"
						( Origin gPackager )
					)
					( objectStatus "J9U2.3" )
				)
				( pin "dq(5)"
					( attribute "PN" "148"
						( Origin gPackager )
					)
					( objectStatus "J9U2.148" )
				)
				( pin "dq(6)"
					( attribute "PN" "10"
						( Origin gPackager )
					)
					( objectStatus "J9U2.10" )
				)
				( pin "dq(7)"
					( attribute "PN" "155"
						( Origin gPackager )
					)
					( objectStatus "J9U2.155" )
				)
				( pin "dq(8)"
					( attribute "PN" "16"
						( Origin gPackager )
					)
					( objectStatus "J9U2.16" )
				)
				( pin "dq(9)"
					( attribute "PN" "161"
						( Origin gPackager )
					)
					( objectStatus "J9U2.161" )
				)
				( pin "dq(10)"
					( attribute "PN" "23"
						( Origin gPackager )
					)
					( objectStatus "J9U2.23" )
				)
				( pin "dq(11)"
					( attribute "PN" "168"
						( Origin gPackager )
					)
					( objectStatus "J9U2.168" )
				)
				( pin "dq(12)"
					( attribute "PN" "14"
						( Origin gPackager )
					)
					( objectStatus "J9U2.14" )
				)
				( pin "dq(13)"
					( attribute "PN" "159"
						( Origin gPackager )
					)
					( objectStatus "J9U2.159" )
				)
				( pin "dq(14)"
					( attribute "PN" "21"
						( Origin gPackager )
					)
					( objectStatus "J9U2.21" )
				)
				( pin "dq(15)"
					( attribute "PN" "166"
						( Origin gPackager )
					)
					( objectStatus "J9U2.166" )
				)
				( pin "dq(16)"
					( attribute "PN" "27"
						( Origin gPackager )
					)
					( objectStatus "J9U2.27" )
				)
				( pin "dq(17)"
					( attribute "PN" "172"
						( Origin gPackager )
					)
					( objectStatus "J9U2.172" )
				)
				( pin "dq(18)"
					( attribute "PN" "34"
						( Origin gPackager )
					)
					( objectStatus "J9U2.34" )
				)
				( pin "dq(19)"
					( attribute "PN" "179"
						( Origin gPackager )
					)
					( objectStatus "J9U2.179" )
				)
				( pin "dq(20)"
					( attribute "PN" "25"
						( Origin gPackager )
					)
					( objectStatus "J9U2.25" )
				)
				( pin "dq(21)"
					( attribute "PN" "170"
						( Origin gPackager )
					)
					( objectStatus "J9U2.170" )
				)
				( pin "dq(22)"
					( attribute "PN" "32"
						( Origin gPackager )
					)
					( objectStatus "J9U2.32" )
				)
				( pin "dq(23)"
					( attribute "PN" "177"
						( Origin gPackager )
					)
					( objectStatus "J9U2.177" )
				)
				( pin "dq(24)"
					( attribute "PN" "38"
						( Origin gPackager )
					)
					( objectStatus "J9U2.38" )
				)
				( pin "dq(25)"
					( attribute "PN" "183"
						( Origin gPackager )
					)
					( objectStatus "J9U2.183" )
				)
				( pin "dq(26)"
					( attribute "PN" "45"
						( Origin gPackager )
					)
					( objectStatus "J9U2.45" )
				)
				( pin "dq(27)"
					( attribute "PN" "190"
						( Origin gPackager )
					)
					( objectStatus "J9U2.190" )
				)
				( pin "dq(28)"
					( attribute "PN" "36"
						( Origin gPackager )
					)
					( objectStatus "J9U2.36" )
				)
				( pin "dq(29)"
					( attribute "PN" "181"
						( Origin gPackager )
					)
					( objectStatus "J9U2.181" )
				)
				( pin "dq(30)"
					( attribute "PN" "43"
						( Origin gPackager )
					)
					( objectStatus "J9U2.43" )
				)
				( pin "dq(31)"
					( attribute "PN" "188"
						( Origin gPackager )
					)
					( objectStatus "J9U2.188" )
				)
				( pin "dq(32)"
					( attribute "PN" "97"
						( Origin gPackager )
					)
					( objectStatus "J9U2.97" )
				)
				( pin "dq(33)"
					( attribute "PN" "242"
						( Origin gPackager )
					)
					( objectStatus "J9U2.242" )
				)
				( pin "dq(34)"
					( attribute "PN" "104"
						( Origin gPackager )
					)
					( objectStatus "J9U2.104" )
				)
				( pin "dq(35)"
					( attribute "PN" "249"
						( Origin gPackager )
					)
					( objectStatus "J9U2.249" )
				)
				( pin "dq(36)"
					( attribute "PN" "95"
						( Origin gPackager )
					)
					( objectStatus "J9U2.95" )
				)
				( pin "dq(37)"
					( attribute "PN" "240"
						( Origin gPackager )
					)
					( objectStatus "J9U2.240" )
				)
				( pin "dq(38)"
					( attribute "PN" "102"
						( Origin gPackager )
					)
					( objectStatus "J9U2.102" )
				)
				( pin "dq(39)"
					( attribute "PN" "247"
						( Origin gPackager )
					)
					( objectStatus "J9U2.247" )
				)
				( pin "dq(40)"
					( attribute "PN" "108"
						( Origin gPackager )
					)
					( objectStatus "J9U2.108" )
				)
				( pin "dq(41)"
					( attribute "PN" "253"
						( Origin gPackager )
					)
					( objectStatus "J9U2.253" )
				)
				( pin "dq(42)"
					( attribute "PN" "115"
						( Origin gPackager )
					)
					( objectStatus "J9U2.115" )
				)
				( pin "dq(43)"
					( attribute "PN" "260"
						( Origin gPackager )
					)
					( objectStatus "J9U2.260" )
				)
				( pin "dq(44)"
					( attribute "PN" "106"
						( Origin gPackager )
					)
					( objectStatus "J9U2.106" )
				)
				( pin "dq(45)"
					( attribute "PN" "251"
						( Origin gPackager )
					)
					( objectStatus "J9U2.251" )
				)
				( pin "dq(46)"
					( attribute "PN" "113"
						( Origin gPackager )
					)
					( objectStatus "J9U2.113" )
				)
				( pin "dq(47)"
					( attribute "PN" "258"
						( Origin gPackager )
					)
					( objectStatus "J9U2.258" )
				)
				( pin "dq(48)"
					( attribute "PN" "119"
						( Origin gPackager )
					)
					( objectStatus "J9U2.119" )
				)
				( pin "dq(49)"
					( attribute "PN" "264"
						( Origin gPackager )
					)
					( objectStatus "J9U2.264" )
				)
				( pin "dq(50)"
					( attribute "PN" "126"
						( Origin gPackager )
					)
					( objectStatus "J9U2.126" )
				)
				( pin "dq(51)"
					( attribute "PN" "271"
						( Origin gPackager )
					)
					( objectStatus "J9U2.271" )
				)
				( pin "dq(52)"
					( attribute "PN" "117"
						( Origin gPackager )
					)
					( objectStatus "J9U2.117" )
				)
				( pin "dq(53)"
					( attribute "PN" "262"
						( Origin gPackager )
					)
					( objectStatus "J9U2.262" )
				)
				( pin "dq(54)"
					( attribute "PN" "124"
						( Origin gPackager )
					)
					( objectStatus "J9U2.124" )
				)
				( pin "dq(55)"
					( attribute "PN" "269"
						( Origin gPackager )
					)
					( objectStatus "J9U2.269" )
				)
				( pin "dq(56)"
					( attribute "PN" "130"
						( Origin gPackager )
					)
					( objectStatus "J9U2.130" )
				)
				( pin "dq(57)"
					( attribute "PN" "275"
						( Origin gPackager )
					)
					( objectStatus "J9U2.275" )
				)
				( pin "dq(58)"
					( attribute "PN" "137"
						( Origin gPackager )
					)
					( objectStatus "J9U2.137" )
				)
				( pin "dq(59)"
					( attribute "PN" "282"
						( Origin gPackager )
					)
					( objectStatus "J9U2.282" )
				)
				( pin "dq(60)"
					( attribute "PN" "128"
						( Origin gPackager )
					)
					( objectStatus "J9U2.128" )
				)
				( pin "dq(61)"
					( attribute "PN" "273"
						( Origin gPackager )
					)
					( objectStatus "J9U2.273" )
				)
				( pin "dq(62)"
					( attribute "PN" "135"
						( Origin gPackager )
					)
					( objectStatus "J9U2.135" )
				)
				( pin "dq(63)"
					( attribute "PN" "280"
						( Origin gPackager )
					)
					( objectStatus "J9U2.280" )
				)
				( pin "event_n"
					( attribute "PN" "78"
						( Origin gPackager )
					)
					( objectStatus "J9U2.78" )
				)
				( pin "odt(0)"
					( attribute "PN" "87"
						( Origin gPackager )
					)
					( objectStatus "J9U2.87" )
				)
				( pin "odt(1)"
					( attribute "PN" "91"
						( Origin gPackager )
					)
					( objectStatus "J9U2.91" )
				)
				( pin "par"
					( attribute "PN" "222"
						( Origin gPackager )
					)
					( objectStatus "J9U2.222" )
				)
				( pin "reset_n"
					( attribute "PN" "58"
						( Origin gPackager )
					)
					( objectStatus "J9U2.58" )
				)
				( pin "rfu(0)"
					( attribute "PN" "205"
						( Origin gPackager )
					)
					( objectStatus "J9U2.205" )
				)
				( pin "rfu(1)"
					( attribute "PN" "227"
						( Origin gPackager )
					)
					( objectStatus "J9U2.227" )
				)
				( pin "rfu(2)"
					( attribute "PN" "144"
						( Origin gPackager )
					)
					( objectStatus "J9U2.144" )
				)
				( pin "s0_n"
					( attribute "PN" "84"
						( Origin gPackager )
					)
					( objectStatus "J9U2.84" )
				)
				( pin "s1_n"
					( attribute "PN" "89"
						( Origin gPackager )
					)
					( objectStatus "J9U2.89" )
				)
				( pin "s2_n_c(0)"
					( attribute "PN" "93"
						( Origin gPackager )
					)
					( objectStatus "J9U2.93" )
				)
				( pin "s3_n_c(1)"
					( attribute "PN" "237"
						( Origin gPackager )
					)
					( objectStatus "J9U2.237" )
				)
				( pin "sa(0)"
					( attribute "PN" "139"
						( Origin gPackager )
					)
					( objectStatus "J9U2.139" )
				)
				( pin "sa(1)"
					( attribute "PN" "140"
						( Origin gPackager )
					)
					( objectStatus "J9U2.140" )
				)
				( pin "sa(2)"
					( attribute "PN" "238"
						( Origin gPackager )
					)
					( objectStatus "J9U2.238" )
				)
				( pin "save_n_nc"
					( attribute "PN" "230"
						( Origin gPackager )
					)
					( objectStatus "J9U2.230" )
				)
				( pin "scl"
					( attribute "PN" "141"
						( Origin gPackager )
					)
					( objectStatus "J9U2.141" )
				)
				( pin "sda"
					( attribute "PN" "285"
						( Origin gPackager )
					)
					( objectStatus "J9U2.285" )
				)
				( pin "vddspd"
					( attribute "PN" "284"
						( Origin gPackager )
					)
					( objectStatus "J9U2.284" )
				)
				( pin "vrefca"
					( attribute "PN" "146"
						( Origin gPackager )
					)
					( objectStatus "J9U2.146" )
				)
			)
			( gate "@baseboard_fab2_lib.baseboard_fab2(sch_1):page82_i188"
				( attribute "BOM_COST" "MEM"
					( Origin gFrontEnd )
				)
				( attribute "CDS_LIB" "mstr_sconn"
					( Origin gPackager )
				)
				( attribute "CDS_LOCATION" "J9U2"
					( Origin gPackager )
				)
				( attribute "CDS_SEC" "3"
					( Origin gPackager )
				)
				( attribute "LOCATION" "J9U2"
					( Origin gFrontEnd )
				)
				( attribute "MATERIAL" "SCONN"
					( Origin gFrontEnd )
				)
				( attribute "PACK_TYPE" "PIP"
					( Origin gFrontEnd )
				)
				( attribute "PART_NUMBER" "H44441-003"
					( Origin gFrontEnd )
				)
				( attribute "PHYS_PAGE" "82"
					( Origin gFrontEnd )
				)
				( attribute "ROOM" "DDR4_CH_J"
					( Origin gFrontEnd )
				)
				( attribute "ROT" "0"
					( Origin gFrontEnd )
				)
				( attribute "SEC" "3"
					( Origin gFrontEnd )
				)
				( attribute "SEC_TYPE" "PIP"
					( Origin gFrontEnd )
				)
				( attribute "VER" "3"
					( Origin gFrontEnd )
				)
				( attribute "XY" "(1750,2350)"
					( Origin gFrontEnd )
				)
				( attribute "CHIPS_PART_NAME" "SCONN288_H44441003"
					( Origin gPackager )
				)
				( attribute "CDS_PART_NAME" "SCONN288_H44441003_PIP-SCONN,HA"
					( Origin gPackager )
				)
				( objectStatus "J9U2" )
				( pin "vss(0)"
					( attribute "PN" "283"
						( Origin gPackager )
					)
					( objectStatus "J9U2.283" )
				)
				( pin "vss(1)"
					( attribute "PN" "281"
						( Origin gPackager )
					)
					( objectStatus "J9U2.281" )
				)
				( pin "vss(2)"
					( attribute "PN" "279"
						( Origin gPackager )
					)
					( objectStatus "J9U2.279" )
				)
				( pin "vss(3)"
					( attribute "PN" "276"
						( Origin gPackager )
					)
					( objectStatus "J9U2.276" )
				)
				( pin "vss(4)"
					( attribute "PN" "274"
						( Origin gPackager )
					)
					( objectStatus "J9U2.274" )
				)
				( pin "vss(5)"
					( attribute "PN" "272"
						( Origin gPackager )
					)
					( objectStatus "J9U2.272" )
				)
				( pin "vss(6)"
					( attribute "PN" "270"
						( Origin gPackager )
					)
					( objectStatus "J9U2.270" )
				)
				( pin "vss(7)"
					( attribute "PN" "268"
						( Origin gPackager )
					)
					( objectStatus "J9U2.268" )
				)
				( pin "vss(8)"
					( attribute "PN" "265"
						( Origin gPackager )
					)
					( objectStatus "J9U2.265" )
				)
				( pin "vss(9)"
					( attribute "PN" "263"
						( Origin gPackager )
					)
					( objectStatus "J9U2.263" )
				)
				( pin "vss(10)"
					( attribute "PN" "261"
						( Origin gPackager )
					)
					( objectStatus "J9U2.261" )
				)
				( pin "vss(11)"
					( attribute "PN" "259"
						( Origin gPackager )
					)
					( objectStatus "J9U2.259" )
				)
				( pin "vss(12)"
					( attribute "PN" "257"
						( Origin gPackager )
					)
					( objectStatus "J9U2.257" )
				)
				( pin "vss(13)"
					( attribute "PN" "254"
						( Origin gPackager )
					)
					( objectStatus "J9U2.254" )
				)
				( pin "vss(14)"
					( attribute "PN" "252"
						( Origin gPackager )
					)
					( objectStatus "J9U2.252" )
				)
				( pin "vss(15)"
					( attribute "PN" "250"
						( Origin gPackager )
					)
					( objectStatus "J9U2.250" )
				)
				( pin "vss(16)"
					( attribute "PN" "248"
						( Origin gPackager )
					)
					( objectStatus "J9U2.248" )
				)
				( pin "vss(17)"
					( attribute "PN" "246"
						( Origin gPackager )
					)
					( objectStatus "J9U2.246" )
				)
				( pin "vss(18)"
					( attribute "PN" "243"
						( Origin gPackager )
					)
					( objectStatus "J9U2.243" )
				)
				( pin "vss(19)"
					( attribute "PN" "241"
						( Origin gPackager )
					)
					( objectStatus "J9U2.241" )
				)
				( pin "vss(20)"
					( attribute "PN" "239"
						( Origin gPackager )
					)
					( objectStatus "J9U2.239" )
				)
				( pin "vss(21)"
					( attribute "PN" "202"
						( Origin gPackager )
					)
					( objectStatus "J9U2.202" )
				)
				( pin "vss(22)"
					( attribute "PN" "200"
						( Origin gPackager )
					)
					( objectStatus "J9U2.200" )
				)
				( pin "vss(23)"
					( attribute "PN" "198"
						( Origin gPackager )
					)
					( objectStatus "J9U2.198" )
				)
				( pin "vss(24)"
					( attribute "PN" "195"
						( Origin gPackager )
					)
					( objectStatus "J9U2.195" )
				)
				( pin "vss(25)"
					( attribute "PN" "193"
						( Origin gPackager )
					)
					( objectStatus "J9U2.193" )
				)
				( pin "vss(26)"
					( attribute "PN" "191"
						( Origin gPackager )
					)
					( objectStatus "J9U2.191" )
				)
				( pin "vss(27)"
					( attribute "PN" "189"
						( Origin gPackager )
					)
					( objectStatus "J9U2.189" )
				)
				( pin "vss(28)"
					( attribute "PN" "187"
						( Origin gPackager )
					)
					( objectStatus "J9U2.187" )
				)
				( pin "vss(29)"
					( attribute "PN" "184"
						( Origin gPackager )
					)
					( objectStatus "J9U2.184" )
				)
				( pin "vss(30)"
					( attribute "PN" "182"
						( Origin gPackager )
					)
					( objectStatus "J9U2.182" )
				)
				( pin "vss(31)"
					( attribute "PN" "180"
						( Origin gPackager )
					)
					( objectStatus "J9U2.180" )
				)
				( pin "vss(32)"
					( attribute "PN" "178"
						( Origin gPackager )
					)
					( objectStatus "J9U2.178" )
				)
				( pin "vss(33)"
					( attribute "PN" "176"
						( Origin gPackager )
					)
					( objectStatus "J9U2.176" )
				)
				( pin "vss(34)"
					( attribute "PN" "173"
						( Origin gPackager )
					)
					( objectStatus "J9U2.173" )
				)
				( pin "vss(35)"
					( attribute "PN" "171"
						( Origin gPackager )
					)
					( objectStatus "J9U2.171" )
				)
				( pin "vss(36)"
					( attribute "PN" "169"
						( Origin gPackager )
					)
					( objectStatus "J9U2.169" )
				)
				( pin "vss(37)"
					( attribute "PN" "167"
						( Origin gPackager )
					)
					( objectStatus "J9U2.167" )
				)
				( pin "vss(38)"
					( attribute "PN" "165"
						( Origin gPackager )
					)
					( objectStatus "J9U2.165" )
				)
				( pin "vss(39)"
					( attribute "PN" "162"
						( Origin gPackager )
					)
					( objectStatus "J9U2.162" )
				)
				( pin "vss(40)"
					( attribute "PN" "160"
						( Origin gPackager )
					)
					( objectStatus "J9U2.160" )
				)
				( pin "vss(41)"
					( attribute "PN" "158"
						( Origin gPackager )
					)
					( objectStatus "J9U2.158" )
				)
				( pin "vss(42)"
					( attribute "PN" "156"
						( Origin gPackager )
					)
					( objectStatus "J9U2.156" )
				)
				( pin "vss(43)"
					( attribute "PN" "154"
						( Origin gPackager )
					)
					( objectStatus "J9U2.154" )
				)
				( pin "vss(44)"
					( attribute "PN" "151"
						( Origin gPackager )
					)
					( objectStatus "J9U2.151" )
				)
				( pin "vss(45)"
					( attribute "PN" "149"
						( Origin gPackager )
					)
					( objectStatus "J9U2.149" )
				)
				( pin "vss(46)"
					( attribute "PN" "147"
						( Origin gPackager )
					)
					( objectStatus "J9U2.147" )
				)
				( pin "vss(47)"
					( attribute "PN" "138"
						( Origin gPackager )
					)
					( objectStatus "J9U2.138" )
				)
				( pin "vss(48)"
					( attribute "PN" "136"
						( Origin gPackager )
					)
					( objectStatus "J9U2.136" )
				)
				( pin "vss(49)"
					( attribute "PN" "134"
						( Origin gPackager )
					)
					( objectStatus "J9U2.134" )
				)
				( pin "vss(50)"
					( attribute "PN" "131"
						( Origin gPackager )
					)
					( objectStatus "J9U2.131" )
				)
				( pin "vss(51)"
					( attribute "PN" "129"
						( Origin gPackager )
					)
					( objectStatus "J9U2.129" )
				)
				( pin "vss(52)"
					( attribute "PN" "127"
						( Origin gPackager )
					)
					( objectStatus "J9U2.127" )
				)
				( pin "vss(53)"
					( attribute "PN" "125"
						( Origin gPackager )
					)
					( objectStatus "J9U2.125" )
				)
				( pin "vss(54)"
					( attribute "PN" "123"
						( Origin gPackager )
					)
					( objectStatus "J9U2.123" )
				)
				( pin "vss(55)"
					( attribute "PN" "120"
						( Origin gPackager )
					)
					( objectStatus "J9U2.120" )
				)
				( pin "vss(56)"
					( attribute "PN" "118"
						( Origin gPackager )
					)
					( objectStatus "J9U2.118" )
				)
				( pin "vss(57)"
					( attribute "PN" "116"
						( Origin gPackager )
					)
					( objectStatus "J9U2.116" )
				)
				( pin "vss(58)"
					( attribute "PN" "114"
						( Origin gPackager )
					)
					( objectStatus "J9U2.114" )
				)
				( pin "vss(59)"
					( attribute "PN" "112"
						( Origin gPackager )
					)
					( objectStatus "J9U2.112" )
				)
				( pin "vss(60)"
					( attribute "PN" "109"
						( Origin gPackager )
					)
					( objectStatus "J9U2.109" )
				)
				( pin "vss(61)"
					( attribute "PN" "107"
						( Origin gPackager )
					)
					( objectStatus "J9U2.107" )
				)
				( pin "vss(62)"
					( attribute "PN" "105"
						( Origin gPackager )
					)
					( objectStatus "J9U2.105" )
				)
				( pin "vss(63)"
					( attribute "PN" "103"
						( Origin gPackager )
					)
					( objectStatus "J9U2.103" )
				)
				( pin "vss(64)"
					( attribute "PN" "101"
						( Origin gPackager )
					)
					( objectStatus "J9U2.101" )
				)
				( pin "vss(65)"
					( attribute "PN" "98"
						( Origin gPackager )
					)
					( objectStatus "J9U2.98" )
				)
				( pin "vss(66)"
					( attribute "PN" "96"
						( Origin gPackager )
					)
					( objectStatus "J9U2.96" )
				)
				( pin "vss(67)"
					( attribute "PN" "94"
						( Origin gPackager )
					)
					( objectStatus "J9U2.94" )
				)
				( pin "vss(68)"
					( attribute "PN" "57"
						( Origin gPackager )
					)
					( objectStatus "J9U2.57" )
				)
				( pin "vss(69)"
					( attribute "PN" "55"
						( Origin gPackager )
					)
					( objectStatus "J9U2.55" )
				)
				( pin "vss(70)"
					( attribute "PN" "53"
						( Origin gPackager )
					)
					( objectStatus "J9U2.53" )
				)
				( pin "vss(71)"
					( attribute "PN" "50"
						( Origin gPackager )
					)
					( objectStatus "J9U2.50" )
				)
				( pin "vss(72)"
					( attribute "PN" "48"
						( Origin gPackager )
					)
					( objectStatus "J9U2.48" )
				)
				( pin "vss(73)"
					( attribute "PN" "46"
						( Origin gPackager )
					)
					( objectStatus "J9U2.46" )
				)
				( pin "vss(74)"
					( attribute "PN" "44"
						( Origin gPackager )
					)
					( objectStatus "J9U2.44" )
				)
				( pin "vss(75)"
					( attribute "PN" "42"
						( Origin gPackager )
					)
					( objectStatus "J9U2.42" )
				)
				( pin "vss(76)"
					( attribute "PN" "39"
						( Origin gPackager )
					)
					( objectStatus "J9U2.39" )
				)
				( pin "vss(77)"
					( attribute "PN" "37"
						( Origin gPackager )
					)
					( objectStatus "J9U2.37" )
				)
				( pin "vss(78)"
					( attribute "PN" "35"
						( Origin gPackager )
					)
					( objectStatus "J9U2.35" )
				)
				( pin "vss(79)"
					( attribute "PN" "33"
						( Origin gPackager )
					)
					( objectStatus "J9U2.33" )
				)
				( pin "vss(80)"
					( attribute "PN" "31"
						( Origin gPackager )
					)
					( objectStatus "J9U2.31" )
				)
				( pin "vss(81)"
					( attribute "PN" "28"
						( Origin gPackager )
					)
					( objectStatus "J9U2.28" )
				)
				( pin "vss(82)"
					( attribute "PN" "26"
						( Origin gPackager )
					)
					( objectStatus "J9U2.26" )
				)
				( pin "vss(83)"
					( attribute "PN" "24"
						( Origin gPackager )
					)
					( objectStatus "J9U2.24" )
				)
				( pin "vss(84)"
					( attribute "PN" "22"
						( Origin gPackager )
					)
					( objectStatus "J9U2.22" )
				)
				( pin "vss(85)"
					( attribute "PN" "20"
						( Origin gPackager )
					)
					( objectStatus "J9U2.20" )
				)
				( pin "vss(86)"
					( attribute "PN" "17"
						( Origin gPackager )
					)
					( objectStatus "J9U2.17" )
				)
				( pin "vss(87)"
					( attribute "PN" "15"
						( Origin gPackager )
					)
					( objectStatus "J9U2.15" )
				)
				( pin "vss(88)"
					( attribute "PN" "13"
						( Origin gPackager )
					)
					( objectStatus "J9U2.13" )
				)
				( pin "vss(89)"
					( attribute "PN" "11"
						( Origin gPackager )
					)
					( objectStatus "J9U2.11" )
				)
				( pin "vss(90)"
					( attribute "PN" "9"
						( Origin gPackager )
					)
					( objectStatus "J9U2.9" )
				)
				( pin "vss(91)"
					( attribute "PN" "6"
						( Origin gPackager )
					)
					( objectStatus "J9U2.6" )
				)
				( pin "vss(92)"
					( attribute "PN" "4"
						( Origin gPackager )
					)
					( objectStatus "J9U2.4" )
				)
				( pin "vss(93)"
					( attribute "PN" "2"
						( Origin gPackager )
					)
					( objectStatus "J9U2.2" )
				)
			)
			( gate "@baseboard_fab2_lib.baseboard_fab2(sch_1):page83_i43"
				( attribute "BOM_COST" "MEM"
					( Origin gFrontEnd )
				)
				( attribute "CDS_LIB" "mstr_sconn"
					( Origin gPackager )
				)
				( attribute "CDS_LOCATION" "J1B1"
					( Origin gPackager )
				)
				( attribute "CDS_SEC" "3"
					( Origin gPackager )
				)
				( attribute "LOCATION" "J1B1"
					( Origin gFrontEnd )
				)
				( attribute "MATERIAL" "SCONN"
					( Origin gFrontEnd )
				)
				( attribute "PACK_TYPE" "PIP"
					( Origin gFrontEnd )
				)
				( attribute "PART_NUMBER" "H44441-004"
					( Origin gFrontEnd )
				)
				( attribute "PHYS_PAGE" "83"
					( Origin gFrontEnd )
				)
				( attribute "ROOM" "DDR4_CH_K"
					( Origin gFrontEnd )
				)
				( attribute "ROT" "0"
					( Origin gFrontEnd )
				)
				( attribute "SEC" "3"
					( Origin gFrontEnd )
				)
				( attribute "SEC_TYPE" "PIP"
					( Origin gFrontEnd )
				)
				( attribute "VER" "3"
					( Origin gFrontEnd )
				)
				( attribute "XY" "(1800,2400)"
					( Origin gFrontEnd )
				)
				( attribute "CHIPS_PART_NAME" "SCONN288_H44441004"
					( Origin gPackager )
				)
				( attribute "CDS_PART_NAME" "SCONN288_H44441004_PIP-SCONN,HA"
					( Origin gPackager )
				)
				( objectStatus "J1B1" )
				( pin "vss(0)"
					( attribute "PN" "283"
						( Origin gPackager )
					)
					( objectStatus "J1B1.283" )
				)
				( pin "vss(1)"
					( attribute "PN" "281"
						( Origin gPackager )
					)
					( objectStatus "J1B1.281" )
				)
				( pin "vss(2)"
					( attribute "PN" "279"
						( Origin gPackager )
					)
					( objectStatus "J1B1.279" )
				)
				( pin "vss(3)"
					( attribute "PN" "276"
						( Origin gPackager )
					)
					( objectStatus "J1B1.276" )
				)
				( pin "vss(4)"
					( attribute "PN" "274"
						( Origin gPackager )
					)
					( objectStatus "J1B1.274" )
				)
				( pin "vss(5)"
					( attribute "PN" "272"
						( Origin gPackager )
					)
					( objectStatus "J1B1.272" )
				)
				( pin "vss(6)"
					( attribute "PN" "270"
						( Origin gPackager )
					)
					( objectStatus "J1B1.270" )
				)
				( pin "vss(7)"
					( attribute "PN" "268"
						( Origin gPackager )
					)
					( objectStatus "J1B1.268" )
				)
				( pin "vss(8)"
					( attribute "PN" "265"
						( Origin gPackager )
					)
					( objectStatus "J1B1.265" )
				)
				( pin "vss(9)"
					( attribute "PN" "263"
						( Origin gPackager )
					)
					( objectStatus "J1B1.263" )
				)
				( pin "vss(10)"
					( attribute "PN" "261"
						( Origin gPackager )
					)
					( objectStatus "J1B1.261" )
				)
				( pin "vss(11)"
					( attribute "PN" "259"
						( Origin gPackager )
					)
					( objectStatus "J1B1.259" )
				)
				( pin "vss(12)"
					( attribute "PN" "257"
						( Origin gPackager )
					)
					( objectStatus "J1B1.257" )
				)
				( pin "vss(13)"
					( attribute "PN" "254"
						( Origin gPackager )
					)
					( objectStatus "J1B1.254" )
				)
				( pin "vss(14)"
					( attribute "PN" "252"
						( Origin gPackager )
					)
					( objectStatus "J1B1.252" )
				)
				( pin "vss(15)"
					( attribute "PN" "250"
						( Origin gPackager )
					)
					( objectStatus "J1B1.250" )
				)
				( pin "vss(16)"
					( attribute "PN" "248"
						( Origin gPackager )
					)
					( objectStatus "J1B1.248" )
				)
				( pin "vss(17)"
					( attribute "PN" "246"
						( Origin gPackager )
					)
					( objectStatus "J1B1.246" )
				)
				( pin "vss(18)"
					( attribute "PN" "243"
						( Origin gPackager )
					)
					( objectStatus "J1B1.243" )
				)
				( pin "vss(19)"
					( attribute "PN" "241"
						( Origin gPackager )
					)
					( objectStatus "J1B1.241" )
				)
				( pin "vss(20)"
					( attribute "PN" "239"
						( Origin gPackager )
					)
					( objectStatus "J1B1.239" )
				)
				( pin "vss(21)"
					( attribute "PN" "202"
						( Origin gPackager )
					)
					( objectStatus "J1B1.202" )
				)
				( pin "vss(22)"
					( attribute "PN" "200"
						( Origin gPackager )
					)
					( objectStatus "J1B1.200" )
				)
				( pin "vss(23)"
					( attribute "PN" "198"
						( Origin gPackager )
					)
					( objectStatus "J1B1.198" )
				)
				( pin "vss(24)"
					( attribute "PN" "195"
						( Origin gPackager )
					)
					( objectStatus "J1B1.195" )
				)
				( pin "vss(25)"
					( attribute "PN" "193"
						( Origin gPackager )
					)
					( objectStatus "J1B1.193" )
				)
				( pin "vss(26)"
					( attribute "PN" "191"
						( Origin gPackager )
					)
					( objectStatus "J1B1.191" )
				)
				( pin "vss(27)"
					( attribute "PN" "189"
						( Origin gPackager )
					)
					( objectStatus "J1B1.189" )
				)
				( pin "vss(28)"
					( attribute "PN" "187"
						( Origin gPackager )
					)
					( objectStatus "J1B1.187" )
				)
				( pin "vss(29)"
					( attribute "PN" "184"
						( Origin gPackager )
					)
					( objectStatus "J1B1.184" )
				)
				( pin "vss(30)"
					( attribute "PN" "182"
						( Origin gPackager )
					)
					( objectStatus "J1B1.182" )
				)
				( pin "vss(31)"
					( attribute "PN" "180"
						( Origin gPackager )
					)
					( objectStatus "J1B1.180" )
				)
				( pin "vss(32)"
					( attribute "PN" "178"
						( Origin gPackager )
					)
					( objectStatus "J1B1.178" )
				)
				( pin "vss(33)"
					( attribute "PN" "176"
						( Origin gPackager )
					)
					( objectStatus "J1B1.176" )
				)
				( pin "vss(34)"
					( attribute "PN" "173"
						( Origin gPackager )
					)
					( objectStatus "J1B1.173" )
				)
				( pin "vss(35)"
					( attribute "PN" "171"
						( Origin gPackager )
					)
					( objectStatus "J1B1.171" )
				)
				( pin "vss(36)"
					( attribute "PN" "169"
						( Origin gPackager )
					)
					( objectStatus "J1B1.169" )
				)
				( pin "vss(37)"
					( attribute "PN" "167"
						( Origin gPackager )
					)
					( objectStatus "J1B1.167" )
				)
				( pin "vss(38)"
					( attribute "PN" "165"
						( Origin gPackager )
					)
					( objectStatus "J1B1.165" )
				)
				( pin "vss(39)"
					( attribute "PN" "162"
						( Origin gPackager )
					)
					( objectStatus "J1B1.162" )
				)
				( pin "vss(40)"
					( attribute "PN" "160"
						( Origin gPackager )
					)
					( objectStatus "J1B1.160" )
				)
				( pin "vss(41)"
					( attribute "PN" "158"
						( Origin gPackager )
					)
					( objectStatus "J1B1.158" )
				)
				( pin "vss(42)"
					( attribute "PN" "156"
						( Origin gPackager )
					)
					( objectStatus "J1B1.156" )
				)
				( pin "vss(43)"
					( attribute "PN" "154"
						( Origin gPackager )
					)
					( objectStatus "J1B1.154" )
				)
				( pin "vss(44)"
					( attribute "PN" "151"
						( Origin gPackager )
					)
					( objectStatus "J1B1.151" )
				)
				( pin "vss(45)"
					( attribute "PN" "149"
						( Origin gPackager )
					)
					( objectStatus "J1B1.149" )
				)
				( pin "vss(46)"
					( attribute "PN" "147"
						( Origin gPackager )
					)
					( objectStatus "J1B1.147" )
				)
				( pin "vss(47)"
					( attribute "PN" "138"
						( Origin gPackager )
					)
					( objectStatus "J1B1.138" )
				)
				( pin "vss(48)"
					( attribute "PN" "136"
						( Origin gPackager )
					)
					( objectStatus "J1B1.136" )
				)
				( pin "vss(49)"
					( attribute "PN" "134"
						( Origin gPackager )
					)
					( objectStatus "J1B1.134" )
				)
				( pin "vss(50)"
					( attribute "PN" "131"
						( Origin gPackager )
					)
					( objectStatus "J1B1.131" )
				)
				( pin "vss(51)"
					( attribute "PN" "129"
						( Origin gPackager )
					)
					( objectStatus "J1B1.129" )
				)
				( pin "vss(52)"
					( attribute "PN" "127"
						( Origin gPackager )
					)
					( objectStatus "J1B1.127" )
				)
				( pin "vss(53)"
					( attribute "PN" "125"
						( Origin gPackager )
					)
					( objectStatus "J1B1.125" )
				)
				( pin "vss(54)"
					( attribute "PN" "123"
						( Origin gPackager )
					)
					( objectStatus "J1B1.123" )
				)
				( pin "vss(55)"
					( attribute "PN" "120"
						( Origin gPackager )
					)
					( objectStatus "J1B1.120" )
				)
				( pin "vss(56)"
					( attribute "PN" "118"
						( Origin gPackager )
					)
					( objectStatus "J1B1.118" )
				)
				( pin "vss(57)"
					( attribute "PN" "116"
						( Origin gPackager )
					)
					( objectStatus "J1B1.116" )
				)
				( pin "vss(58)"
					( attribute "PN" "114"
						( Origin gPackager )
					)
					( objectStatus "J1B1.114" )
				)
				( pin "vss(59)"
					( attribute "PN" "112"
						( Origin gPackager )
					)
					( objectStatus "J1B1.112" )
				)
				( pin "vss(60)"
					( attribute "PN" "109"
						( Origin gPackager )
					)
					( objectStatus "J1B1.109" )
				)
				( pin "vss(61)"
					( attribute "PN" "107"
						( Origin gPackager )
					)
					( objectStatus "J1B1.107" )
				)
				( pin "vss(62)"
					( attribute "PN" "105"
						( Origin gPackager )
					)
					( objectStatus "J1B1.105" )
				)
				( pin "vss(63)"
					( attribute "PN" "103"
						( Origin gPackager )
					)
					( objectStatus "J1B1.103" )
				)
				( pin "vss(64)"
					( attribute "PN" "101"
						( Origin gPackager )
					)
					( objectStatus "J1B1.101" )
				)
				( pin "vss(65)"
					( attribute "PN" "98"
						( Origin gPackager )
					)
					( objectStatus "J1B1.98" )
				)
				( pin "vss(66)"
					( attribute "PN" "96"
						( Origin gPackager )
					)
					( objectStatus "J1B1.96" )
				)
				( pin "vss(67)"
					( attribute "PN" "94"
						( Origin gPackager )
					)
					( objectStatus "J1B1.94" )
				)
				( pin "vss(68)"
					( attribute "PN" "57"
						( Origin gPackager )
					)
					( objectStatus "J1B1.57" )
				)
				( pin "vss(69)"
					( attribute "PN" "55"
						( Origin gPackager )
					)
					( objectStatus "J1B1.55" )
				)
				( pin "vss(70)"
					( attribute "PN" "53"
						( Origin gPackager )
					)
					( objectStatus "J1B1.53" )
				)
				( pin "vss(71)"
					( attribute "PN" "50"
						( Origin gPackager )
					)
					( objectStatus "J1B1.50" )
				)
				( pin "vss(72)"
					( attribute "PN" "48"
						( Origin gPackager )
					)
					( objectStatus "J1B1.48" )
				)
				( pin "vss(73)"
					( attribute "PN" "46"
						( Origin gPackager )
					)
					( objectStatus "J1B1.46" )
				)
				( pin "vss(74)"
					( attribute "PN" "44"
						( Origin gPackager )
					)
					( objectStatus "J1B1.44" )
				)
				( pin "vss(75)"
					( attribute "PN" "42"
						( Origin gPackager )
					)
					( objectStatus "J1B1.42" )
				)
				( pin "vss(76)"
					( attribute "PN" "39"
						( Origin gPackager )
					)
					( objectStatus "J1B1.39" )
				)
				( pin "vss(77)"
					( attribute "PN" "37"
						( Origin gPackager )
					)
					( objectStatus "J1B1.37" )
				)
				( pin "vss(78)"
					( attribute "PN" "35"
						( Origin gPackager )
					)
					( objectStatus "J1B1.35" )
				)
				( pin "vss(79)"
					( attribute "PN" "33"
						( Origin gPackager )
					)
					( objectStatus "J1B1.33" )
				)
				( pin "vss(80)"
					( attribute "PN" "31"
						( Origin gPackager )
					)
					( objectStatus "J1B1.31" )
				)
				( pin "vss(81)"
					( attribute "PN" "28"
						( Origin gPackager )
					)
					( objectStatus "J1B1.28" )
				)
				( pin "vss(82)"
					( attribute "PN" "26"
						( Origin gPackager )
					)
					( objectStatus "J1B1.26" )
				)
				( pin "vss(83)"
					( attribute "PN" "24"
						( Origin gPackager )
					)
					( objectStatus "J1B1.24" )
				)
				( pin "vss(84)"
					( attribute "PN" "22"
						( Origin gPackager )
					)
					( objectStatus "J1B1.22" )
				)
				( pin "vss(85)"
					( attribute "PN" "20"
						( Origin gPackager )
					)
					( objectStatus "J1B1.20" )
				)
				( pin "vss(86)"
					( attribute "PN" "17"
						( Origin gPackager )
					)
					( objectStatus "J1B1.17" )
				)
				( pin "vss(87)"
					( attribute "PN" "15"
						( Origin gPackager )
					)
					( objectStatus "J1B1.15" )
				)
				( pin "vss(88)"
					( attribute "PN" "13"
						( Origin gPackager )
					)
					( objectStatus "J1B1.13" )
				)
				( pin "vss(89)"
					( attribute "PN" "11"
						( Origin gPackager )
					)
					( objectStatus "J1B1.11" )
				)
				( pin "vss(90)"
					( attribute "PN" "9"
						( Origin gPackager )
					)
					( objectStatus "J1B1.9" )
				)
				( pin "vss(91)"
					( attribute "PN" "6"
						( Origin gPackager )
					)
					( objectStatus "J1B1.6" )
				)
				( pin "vss(92)"
					( attribute "PN" "4"
						( Origin gPackager )
					)
					( objectStatus "J1B1.4" )
				)
				( pin "vss(93)"
					( attribute "PN" "2"
						( Origin gPackager )
					)
					( objectStatus "J1B1.2" )
				)
			)
			( gate "@baseboard_fab2_lib.baseboard_fab2(sch_1):page83_i66"
				( attribute "BOM_COST" "MEM"
					( Origin gFrontEnd )
				)
				( attribute "CDS_LIB" "mstr_sconn"
					( Origin gPackager )
				)
				( attribute "CDS_LOCATION" "J1B1"
					( Origin gPackager )
				)
				( attribute "CDS_SEC" "2"
					( Origin gPackager )
				)
				( attribute "LOCATION" "J1B1"
					( Origin gFrontEnd )
				)
				( attribute "MATERIAL" "SCONN"
					( Origin gFrontEnd )
				)
				( attribute "PACK_TYPE" "PIP"
					( Origin gFrontEnd )
				)
				( attribute "PART_NUMBER" "H44441-004"
					( Origin gFrontEnd )
				)
				( attribute "PHYS_PAGE" "83"
					( Origin gFrontEnd )
				)
				( attribute "ROOM" "DDR4_CH_K"
					( Origin gFrontEnd )
				)
				( attribute "ROT" "0"
					( Origin gFrontEnd )
				)
				( attribute "SEC" "2"
					( Origin gFrontEnd )
				)
				( attribute "SEC_TYPE" "PIP"
					( Origin gFrontEnd )
				)
				( attribute "VER" "2"
					( Origin gFrontEnd )
				)
				( attribute "XY" "(0,4350)"
					( Origin gFrontEnd )
				)
				( attribute "CHIPS_PART_NAME" "SCONN288_H44441004"
					( Origin gPackager )
				)
				( attribute "CDS_PART_NAME" "SCONN288_H44441004_PIP-SCONN,HA"
					( Origin gPackager )
				)
				( objectStatus "J1B1" )
				( pin "dqs0n"
					( attribute "PN" "152"
						( Origin gPackager )
					)
					( objectStatus "J1B1.152" )
				)
				( pin "dqs0p"
					( attribute "PN" "153"
						( Origin gPackager )
					)
					( objectStatus "J1B1.153" )
				)
				( pin "dqs1n"
					( attribute "PN" "163"
						( Origin gPackager )
					)
					( objectStatus "J1B1.163" )
				)
				( pin "dqs1p"
					( attribute "PN" "164"
						( Origin gPackager )
					)
					( objectStatus "J1B1.164" )
				)
				( pin "dqs2n"
					( attribute "PN" "174"
						( Origin gPackager )
					)
					( objectStatus "J1B1.174" )
				)
				( pin "dqs2p"
					( attribute "PN" "175"
						( Origin gPackager )
					)
					( objectStatus "J1B1.175" )
				)
				( pin "dqs3n"
					( attribute "PN" "185"
						( Origin gPackager )
					)
					( objectStatus "J1B1.185" )
				)
				( pin "dqs3p"
					( attribute "PN" "186"
						( Origin gPackager )
					)
					( objectStatus "J1B1.186" )
				)
				( pin "dqs4n"
					( attribute "PN" "244"
						( Origin gPackager )
					)
					( objectStatus "J1B1.244" )
				)
				( pin "dqs4p"
					( attribute "PN" "245"
						( Origin gPackager )
					)
					( objectStatus "J1B1.245" )
				)
				( pin "dqs5n"
					( attribute "PN" "255"
						( Origin gPackager )
					)
					( objectStatus "J1B1.255" )
				)
				( pin "dqs5p"
					( attribute "PN" "256"
						( Origin gPackager )
					)
					( objectStatus "J1B1.256" )
				)
				( pin "dqs6n"
					( attribute "PN" "266"
						( Origin gPackager )
					)
					( objectStatus "J1B1.266" )
				)
				( pin "dqs6p"
					( attribute "PN" "267"
						( Origin gPackager )
					)
					( objectStatus "J1B1.267" )
				)
				( pin "dqs7n"
					( attribute "PN" "277"
						( Origin gPackager )
					)
					( objectStatus "J1B1.277" )
				)
				( pin "dqs7p"
					( attribute "PN" "278"
						( Origin gPackager )
					)
					( objectStatus "J1B1.278" )
				)
				( pin "dqs8n"
					( attribute "PN" "196"
						( Origin gPackager )
					)
					( objectStatus "J1B1.196" )
				)
				( pin "dqs8p"
					( attribute "PN" "197"
						( Origin gPackager )
					)
					( objectStatus "J1B1.197" )
				)
				( pin "dqs9n"
					( attribute "PN" "8"
						( Origin gPackager )
					)
					( objectStatus "J1B1.8" )
				)
				( pin "dqs9p"
					( attribute "PN" "7"
						( Origin gPackager )
					)
					( objectStatus "J1B1.7" )
				)
				( pin "dqs10n"
					( attribute "PN" "19"
						( Origin gPackager )
					)
					( objectStatus "J1B1.19" )
				)
				( pin "dqs10p"
					( attribute "PN" "18"
						( Origin gPackager )
					)
					( objectStatus "J1B1.18" )
				)
				( pin "dqs11n"
					( attribute "PN" "30"
						( Origin gPackager )
					)
					( objectStatus "J1B1.30" )
				)
				( pin "dqs11p"
					( attribute "PN" "29"
						( Origin gPackager )
					)
					( objectStatus "J1B1.29" )
				)
				( pin "dqs12n"
					( attribute "PN" "41"
						( Origin gPackager )
					)
					( objectStatus "J1B1.41" )
				)
				( pin "dqs12p"
					( attribute "PN" "40"
						( Origin gPackager )
					)
					( objectStatus "J1B1.40" )
				)
				( pin "dqs13n"
					( attribute "PN" "100"
						( Origin gPackager )
					)
					( objectStatus "J1B1.100" )
				)
				( pin "dqs13p"
					( attribute "PN" "99"
						( Origin gPackager )
					)
					( objectStatus "J1B1.99" )
				)
				( pin "dqs14n"
					( attribute "PN" "111"
						( Origin gPackager )
					)
					( objectStatus "J1B1.111" )
				)
				( pin "dqs14p"
					( attribute "PN" "110"
						( Origin gPackager )
					)
					( objectStatus "J1B1.110" )
				)
				( pin "dqs15n"
					( attribute "PN" "122"
						( Origin gPackager )
					)
					( objectStatus "J1B1.122" )
				)
				( pin "dqs15p"
					( attribute "PN" "121"
						( Origin gPackager )
					)
					( objectStatus "J1B1.121" )
				)
				( pin "dqs16n"
					( attribute "PN" "133"
						( Origin gPackager )
					)
					( objectStatus "J1B1.133" )
				)
				( pin "dqs16p"
					( attribute "PN" "132"
						( Origin gPackager )
					)
					( objectStatus "J1B1.132" )
				)
				( pin "dqs17n"
					( attribute "PN" "52"
						( Origin gPackager )
					)
					( objectStatus "J1B1.52" )
				)
				( pin "dqs17p"
					( attribute "PN" "51"
						( Origin gPackager )
					)
					( objectStatus "J1B1.51" )
				)
			)
			( gate "@baseboard_fab2_lib.baseboard_fab2(sch_1):page83_i111"
				( attribute "BOM_COST" "MEM"
					( Origin gFrontEnd )
				)
				( attribute "CDS_LIB" "mstr_sconn"
					( Origin gPackager )
				)
				( attribute "CDS_LOCATION" "J1B1"
					( Origin gPackager )
				)
				( attribute "CDS_SEC" "1"
					( Origin gPackager )
				)
				( attribute "LOCATION" "J1B1"
					( Origin gFrontEnd )
				)
				( attribute "MATERIAL" "SCONN"
					( Origin gFrontEnd )
				)
				( attribute "PACK_TYPE" "PIP"
					( Origin gFrontEnd )
				)
				( attribute "PART_NUMBER" "H44441-004"
					( Origin gFrontEnd )
				)
				( attribute "PHYS_PAGE" "83"
					( Origin gFrontEnd )
				)
				( attribute "ROOM" "DDR4_CH_K"
					( Origin gFrontEnd )
				)
				( attribute "ROT" "0"
					( Origin gFrontEnd )
				)
				( attribute "SEC" "1"
					( Origin gFrontEnd )
				)
				( attribute "SEC_TYPE" "PIP"
					( Origin gFrontEnd )
				)
				( attribute "VER" "1"
					( Origin gFrontEnd )
				)
				( attribute "XY" "(-2450,3200)"
					( Origin gFrontEnd )
				)
				( attribute "CHIPS_PART_NAME" "SCONN288_H44441004"
					( Origin gPackager )
				)
				( attribute "CDS_PART_NAME" "SCONN288_H44441004_PIP-SCONN,HA"
					( Origin gPackager )
				)
				( objectStatus "J1B1" )
				( pin "a0"
					( attribute "PN" "79"
						( Origin gPackager )
					)
					( objectStatus "J1B1.79" )
				)
				( pin "a1"
					( attribute "PN" "72"
						( Origin gPackager )
					)
					( objectStatus "J1B1.72" )
				)
				( pin "a2"
					( attribute "PN" "216"
						( Origin gPackager )
					)
					( objectStatus "J1B1.216" )
				)
				( pin "a3"
					( attribute "PN" "71"
						( Origin gPackager )
					)
					( objectStatus "J1B1.71" )
				)
				( pin "a4"
					( attribute "PN" "214"
						( Origin gPackager )
					)
					( objectStatus "J1B1.214" )
				)
				( pin "a5"
					( attribute "PN" "213"
						( Origin gPackager )
					)
					( objectStatus "J1B1.213" )
				)
				( pin "a6"
					( attribute "PN" "69"
						( Origin gPackager )
					)
					( objectStatus "J1B1.69" )
				)
				( pin "a7"
					( attribute "PN" "211"
						( Origin gPackager )
					)
					( objectStatus "J1B1.211" )
				)
				( pin "a8"
					( attribute "PN" "68"
						( Origin gPackager )
					)
					( objectStatus "J1B1.68" )
				)
				( pin "a9"
					( attribute "PN" "66"
						( Origin gPackager )
					)
					( objectStatus "J1B1.66" )
				)
				( pin "a10"
					( attribute "PN" "225"
						( Origin gPackager )
					)
					( objectStatus "J1B1.225" )
				)
				( pin "a11"
					( attribute "PN" "210"
						( Origin gPackager )
					)
					( objectStatus "J1B1.210" )
				)
				( pin "a12"
					( attribute "PN" "65"
						( Origin gPackager )
					)
					( objectStatus "J1B1.65" )
				)
				( pin "a13"
					( attribute "PN" "232"
						( Origin gPackager )
					)
					( objectStatus "J1B1.232" )
				)
				( pin "a14_we_n"
					( attribute "PN" "228"
						( Origin gPackager )
					)
					( objectStatus "J1B1.228" )
				)
				( pin "a15_cas_n"
					( attribute "PN" "86"
						( Origin gPackager )
					)
					( objectStatus "J1B1.86" )
				)
				( pin "a16_ras_n"
					( attribute "PN" "82"
						( Origin gPackager )
					)
					( objectStatus "J1B1.82" )
				)
				( pin "a17"
					( attribute "PN" "234"
						( Origin gPackager )
					)
					( objectStatus "J1B1.234" )
				)
				( pin "act_n"
					( attribute "PN" "62"
						( Origin gPackager )
					)
					( objectStatus "J1B1.62" )
				)
				( pin "alert_n"
					( attribute "PN" "208"
						( Origin gPackager )
					)
					( objectStatus "J1B1.208" )
				)
				( pin "ba(0)"
					( attribute "PN" "81"
						( Origin gPackager )
					)
					( objectStatus "J1B1.81" )
				)
				( pin "ba(1)"
					( attribute "PN" "224"
						( Origin gPackager )
					)
					( objectStatus "J1B1.224" )
				)
				( pin "bg(0)"
					( attribute "PN" "63"
						( Origin gPackager )
					)
					( objectStatus "J1B1.63" )
				)
				( pin "bg(1)"
					( attribute "PN" "207"
						( Origin gPackager )
					)
					( objectStatus "J1B1.207" )
				)
				( pin "c(2)"
					( attribute "PN" "235"
						( Origin gPackager )
					)
					( objectStatus "J1B1.235" )
				)
				( pin "cb(0)"
					( attribute "PN" "49"
						( Origin gPackager )
					)
					( objectStatus "J1B1.49" )
				)
				( pin "cb(1)"
					( attribute "PN" "194"
						( Origin gPackager )
					)
					( objectStatus "J1B1.194" )
				)
				( pin "cb(2)"
					( attribute "PN" "56"
						( Origin gPackager )
					)
					( objectStatus "J1B1.56" )
				)
				( pin "cb(3)"
					( attribute "PN" "201"
						( Origin gPackager )
					)
					( objectStatus "J1B1.201" )
				)
				( pin "cb(4)"
					( attribute "PN" "47"
						( Origin gPackager )
					)
					( objectStatus "J1B1.47" )
				)
				( pin "cb(5)"
					( attribute "PN" "192"
						( Origin gPackager )
					)
					( objectStatus "J1B1.192" )
				)
				( pin "cb(6)"
					( attribute "PN" "54"
						( Origin gPackager )
					)
					( objectStatus "J1B1.54" )
				)
				( pin "cb(7)"
					( attribute "PN" "199"
						( Origin gPackager )
					)
					( objectStatus "J1B1.199" )
				)
				( pin "ck0n"
					( attribute "PN" "75"
						( Origin gPackager )
					)
					( objectStatus "J1B1.75" )
				)
				( pin "ck0p"
					( attribute "PN" "74"
						( Origin gPackager )
					)
					( objectStatus "J1B1.74" )
				)
				( pin "ck1n"
					( attribute "PN" "219"
						( Origin gPackager )
					)
					( objectStatus "J1B1.219" )
				)
				( pin "ck1p"
					( attribute "PN" "218"
						( Origin gPackager )
					)
					( objectStatus "J1B1.218" )
				)
				( pin "cke(0)"
					( attribute "PN" "60"
						( Origin gPackager )
					)
					( objectStatus "J1B1.60" )
				)
				( pin "cke(1)"
					( attribute "PN" "203"
						( Origin gPackager )
					)
					( objectStatus "J1B1.203" )
				)
				( pin "dq(0)"
					( attribute "PN" "5"
						( Origin gPackager )
					)
					( objectStatus "J1B1.5" )
				)
				( pin "dq(1)"
					( attribute "PN" "150"
						( Origin gPackager )
					)
					( objectStatus "J1B1.150" )
				)
				( pin "dq(2)"
					( attribute "PN" "12"
						( Origin gPackager )
					)
					( objectStatus "J1B1.12" )
				)
				( pin "dq(3)"
					( attribute "PN" "157"
						( Origin gPackager )
					)
					( objectStatus "J1B1.157" )
				)
				( pin "dq(4)"
					( attribute "PN" "3"
						( Origin gPackager )
					)
					( objectStatus "J1B1.3" )
				)
				( pin "dq(5)"
					( attribute "PN" "148"
						( Origin gPackager )
					)
					( objectStatus "J1B1.148" )
				)
				( pin "dq(6)"
					( attribute "PN" "10"
						( Origin gPackager )
					)
					( objectStatus "J1B1.10" )
				)
				( pin "dq(7)"
					( attribute "PN" "155"
						( Origin gPackager )
					)
					( objectStatus "J1B1.155" )
				)
				( pin "dq(8)"
					( attribute "PN" "16"
						( Origin gPackager )
					)
					( objectStatus "J1B1.16" )
				)
				( pin "dq(9)"
					( attribute "PN" "161"
						( Origin gPackager )
					)
					( objectStatus "J1B1.161" )
				)
				( pin "dq(10)"
					( attribute "PN" "23"
						( Origin gPackager )
					)
					( objectStatus "J1B1.23" )
				)
				( pin "dq(11)"
					( attribute "PN" "168"
						( Origin gPackager )
					)
					( objectStatus "J1B1.168" )
				)
				( pin "dq(12)"
					( attribute "PN" "14"
						( Origin gPackager )
					)
					( objectStatus "J1B1.14" )
				)
				( pin "dq(13)"
					( attribute "PN" "159"
						( Origin gPackager )
					)
					( objectStatus "J1B1.159" )
				)
				( pin "dq(14)"
					( attribute "PN" "21"
						( Origin gPackager )
					)
					( objectStatus "J1B1.21" )
				)
				( pin "dq(15)"
					( attribute "PN" "166"
						( Origin gPackager )
					)
					( objectStatus "J1B1.166" )
				)
				( pin "dq(16)"
					( attribute "PN" "27"
						( Origin gPackager )
					)
					( objectStatus "J1B1.27" )
				)
				( pin "dq(17)"
					( attribute "PN" "172"
						( Origin gPackager )
					)
					( objectStatus "J1B1.172" )
				)
				( pin "dq(18)"
					( attribute "PN" "34"
						( Origin gPackager )
					)
					( objectStatus "J1B1.34" )
				)
				( pin "dq(19)"
					( attribute "PN" "179"
						( Origin gPackager )
					)
					( objectStatus "J1B1.179" )
				)
				( pin "dq(20)"
					( attribute "PN" "25"
						( Origin gPackager )
					)
					( objectStatus "J1B1.25" )
				)
				( pin "dq(21)"
					( attribute "PN" "170"
						( Origin gPackager )
					)
					( objectStatus "J1B1.170" )
				)
				( pin "dq(22)"
					( attribute "PN" "32"
						( Origin gPackager )
					)
					( objectStatus "J1B1.32" )
				)
				( pin "dq(23)"
					( attribute "PN" "177"
						( Origin gPackager )
					)
					( objectStatus "J1B1.177" )
				)
				( pin "dq(24)"
					( attribute "PN" "38"
						( Origin gPackager )
					)
					( objectStatus "J1B1.38" )
				)
				( pin "dq(25)"
					( attribute "PN" "183"
						( Origin gPackager )
					)
					( objectStatus "J1B1.183" )
				)
				( pin "dq(26)"
					( attribute "PN" "45"
						( Origin gPackager )
					)
					( objectStatus "J1B1.45" )
				)
				( pin "dq(27)"
					( attribute "PN" "190"
						( Origin gPackager )
					)
					( objectStatus "J1B1.190" )
				)
				( pin "dq(28)"
					( attribute "PN" "36"
						( Origin gPackager )
					)
					( objectStatus "J1B1.36" )
				)
				( pin "dq(29)"
					( attribute "PN" "181"
						( Origin gPackager )
					)
					( objectStatus "J1B1.181" )
				)
				( pin "dq(30)"
					( attribute "PN" "43"
						( Origin gPackager )
					)
					( objectStatus "J1B1.43" )
				)
				( pin "dq(31)"
					( attribute "PN" "188"
						( Origin gPackager )
					)
					( objectStatus "J1B1.188" )
				)
				( pin "dq(32)"
					( attribute "PN" "97"
						( Origin gPackager )
					)
					( objectStatus "J1B1.97" )
				)
				( pin "dq(33)"
					( attribute "PN" "242"
						( Origin gPackager )
					)
					( objectStatus "J1B1.242" )
				)
				( pin "dq(34)"
					( attribute "PN" "104"
						( Origin gPackager )
					)
					( objectStatus "J1B1.104" )
				)
				( pin "dq(35)"
					( attribute "PN" "249"
						( Origin gPackager )
					)
					( objectStatus "J1B1.249" )
				)
				( pin "dq(36)"
					( attribute "PN" "95"
						( Origin gPackager )
					)
					( objectStatus "J1B1.95" )
				)
				( pin "dq(37)"
					( attribute "PN" "240"
						( Origin gPackager )
					)
					( objectStatus "J1B1.240" )
				)
				( pin "dq(38)"
					( attribute "PN" "102"
						( Origin gPackager )
					)
					( objectStatus "J1B1.102" )
				)
				( pin "dq(39)"
					( attribute "PN" "247"
						( Origin gPackager )
					)
					( objectStatus "J1B1.247" )
				)
				( pin "dq(40)"
					( attribute "PN" "108"
						( Origin gPackager )
					)
					( objectStatus "J1B1.108" )
				)
				( pin "dq(41)"
					( attribute "PN" "253"
						( Origin gPackager )
					)
					( objectStatus "J1B1.253" )
				)
				( pin "dq(42)"
					( attribute "PN" "115"
						( Origin gPackager )
					)
					( objectStatus "J1B1.115" )
				)
				( pin "dq(43)"
					( attribute "PN" "260"
						( Origin gPackager )
					)
					( objectStatus "J1B1.260" )
				)
				( pin "dq(44)"
					( attribute "PN" "106"
						( Origin gPackager )
					)
					( objectStatus "J1B1.106" )
				)
				( pin "dq(45)"
					( attribute "PN" "251"
						( Origin gPackager )
					)
					( objectStatus "J1B1.251" )
				)
				( pin "dq(46)"
					( attribute "PN" "113"
						( Origin gPackager )
					)
					( objectStatus "J1B1.113" )
				)
				( pin "dq(47)"
					( attribute "PN" "258"
						( Origin gPackager )
					)
					( objectStatus "J1B1.258" )
				)
				( pin "dq(48)"
					( attribute "PN" "119"
						( Origin gPackager )
					)
					( objectStatus "J1B1.119" )
				)
				( pin "dq(49)"
					( attribute "PN" "264"
						( Origin gPackager )
					)
					( objectStatus "J1B1.264" )
				)
				( pin "dq(50)"
					( attribute "PN" "126"
						( Origin gPackager )
					)
					( objectStatus "J1B1.126" )
				)
				( pin "dq(51)"
					( attribute "PN" "271"
						( Origin gPackager )
					)
					( objectStatus "J1B1.271" )
				)
				( pin "dq(52)"
					( attribute "PN" "117"
						( Origin gPackager )
					)
					( objectStatus "J1B1.117" )
				)
				( pin "dq(53)"
					( attribute "PN" "262"
						( Origin gPackager )
					)
					( objectStatus "J1B1.262" )
				)
				( pin "dq(54)"
					( attribute "PN" "124"
						( Origin gPackager )
					)
					( objectStatus "J1B1.124" )
				)
				( pin "dq(55)"
					( attribute "PN" "269"
						( Origin gPackager )
					)
					( objectStatus "J1B1.269" )
				)
				( pin "dq(56)"
					( attribute "PN" "130"
						( Origin gPackager )
					)
					( objectStatus "J1B1.130" )
				)
				( pin "dq(57)"
					( attribute "PN" "275"
						( Origin gPackager )
					)
					( objectStatus "J1B1.275" )
				)
				( pin "dq(58)"
					( attribute "PN" "137"
						( Origin gPackager )
					)
					( objectStatus "J1B1.137" )
				)
				( pin "dq(59)"
					( attribute "PN" "282"
						( Origin gPackager )
					)
					( objectStatus "J1B1.282" )
				)
				( pin "dq(60)"
					( attribute "PN" "128"
						( Origin gPackager )
					)
					( objectStatus "J1B1.128" )
				)
				( pin "dq(61)"
					( attribute "PN" "273"
						( Origin gPackager )
					)
					( objectStatus "J1B1.273" )
				)
				( pin "dq(62)"
					( attribute "PN" "135"
						( Origin gPackager )
					)
					( objectStatus "J1B1.135" )
				)
				( pin "dq(63)"
					( attribute "PN" "280"
						( Origin gPackager )
					)
					( objectStatus "J1B1.280" )
				)
				( pin "event_n"
					( attribute "PN" "78"
						( Origin gPackager )
					)
					( objectStatus "J1B1.78" )
				)
				( pin "odt(0)"
					( attribute "PN" "87"
						( Origin gPackager )
					)
					( objectStatus "J1B1.87" )
				)
				( pin "odt(1)"
					( attribute "PN" "91"
						( Origin gPackager )
					)
					( objectStatus "J1B1.91" )
				)
				( pin "par"
					( attribute "PN" "222"
						( Origin gPackager )
					)
					( objectStatus "J1B1.222" )
				)
				( pin "reset_n"
					( attribute "PN" "58"
						( Origin gPackager )
					)
					( objectStatus "J1B1.58" )
				)
				( pin "rfu(0)"
					( attribute "PN" "205"
						( Origin gPackager )
					)
					( objectStatus "J1B1.205" )
				)
				( pin "rfu(1)"
					( attribute "PN" "227"
						( Origin gPackager )
					)
					( objectStatus "J1B1.227" )
				)
				( pin "rfu(2)"
					( attribute "PN" "144"
						( Origin gPackager )
					)
					( objectStatus "J1B1.144" )
				)
				( pin "s0_n"
					( attribute "PN" "84"
						( Origin gPackager )
					)
					( objectStatus "J1B1.84" )
				)
				( pin "s1_n"
					( attribute "PN" "89"
						( Origin gPackager )
					)
					( objectStatus "J1B1.89" )
				)
				( pin "s2_n_c(0)"
					( attribute "PN" "93"
						( Origin gPackager )
					)
					( objectStatus "J1B1.93" )
				)
				( pin "s3_n_c(1)"
					( attribute "PN" "237"
						( Origin gPackager )
					)
					( objectStatus "J1B1.237" )
				)
				( pin "sa(0)"
					( attribute "PN" "139"
						( Origin gPackager )
					)
					( objectStatus "J1B1.139" )
				)
				( pin "sa(1)"
					( attribute "PN" "140"
						( Origin gPackager )
					)
					( objectStatus "J1B1.140" )
				)
				( pin "sa(2)"
					( attribute "PN" "238"
						( Origin gPackager )
					)
					( objectStatus "J1B1.238" )
				)
				( pin "save_n_nc"
					( attribute "PN" "230"
						( Origin gPackager )
					)
					( objectStatus "J1B1.230" )
				)
				( pin "scl"
					( attribute "PN" "141"
						( Origin gPackager )
					)
					( objectStatus "J1B1.141" )
				)
				( pin "sda"
					( attribute "PN" "285"
						( Origin gPackager )
					)
					( objectStatus "J1B1.285" )
				)
				( pin "vddspd"
					( attribute "PN" "284"
						( Origin gPackager )
					)
					( objectStatus "J1B1.284" )
				)
				( pin "vrefca"
					( attribute "PN" "146"
						( Origin gPackager )
					)
					( objectStatus "J1B1.146" )
				)
			)
			( gate "@baseboard_fab2_lib.baseboard_fab2(sch_1):page83_i167"
				( attribute "BOM_COST" "MEM"
					( Origin gFrontEnd )
				)
				( attribute "CDS_LIB" "mstr_sconn"
					( Origin gPackager )
				)
				( attribute "CDS_LOCATION" "J1B1"
					( Origin gPackager )
				)
				( attribute "CDS_SEC" "4"
					( Origin gPackager )
				)
				( attribute "LOCATION" "J1B1"
					( Origin gFrontEnd )
				)
				( attribute "MATERIAL" "SCONN"
					( Origin gFrontEnd )
				)
				( attribute "PACK_TYPE" "PIP"
					( Origin gFrontEnd )
				)
				( attribute "PART_NUMBER" "H44441-004"
					( Origin gFrontEnd )
				)
				( attribute "PHYS_PAGE" "83"
					( Origin gFrontEnd )
				)
				( attribute "ROOM" "DDR4_CH_K"
					( Origin gFrontEnd )
				)
				( attribute "ROT" "0"
					( Origin gFrontEnd )
				)
				( attribute "SEC" "4"
					( Origin gFrontEnd )
				)
				( attribute "SEC_TYPE" "PIP"
					( Origin gFrontEnd )
				)
				( attribute "VER" "4"
					( Origin gFrontEnd )
				)
				( attribute "XY" "(-150,2100)"
					( Origin gFrontEnd )
				)
				( attribute "CHIPS_PART_NAME" "SCONN288_H44441004"
					( Origin gPackager )
				)
				( attribute "CDS_PART_NAME" "SCONN288_H44441004_PIP-SCONN,HA"
					( Origin gPackager )
				)
				( objectStatus "J1B1" )
				( pin "\12v\(0)"
					( attribute "PN" "145"
						( Origin gPackager )
					)
					( objectStatus "J1B1.145" )
				)
				( pin "\12v\(1)"
					( attribute "PN" "1"
						( Origin gPackager )
					)
					( objectStatus "J1B1.1" )
				)
				( pin "vdd(0)"
					( attribute "PN" "236"
						( Origin gPackager )
					)
					( objectStatus "J1B1.236" )
				)
				( pin "vdd(1)"
					( attribute "PN" "233"
						( Origin gPackager )
					)
					( objectStatus "J1B1.233" )
				)
				( pin "vdd(2)"
					( attribute "PN" "231"
						( Origin gPackager )
					)
					( objectStatus "J1B1.231" )
				)
				( pin "vdd(3)"
					( attribute "PN" "229"
						( Origin gPackager )
					)
					( objectStatus "J1B1.229" )
				)
				( pin "vdd(4)"
					( attribute "PN" "226"
						( Origin gPackager )
					)
					( objectStatus "J1B1.226" )
				)
				( pin "vdd(5)"
					( attribute "PN" "223"
						( Origin gPackager )
					)
					( objectStatus "J1B1.223" )
				)
				( pin "vdd(6)"
					( attribute "PN" "220"
						( Origin gPackager )
					)
					( objectStatus "J1B1.220" )
				)
				( pin "vdd(7)"
					( attribute "PN" "217"
						( Origin gPackager )
					)
					( objectStatus "J1B1.217" )
				)
				( pin "vdd(8)"
					( attribute "PN" "215"
						( Origin gPackager )
					)
					( objectStatus "J1B1.215" )
				)
				( pin "vdd(9)"
					( attribute "PN" "212"
						( Origin gPackager )
					)
					( objectStatus "J1B1.212" )
				)
				( pin "vdd(10)"
					( attribute "PN" "209"
						( Origin gPackager )
					)
					( objectStatus "J1B1.209" )
				)
				( pin "vdd(11)"
					( attribute "PN" "206"
						( Origin gPackager )
					)
					( objectStatus "J1B1.206" )
				)
				( pin "vdd(12)"
					( attribute "PN" "204"
						( Origin gPackager )
					)
					( objectStatus "J1B1.204" )
				)
				( pin "vdd(13)"
					( attribute "PN" "92"
						( Origin gPackager )
					)
					( objectStatus "J1B1.92" )
				)
				( pin "vdd(14)"
					( attribute "PN" "90"
						( Origin gPackager )
					)
					( objectStatus "J1B1.90" )
				)
				( pin "vdd(15)"
					( attribute "PN" "88"
						( Origin gPackager )
					)
					( objectStatus "J1B1.88" )
				)
				( pin "vdd(16)"
					( attribute "PN" "85"
						( Origin gPackager )
					)
					( objectStatus "J1B1.85" )
				)
				( pin "vdd(17)"
					( attribute "PN" "83"
						( Origin gPackager )
					)
					( objectStatus "J1B1.83" )
				)
				( pin "vdd(18)"
					( attribute "PN" "80"
						( Origin gPackager )
					)
					( objectStatus "J1B1.80" )
				)
				( pin "vdd(19)"
					( attribute "PN" "76"
						( Origin gPackager )
					)
					( objectStatus "J1B1.76" )
				)
				( pin "vdd(20)"
					( attribute "PN" "73"
						( Origin gPackager )
					)
					( objectStatus "J1B1.73" )
				)
				( pin "vdd(21)"
					( attribute "PN" "70"
						( Origin gPackager )
					)
					( objectStatus "J1B1.70" )
				)
				( pin "vdd(22)"
					( attribute "PN" "67"
						( Origin gPackager )
					)
					( objectStatus "J1B1.67" )
				)
				( pin "vdd(23)"
					( attribute "PN" "64"
						( Origin gPackager )
					)
					( objectStatus "J1B1.64" )
				)
				( pin "vdd(24)"
					( attribute "PN" "61"
						( Origin gPackager )
					)
					( objectStatus "J1B1.61" )
				)
				( pin "vdd(25)"
					( attribute "PN" "59"
						( Origin gPackager )
					)
					( objectStatus "J1B1.59" )
				)
				( pin "vpp(0)"
					( attribute "PN" "287"
						( Origin gPackager )
					)
					( objectStatus "J1B1.287" )
				)
				( pin "vpp(1)"
					( attribute "PN" "286"
						( Origin gPackager )
					)
					( objectStatus "J1B1.286" )
				)
				( pin "vpp(2)"
					( attribute "PN" "288"
						( Origin gPackager )
					)
					( objectStatus "J1B1.288" )
				)
				( pin "vpp(3)"
					( attribute "PN" "143"
						( Origin gPackager )
					)
					( objectStatus "J1B1.143" )
				)
				( pin "vpp(4)"
					( attribute "PN" "142"
						( Origin gPackager )
					)
					( objectStatus "J1B1.142" )
				)
				( pin "vtt(0)"
					( attribute "PN" "221"
						( Origin gPackager )
					)
					( objectStatus "J1B1.221" )
				)
				( pin "vtt(1)"
					( attribute "PN" "77"
						( Origin gPackager )
					)
					( objectStatus "J1B1.77" )
				)
			)
			( gate "@baseboard_fab2_lib.baseboard_fab2(sch_1):page83_i176"
				( attribute "BOM_COST" "MEM"
					( Origin gFrontEnd )
				)
				( attribute "CDS_LIB" "dev_discrete"
					( Origin gPackager )
				)
				( attribute "CDS_LOCATION" "C1B9"
					( Origin gPackager )
				)
				( attribute "CDS_SEC" "1"
					( Origin gPackager )
				)
				( attribute "LOCATION" "C1B9"
					( Origin gFrontEnd )
				)
				( attribute "MATERIAL" "X7R"
					( Origin gFrontEnd )
				)
				( attribute "PACK_TYPE" "0402V"
					( Origin gFrontEnd )
				)
				( attribute "PART_NUMBER" "A36096-045"
					( Origin gFrontEnd )
				)
				( attribute "PHYS_PAGE" "83"
					( Origin gFrontEnd )
				)
				( attribute "ROOM" "DDR4_CH_K"
					( Origin gFrontEnd )
				)
				( attribute "ROT" "2"
					( Origin gFrontEnd )
				)
				( attribute "SEC" "1"
					( Origin gPackager )
				)
				( attribute "TOLERANCE" "10%"
					( Origin gFrontEnd )
				)
				( attribute "VALUE" "0.01UF"
					( Origin gFrontEnd )
				)
				( attribute "VER" "1"
					( Origin gFrontEnd )
				)
				( attribute "VOLTAGE" "25V"
					( Units "uVoltage" "V" 1.000000)
					( Origin gFrontEnd )
				)
				( attribute "XY" "(-4600,1500)"
					( Origin gFrontEnd )
				)
				( attribute "CHIPS_PART_NAME" "CAP_A"
					( Origin gPackager )
				)
				( attribute "CDS_PART_NAME" "CAP_A_0402V-0.01UF,25V,10%,X7RA"
					( Origin gPackager )
				)
				( objectStatus "C1B9" )
				( pin "a"
					( attribute "PN" "1"
						( Origin gPackager )
					)
					( objectStatus "C1B9.1" )
				)
				( pin "b"
					( attribute "PN" "2"
						( Origin gPackager )
					)
					( objectStatus "C1B9.2" )
				)
			)
			( gate "@baseboard_fab2_lib.baseboard_fab2(sch_1):page84_i4"
				( attribute "BOM_COST" "MEM"
					( Origin gFrontEnd )
				)
				( attribute "CDS_LIB" "dev_discrete"
					( Origin gPackager )
				)
				( attribute "CDS_LOCATION" "C9M1"
					( Origin gPackager )
				)
				( attribute "CDS_SEC" "1"
					( Origin gPackager )
				)
				( attribute "LOCATION" "C9M1"
					( Origin gFrontEnd )
				)
				( attribute "MATERIAL" "X7R"
					( Origin gFrontEnd )
				)
				( attribute "PACK_TYPE" "0402V"
					( Origin gFrontEnd )
				)
				( attribute "PART_NUMBER" "A36096-045"
					( Origin gFrontEnd )
				)
				( attribute "PHYS_PAGE" "84"
					( Origin gFrontEnd )
				)
				( attribute "ROOM" "DDR4_CH_C"
					( Origin gFrontEnd )
				)
				( attribute "ROT" "2"
					( Origin gFrontEnd )
				)
				( attribute "SEC" "1"
					( Origin gPackager )
				)
				( attribute "TOLERANCE" "10%"
					( Origin gFrontEnd )
				)
				( attribute "VALUE" "0.01UF"
					( Origin gFrontEnd )
				)
				( attribute "VER" "1"
					( Origin gFrontEnd )
				)
				( attribute "VOLTAGE" "25V"
					( Units "uVoltage" "V" 1.000000)
					( Origin gFrontEnd )
				)
				( attribute "XY" "(-3000,1125)"
					( Origin gFrontEnd )
				)
				( attribute "CHIPS_PART_NAME" "CAP_A"
					( Origin gPackager )
				)
				( attribute "CDS_PART_NAME" "CAP_A_0402V-0.01UF,25V,10%,X7RA"
					( Origin gPackager )
				)
				( objectStatus "C9M1" )
				( pin "a"
					( attribute "PN" "1"
						( Origin gPackager )
					)
					( objectStatus "C9M1.1" )
				)
				( pin "b"
					( attribute "PN" "2"
						( Origin gPackager )
					)
					( objectStatus "C9M1.2" )
				)
			)
			( gate "@baseboard_fab2_lib.baseboard_fab2(sch_1):page84_i14"
				( attribute "BOM_COST" "MEM"
					( Origin gFrontEnd )
				)
				( attribute "CDS_LIB" "mstr_sconn"
					( Origin gPackager )
				)
				( attribute "CDS_LOCATION" "J9M1"
					( Origin gPackager )
				)
				( attribute "CDS_SEC" "1"
					( Origin gPackager )
				)
				( attribute "LOCATION" "J9M1"
					( Origin gFrontEnd )
				)
				( attribute "MATERIAL" "SCONN"
					( Origin gFrontEnd )
				)
				( attribute "PACK_TYPE" "PIP"
					( Origin gFrontEnd )
				)
				( attribute "PART_NUMBER" "H44441-003"
					( Origin gFrontEnd )
				)
				( attribute "PHYS_PAGE" "84"
					( Origin gFrontEnd )
				)
				( attribute "ROOM" "DDR4_CH_K"
					( Origin gFrontEnd )
				)
				( attribute "ROT" "0"
					( Origin gFrontEnd )
				)
				( attribute "SEC" "1"
					( Origin gFrontEnd )
				)
				( attribute "SEC_TYPE" "PIP"
					( Origin gFrontEnd )
				)
				( attribute "VER" "1"
					( Origin gFrontEnd )
				)
				( attribute "XY" "(-850,2825)"
					( Origin gFrontEnd )
				)
				( attribute "CHIPS_PART_NAME" "SCONN288_H44441003"
					( Origin gPackager )
				)
				( attribute "CDS_PART_NAME" "SCONN288_H44441003_PIP-SCONN,HA"
					( Origin gPackager )
				)
				( objectStatus "J9M1" )
				( pin "a0"
					( attribute "PN" "79"
						( Origin gPackager )
					)
					( objectStatus "J9M1.79" )
				)
				( pin "a1"
					( attribute "PN" "72"
						( Origin gPackager )
					)
					( objectStatus "J9M1.72" )
				)
				( pin "a2"
					( attribute "PN" "216"
						( Origin gPackager )
					)
					( objectStatus "J9M1.216" )
				)
				( pin "a3"
					( attribute "PN" "71"
						( Origin gPackager )
					)
					( objectStatus "J9M1.71" )
				)
				( pin "a4"
					( attribute "PN" "214"
						( Origin gPackager )
					)
					( objectStatus "J9M1.214" )
				)
				( pin "a5"
					( attribute "PN" "213"
						( Origin gPackager )
					)
					( objectStatus "J9M1.213" )
				)
				( pin "a6"
					( attribute "PN" "69"
						( Origin gPackager )
					)
					( objectStatus "J9M1.69" )
				)
				( pin "a7"
					( attribute "PN" "211"
						( Origin gPackager )
					)
					( objectStatus "J9M1.211" )
				)
				( pin "a8"
					( attribute "PN" "68"
						( Origin gPackager )
					)
					( objectStatus "J9M1.68" )
				)
				( pin "a9"
					( attribute "PN" "66"
						( Origin gPackager )
					)
					( objectStatus "J9M1.66" )
				)
				( pin "a10"
					( attribute "PN" "225"
						( Origin gPackager )
					)
					( objectStatus "J9M1.225" )
				)
				( pin "a11"
					( attribute "PN" "210"
						( Origin gPackager )
					)
					( objectStatus "J9M1.210" )
				)
				( pin "a12"
					( attribute "PN" "65"
						( Origin gPackager )
					)
					( objectStatus "J9M1.65" )
				)
				( pin "a13"
					( attribute "PN" "232"
						( Origin gPackager )
					)
					( objectStatus "J9M1.232" )
				)
				( pin "a14_we_n"
					( attribute "PN" "228"
						( Origin gPackager )
					)
					( objectStatus "J9M1.228" )
				)
				( pin "a15_cas_n"
					( attribute "PN" "86"
						( Origin gPackager )
					)
					( objectStatus "J9M1.86" )
				)
				( pin "a16_ras_n"
					( attribute "PN" "82"
						( Origin gPackager )
					)
					( objectStatus "J9M1.82" )
				)
				( pin "a17"
					( attribute "PN" "234"
						( Origin gPackager )
					)
					( objectStatus "J9M1.234" )
				)
				( pin "act_n"
					( attribute "PN" "62"
						( Origin gPackager )
					)
					( objectStatus "J9M1.62" )
				)
				( pin "alert_n"
					( attribute "PN" "208"
						( Origin gPackager )
					)
					( objectStatus "J9M1.208" )
				)
				( pin "ba(0)"
					( attribute "PN" "81"
						( Origin gPackager )
					)
					( objectStatus "J9M1.81" )
				)
				( pin "ba(1)"
					( attribute "PN" "224"
						( Origin gPackager )
					)
					( objectStatus "J9M1.224" )
				)
				( pin "bg(0)"
					( attribute "PN" "63"
						( Origin gPackager )
					)
					( objectStatus "J9M1.63" )
				)
				( pin "bg(1)"
					( attribute "PN" "207"
						( Origin gPackager )
					)
					( objectStatus "J9M1.207" )
				)
				( pin "c(2)"
					( attribute "PN" "235"
						( Origin gPackager )
					)
					( objectStatus "J9M1.235" )
				)
				( pin "cb(0)"
					( attribute "PN" "49"
						( Origin gPackager )
					)
					( objectStatus "J9M1.49" )
				)
				( pin "cb(1)"
					( attribute "PN" "194"
						( Origin gPackager )
					)
					( objectStatus "J9M1.194" )
				)
				( pin "cb(2)"
					( attribute "PN" "56"
						( Origin gPackager )
					)
					( objectStatus "J9M1.56" )
				)
				( pin "cb(3)"
					( attribute "PN" "201"
						( Origin gPackager )
					)
					( objectStatus "J9M1.201" )
				)
				( pin "cb(4)"
					( attribute "PN" "47"
						( Origin gPackager )
					)
					( objectStatus "J9M1.47" )
				)
				( pin "cb(5)"
					( attribute "PN" "192"
						( Origin gPackager )
					)
					( objectStatus "J9M1.192" )
				)
				( pin "cb(6)"
					( attribute "PN" "54"
						( Origin gPackager )
					)
					( objectStatus "J9M1.54" )
				)
				( pin "cb(7)"
					( attribute "PN" "199"
						( Origin gPackager )
					)
					( objectStatus "J9M1.199" )
				)
				( pin "ck0n"
					( attribute "PN" "75"
						( Origin gPackager )
					)
					( objectStatus "J9M1.75" )
				)
				( pin "ck0p"
					( attribute "PN" "74"
						( Origin gPackager )
					)
					( objectStatus "J9M1.74" )
				)
				( pin "ck1n"
					( attribute "PN" "219"
						( Origin gPackager )
					)
					( objectStatus "J9M1.219" )
				)
				( pin "ck1p"
					( attribute "PN" "218"
						( Origin gPackager )
					)
					( objectStatus "J9M1.218" )
				)
				( pin "cke(0)"
					( attribute "PN" "60"
						( Origin gPackager )
					)
					( objectStatus "J9M1.60" )
				)
				( pin "cke(1)"
					( attribute "PN" "203"
						( Origin gPackager )
					)
					( objectStatus "J9M1.203" )
				)
				( pin "dq(0)"
					( attribute "PN" "5"
						( Origin gPackager )
					)
					( objectStatus "J9M1.5" )
				)
				( pin "dq(1)"
					( attribute "PN" "150"
						( Origin gPackager )
					)
					( objectStatus "J9M1.150" )
				)
				( pin "dq(2)"
					( attribute "PN" "12"
						( Origin gPackager )
					)
					( objectStatus "J9M1.12" )
				)
				( pin "dq(3)"
					( attribute "PN" "157"
						( Origin gPackager )
					)
					( objectStatus "J9M1.157" )
				)
				( pin "dq(4)"
					( attribute "PN" "3"
						( Origin gPackager )
					)
					( objectStatus "J9M1.3" )
				)
				( pin "dq(5)"
					( attribute "PN" "148"
						( Origin gPackager )
					)
					( objectStatus "J9M1.148" )
				)
				( pin "dq(6)"
					( attribute "PN" "10"
						( Origin gPackager )
					)
					( objectStatus "J9M1.10" )
				)
				( pin "dq(7)"
					( attribute "PN" "155"
						( Origin gPackager )
					)
					( objectStatus "J9M1.155" )
				)
				( pin "dq(8)"
					( attribute "PN" "16"
						( Origin gPackager )
					)
					( objectStatus "J9M1.16" )
				)
				( pin "dq(9)"
					( attribute "PN" "161"
						( Origin gPackager )
					)
					( objectStatus "J9M1.161" )
				)
				( pin "dq(10)"
					( attribute "PN" "23"
						( Origin gPackager )
					)
					( objectStatus "J9M1.23" )
				)
				( pin "dq(11)"
					( attribute "PN" "168"
						( Origin gPackager )
					)
					( objectStatus "J9M1.168" )
				)
				( pin "dq(12)"
					( attribute "PN" "14"
						( Origin gPackager )
					)
					( objectStatus "J9M1.14" )
				)
				( pin "dq(13)"
					( attribute "PN" "159"
						( Origin gPackager )
					)
					( objectStatus "J9M1.159" )
				)
				( pin "dq(14)"
					( attribute "PN" "21"
						( Origin gPackager )
					)
					( objectStatus "J9M1.21" )
				)
				( pin "dq(15)"
					( attribute "PN" "166"
						( Origin gPackager )
					)
					( objectStatus "J9M1.166" )
				)
				( pin "dq(16)"
					( attribute "PN" "27"
						( Origin gPackager )
					)
					( objectStatus "J9M1.27" )
				)
				( pin "dq(17)"
					( attribute "PN" "172"
						( Origin gPackager )
					)
					( objectStatus "J9M1.172" )
				)
				( pin "dq(18)"
					( attribute "PN" "34"
						( Origin gPackager )
					)
					( objectStatus "J9M1.34" )
				)
				( pin "dq(19)"
					( attribute "PN" "179"
						( Origin gPackager )
					)
					( objectStatus "J9M1.179" )
				)
				( pin "dq(20)"
					( attribute "PN" "25"
						( Origin gPackager )
					)
					( objectStatus "J9M1.25" )
				)
				( pin "dq(21)"
					( attribute "PN" "170"
						( Origin gPackager )
					)
					( objectStatus "J9M1.170" )
				)
				( pin "dq(22)"
					( attribute "PN" "32"
						( Origin gPackager )
					)
					( objectStatus "J9M1.32" )
				)
				( pin "dq(23)"
					( attribute "PN" "177"
						( Origin gPackager )
					)
					( objectStatus "J9M1.177" )
				)
				( pin "dq(24)"
					( attribute "PN" "38"
						( Origin gPackager )
					)
					( objectStatus "J9M1.38" )
				)
				( pin "dq(25)"
					( attribute "PN" "183"
						( Origin gPackager )
					)
					( objectStatus "J9M1.183" )
				)
				( pin "dq(26)"
					( attribute "PN" "45"
						( Origin gPackager )
					)
					( objectStatus "J9M1.45" )
				)
				( pin "dq(27)"
					( attribute "PN" "190"
						( Origin gPackager )
					)
					( objectStatus "J9M1.190" )
				)
				( pin "dq(28)"
					( attribute "PN" "36"
						( Origin gPackager )
					)
					( objectStatus "J9M1.36" )
				)
				( pin "dq(29)"
					( attribute "PN" "181"
						( Origin gPackager )
					)
					( objectStatus "J9M1.181" )
				)
				( pin "dq(30)"
					( attribute "PN" "43"
						( Origin gPackager )
					)
					( objectStatus "J9M1.43" )
				)
				( pin "dq(31)"
					( attribute "PN" "188"
						( Origin gPackager )
					)
					( objectStatus "J9M1.188" )
				)
				( pin "dq(32)"
					( attribute "PN" "97"
						( Origin gPackager )
					)
					( objectStatus "J9M1.97" )
				)
				( pin "dq(33)"
					( attribute "PN" "242"
						( Origin gPackager )
					)
					( objectStatus "J9M1.242" )
				)
				( pin "dq(34)"
					( attribute "PN" "104"
						( Origin gPackager )
					)
					( objectStatus "J9M1.104" )
				)
				( pin "dq(35)"
					( attribute "PN" "249"
						( Origin gPackager )
					)
					( objectStatus "J9M1.249" )
				)
				( pin "dq(36)"
					( attribute "PN" "95"
						( Origin gPackager )
					)
					( objectStatus "J9M1.95" )
				)
				( pin "dq(37)"
					( attribute "PN" "240"
						( Origin gPackager )
					)
					( objectStatus "J9M1.240" )
				)
				( pin "dq(38)"
					( attribute "PN" "102"
						( Origin gPackager )
					)
					( objectStatus "J9M1.102" )
				)
				( pin "dq(39)"
					( attribute "PN" "247"
						( Origin gPackager )
					)
					( objectStatus "J9M1.247" )
				)
				( pin "dq(40)"
					( attribute "PN" "108"
						( Origin gPackager )
					)
					( objectStatus "J9M1.108" )
				)
				( pin "dq(41)"
					( attribute "PN" "253"
						( Origin gPackager )
					)
					( objectStatus "J9M1.253" )
				)
				( pin "dq(42)"
					( attribute "PN" "115"
						( Origin gPackager )
					)
					( objectStatus "J9M1.115" )
				)
				( pin "dq(43)"
					( attribute "PN" "260"
						( Origin gPackager )
					)
					( objectStatus "J9M1.260" )
				)
				( pin "dq(44)"
					( attribute "PN" "106"
						( Origin gPackager )
					)
					( objectStatus "J9M1.106" )
				)
				( pin "dq(45)"
					( attribute "PN" "251"
						( Origin gPackager )
					)
					( objectStatus "J9M1.251" )
				)
				( pin "dq(46)"
					( attribute "PN" "113"
						( Origin gPackager )
					)
					( objectStatus "J9M1.113" )
				)
				( pin "dq(47)"
					( attribute "PN" "258"
						( Origin gPackager )
					)
					( objectStatus "J9M1.258" )
				)
				( pin "dq(48)"
					( attribute "PN" "119"
						( Origin gPackager )
					)
					( objectStatus "J9M1.119" )
				)
				( pin "dq(49)"
					( attribute "PN" "264"
						( Origin gPackager )
					)
					( objectStatus "J9M1.264" )
				)
				( pin "dq(50)"
					( attribute "PN" "126"
						( Origin gPackager )
					)
					( objectStatus "J9M1.126" )
				)
				( pin "dq(51)"
					( attribute "PN" "271"
						( Origin gPackager )
					)
					( objectStatus "J9M1.271" )
				)
				( pin "dq(52)"
					( attribute "PN" "117"
						( Origin gPackager )
					)
					( objectStatus "J9M1.117" )
				)
				( pin "dq(53)"
					( attribute "PN" "262"
						( Origin gPackager )
					)
					( objectStatus "J9M1.262" )
				)
				( pin "dq(54)"
					( attribute "PN" "124"
						( Origin gPackager )
					)
					( objectStatus "J9M1.124" )
				)
				( pin "dq(55)"
					( attribute "PN" "269"
						( Origin gPackager )
					)
					( objectStatus "J9M1.269" )
				)
				( pin "dq(56)"
					( attribute "PN" "130"
						( Origin gPackager )
					)
					( objectStatus "J9M1.130" )
				)
				( pin "dq(57)"
					( attribute "PN" "275"
						( Origin gPackager )
					)
					( objectStatus "J9M1.275" )
				)
				( pin "dq(58)"
					( attribute "PN" "137"
						( Origin gPackager )
					)
					( objectStatus "J9M1.137" )
				)
				( pin "dq(59)"
					( attribute "PN" "282"
						( Origin gPackager )
					)
					( objectStatus "J9M1.282" )
				)
				( pin "dq(60)"
					( attribute "PN" "128"
						( Origin gPackager )
					)
					( objectStatus "J9M1.128" )
				)
				( pin "dq(61)"
					( attribute "PN" "273"
						( Origin gPackager )
					)
					( objectStatus "J9M1.273" )
				)
				( pin "dq(62)"
					( attribute "PN" "135"
						( Origin gPackager )
					)
					( objectStatus "J9M1.135" )
				)
				( pin "dq(63)"
					( attribute "PN" "280"
						( Origin gPackager )
					)
					( objectStatus "J9M1.280" )
				)
				( pin "event_n"
					( attribute "PN" "78"
						( Origin gPackager )
					)
					( objectStatus "J9M1.78" )
				)
				( pin "odt(0)"
					( attribute "PN" "87"
						( Origin gPackager )
					)
					( objectStatus "J9M1.87" )
				)
				( pin "odt(1)"
					( attribute "PN" "91"
						( Origin gPackager )
					)
					( objectStatus "J9M1.91" )
				)
				( pin "par"
					( attribute "PN" "222"
						( Origin gPackager )
					)
					( objectStatus "J9M1.222" )
				)
				( pin "reset_n"
					( attribute "PN" "58"
						( Origin gPackager )
					)
					( objectStatus "J9M1.58" )
				)
				( pin "rfu(0)"
					( attribute "PN" "205"
						( Origin gPackager )
					)
					( objectStatus "J9M1.205" )
				)
				( pin "rfu(1)"
					( attribute "PN" "227"
						( Origin gPackager )
					)
					( objectStatus "J9M1.227" )
				)
				( pin "rfu(2)"
					( attribute "PN" "144"
						( Origin gPackager )
					)
					( objectStatus "J9M1.144" )
				)
				( pin "s0_n"
					( attribute "PN" "84"
						( Origin gPackager )
					)
					( objectStatus "J9M1.84" )
				)
				( pin "s1_n"
					( attribute "PN" "89"
						( Origin gPackager )
					)
					( objectStatus "J9M1.89" )
				)
				( pin "s2_n_c(0)"
					( attribute "PN" "93"
						( Origin gPackager )
					)
					( objectStatus "J9M1.93" )
				)
				( pin "s3_n_c(1)"
					( attribute "PN" "237"
						( Origin gPackager )
					)
					( objectStatus "J9M1.237" )
				)
				( pin "sa(0)"
					( attribute "PN" "139"
						( Origin gPackager )
					)
					( objectStatus "J9M1.139" )
				)
				( pin "sa(1)"
					( attribute "PN" "140"
						( Origin gPackager )
					)
					( objectStatus "J9M1.140" )
				)
				( pin "sa(2)"
					( attribute "PN" "238"
						( Origin gPackager )
					)
					( objectStatus "J9M1.238" )
				)
				( pin "save_n_nc"
					( attribute "PN" "230"
						( Origin gPackager )
					)
					( objectStatus "J9M1.230" )
				)
				( pin "scl"
					( attribute "PN" "141"
						( Origin gPackager )
					)
					( objectStatus "J9M1.141" )
				)
				( pin "sda"
					( attribute "PN" "285"
						( Origin gPackager )
					)
					( objectStatus "J9M1.285" )
				)
				( pin "vddspd"
					( attribute "PN" "284"
						( Origin gPackager )
					)
					( objectStatus "J9M1.284" )
				)
				( pin "vrefca"
					( attribute "PN" "146"
						( Origin gPackager )
					)
					( objectStatus "J9M1.146" )
				)
			)
			( gate "@baseboard_fab2_lib.baseboard_fab2(sch_1):page84_i57"
				( attribute "BOM_COST" "MEM"
					( Origin gFrontEnd )
				)
				( attribute "CDS_LIB" "mstr_sconn"
					( Origin gPackager )
				)
				( attribute "CDS_LOCATION" "J9M1"
					( Origin gPackager )
				)
				( attribute "CDS_SEC" "4"
					( Origin gPackager )
				)
				( attribute "LOCATION" "J9M1"
					( Origin gFrontEnd )
				)
				( attribute "MATERIAL" "SCONN"
					( Origin gFrontEnd )
				)
				( attribute "PACK_TYPE" "PIP"
					( Origin gFrontEnd )
				)
				( attribute "PART_NUMBER" "H44441-003"
					( Origin gFrontEnd )
				)
				( attribute "PHYS_PAGE" "84"
					( Origin gFrontEnd )
				)
				( attribute "ROOM" "DDR4_CH_K"
					( Origin gFrontEnd )
				)
				( attribute "ROT" "0"
					( Origin gFrontEnd )
				)
				( attribute "SEC" "4"
					( Origin gFrontEnd )
				)
				( attribute "SEC_TYPE" "PIP"
					( Origin gFrontEnd )
				)
				( attribute "VER" "4"
					( Origin gFrontEnd )
				)
				( attribute "XY" "(1450,1725)"
					( Origin gFrontEnd )
				)
				( attribute "CHIPS_PART_NAME" "SCONN288_H44441003"
					( Origin gPackager )
				)
				( attribute "CDS_PART_NAME" "SCONN288_H44441003_PIP-SCONN,HA"
					( Origin gPackager )
				)
				( objectStatus "J9M1" )
				( pin "\12v\(0)"
					( attribute "PN" "145"
						( Origin gPackager )
					)
					( objectStatus "J9M1.145" )
				)
				( pin "\12v\(1)"
					( attribute "PN" "1"
						( Origin gPackager )
					)
					( objectStatus "J9M1.1" )
				)
				( pin "vdd(0)"
					( attribute "PN" "236"
						( Origin gPackager )
					)
					( objectStatus "J9M1.236" )
				)
				( pin "vdd(1)"
					( attribute "PN" "233"
						( Origin gPackager )
					)
					( objectStatus "J9M1.233" )
				)
				( pin "vdd(2)"
					( attribute "PN" "231"
						( Origin gPackager )
					)
					( objectStatus "J9M1.231" )
				)
				( pin "vdd(3)"
					( attribute "PN" "229"
						( Origin gPackager )
					)
					( objectStatus "J9M1.229" )
				)
				( pin "vdd(4)"
					( attribute "PN" "226"
						( Origin gPackager )
					)
					( objectStatus "J9M1.226" )
				)
				( pin "vdd(5)"
					( attribute "PN" "223"
						( Origin gPackager )
					)
					( objectStatus "J9M1.223" )
				)
				( pin "vdd(6)"
					( attribute "PN" "220"
						( Origin gPackager )
					)
					( objectStatus "J9M1.220" )
				)
				( pin "vdd(7)"
					( attribute "PN" "217"
						( Origin gPackager )
					)
					( objectStatus "J9M1.217" )
				)
				( pin "vdd(8)"
					( attribute "PN" "215"
						( Origin gPackager )
					)
					( objectStatus "J9M1.215" )
				)
				( pin "vdd(9)"
					( attribute "PN" "212"
						( Origin gPackager )
					)
					( objectStatus "J9M1.212" )
				)
				( pin "vdd(10)"
					( attribute "PN" "209"
						( Origin gPackager )
					)
					( objectStatus "J9M1.209" )
				)
				( pin "vdd(11)"
					( attribute "PN" "206"
						( Origin gPackager )
					)
					( objectStatus "J9M1.206" )
				)
				( pin "vdd(12)"
					( attribute "PN" "204"
						( Origin gPackager )
					)
					( objectStatus "J9M1.204" )
				)
				( pin "vdd(13)"
					( attribute "PN" "92"
						( Origin gPackager )
					)
					( objectStatus "J9M1.92" )
				)
				( pin "vdd(14)"
					( attribute "PN" "90"
						( Origin gPackager )
					)
					( objectStatus "J9M1.90" )
				)
				( pin "vdd(15)"
					( attribute "PN" "88"
						( Origin gPackager )
					)
					( objectStatus "J9M1.88" )
				)
				( pin "vdd(16)"
					( attribute "PN" "85"
						( Origin gPackager )
					)
					( objectStatus "J9M1.85" )
				)
				( pin "vdd(17)"
					( attribute "PN" "83"
						( Origin gPackager )
					)
					( objectStatus "J9M1.83" )
				)
				( pin "vdd(18)"
					( attribute "PN" "80"
						( Origin gPackager )
					)
					( objectStatus "J9M1.80" )
				)
				( pin "vdd(19)"
					( attribute "PN" "76"
						( Origin gPackager )
					)
					( objectStatus "J9M1.76" )
				)
				( pin "vdd(20)"
					( attribute "PN" "73"
						( Origin gPackager )
					)
					( objectStatus "J9M1.73" )
				)
				( pin "vdd(21)"
					( attribute "PN" "70"
						( Origin gPackager )
					)
					( objectStatus "J9M1.70" )
				)
				( pin "vdd(22)"
					( attribute "PN" "67"
						( Origin gPackager )
					)
					( objectStatus "J9M1.67" )
				)
				( pin "vdd(23)"
					( attribute "PN" "64"
						( Origin gPackager )
					)
					( objectStatus "J9M1.64" )
				)
				( pin "vdd(24)"
					( attribute "PN" "61"
						( Origin gPackager )
					)
					( objectStatus "J9M1.61" )
				)
				( pin "vdd(25)"
					( attribute "PN" "59"
						( Origin gPackager )
					)
					( objectStatus "J9M1.59" )
				)
				( pin "vpp(0)"
					( attribute "PN" "287"
						( Origin gPackager )
					)
					( objectStatus "J9M1.287" )
				)
				( pin "vpp(1)"
					( attribute "PN" "286"
						( Origin gPackager )
					)
					( objectStatus "J9M1.286" )
				)
				( pin "vpp(2)"
					( attribute "PN" "288"
						( Origin gPackager )
					)
					( objectStatus "J9M1.288" )
				)
				( pin "vpp(3)"
					( attribute "PN" "143"
						( Origin gPackager )
					)
					( objectStatus "J9M1.143" )
				)
				( pin "vpp(4)"
					( attribute "PN" "142"
						( Origin gPackager )
					)
					( objectStatus "J9M1.142" )
				)
				( pin "vtt(0)"
					( attribute "PN" "221"
						( Origin gPackager )
					)
					( objectStatus "J9M1.221" )
				)
				( pin "vtt(1)"
					( attribute "PN" "77"
						( Origin gPackager )
					)
					( objectStatus "J9M1.77" )
				)
			)
			( gate "@baseboard_fab2_lib.baseboard_fab2(sch_1):page84_i102"
				( attribute "BOM_COST" "MEM"
					( Origin gFrontEnd )
				)
				( attribute "CDS_LIB" "mstr_sconn"
					( Origin gPackager )
				)
				( attribute "CDS_LOCATION" "J9M1"
					( Origin gPackager )
				)
				( attribute "CDS_SEC" "2"
					( Origin gPackager )
				)
				( attribute "LOCATION" "J9M1"
					( Origin gFrontEnd )
				)
				( attribute "MATERIAL" "SCONN"
					( Origin gFrontEnd )
				)
				( attribute "PACK_TYPE" "PIP"
					( Origin gFrontEnd )
				)
				( attribute "PART_NUMBER" "H44441-003"
					( Origin gFrontEnd )
				)
				( attribute "PHYS_PAGE" "84"
					( Origin gFrontEnd )
				)
				( attribute "ROOM" "DDR4_CH_K"
					( Origin gFrontEnd )
				)
				( attribute "ROT" "0"
					( Origin gFrontEnd )
				)
				( attribute "SEC" "2"
					( Origin gFrontEnd )
				)
				( attribute "SEC_TYPE" "PIP"
					( Origin gFrontEnd )
				)
				( attribute "VER" "2"
					( Origin gFrontEnd )
				)
				( attribute "XY" "(1600,3975)"
					( Origin gFrontEnd )
				)
				( attribute "CHIPS_PART_NAME" "SCONN288_H44441003"
					( Origin gPackager )
				)
				( attribute "CDS_PART_NAME" "SCONN288_H44441003_PIP-SCONN,HA"
					( Origin gPackager )
				)
				( objectStatus "J9M1" )
				( pin "dqs0n"
					( attribute "PN" "152"
						( Origin gPackager )
					)
					( objectStatus "J9M1.152" )
				)
				( pin "dqs0p"
					( attribute "PN" "153"
						( Origin gPackager )
					)
					( objectStatus "J9M1.153" )
				)
				( pin "dqs1n"
					( attribute "PN" "163"
						( Origin gPackager )
					)
					( objectStatus "J9M1.163" )
				)
				( pin "dqs1p"
					( attribute "PN" "164"
						( Origin gPackager )
					)
					( objectStatus "J9M1.164" )
				)
				( pin "dqs2n"
					( attribute "PN" "174"
						( Origin gPackager )
					)
					( objectStatus "J9M1.174" )
				)
				( pin "dqs2p"
					( attribute "PN" "175"
						( Origin gPackager )
					)
					( objectStatus "J9M1.175" )
				)
				( pin "dqs3n"
					( attribute "PN" "185"
						( Origin gPackager )
					)
					( objectStatus "J9M1.185" )
				)
				( pin "dqs3p"
					( attribute "PN" "186"
						( Origin gPackager )
					)
					( objectStatus "J9M1.186" )
				)
				( pin "dqs4n"
					( attribute "PN" "244"
						( Origin gPackager )
					)
					( objectStatus "J9M1.244" )
				)
				( pin "dqs4p"
					( attribute "PN" "245"
						( Origin gPackager )
					)
					( objectStatus "J9M1.245" )
				)
				( pin "dqs5n"
					( attribute "PN" "255"
						( Origin gPackager )
					)
					( objectStatus "J9M1.255" )
				)
				( pin "dqs5p"
					( attribute "PN" "256"
						( Origin gPackager )
					)
					( objectStatus "J9M1.256" )
				)
				( pin "dqs6n"
					( attribute "PN" "266"
						( Origin gPackager )
					)
					( objectStatus "J9M1.266" )
				)
				( pin "dqs6p"
					( attribute "PN" "267"
						( Origin gPackager )
					)
					( objectStatus "J9M1.267" )
				)
				( pin "dqs7n"
					( attribute "PN" "277"
						( Origin gPackager )
					)
					( objectStatus "J9M1.277" )
				)
				( pin "dqs7p"
					( attribute "PN" "278"
						( Origin gPackager )
					)
					( objectStatus "J9M1.278" )
				)
				( pin "dqs8n"
					( attribute "PN" "196"
						( Origin gPackager )
					)
					( objectStatus "J9M1.196" )
				)
				( pin "dqs8p"
					( attribute "PN" "197"
						( Origin gPackager )
					)
					( objectStatus "J9M1.197" )
				)
				( pin "dqs9n"
					( attribute "PN" "8"
						( Origin gPackager )
					)
					( objectStatus "J9M1.8" )
				)
				( pin "dqs9p"
					( attribute "PN" "7"
						( Origin gPackager )
					)
					( objectStatus "J9M1.7" )
				)
				( pin "dqs10n"
					( attribute "PN" "19"
						( Origin gPackager )
					)
					( objectStatus "J9M1.19" )
				)
				( pin "dqs10p"
					( attribute "PN" "18"
						( Origin gPackager )
					)
					( objectStatus "J9M1.18" )
				)
				( pin "dqs11n"
					( attribute "PN" "30"
						( Origin gPackager )
					)
					( objectStatus "J9M1.30" )
				)
				( pin "dqs11p"
					( attribute "PN" "29"
						( Origin gPackager )
					)
					( objectStatus "J9M1.29" )
				)
				( pin "dqs12n"
					( attribute "PN" "41"
						( Origin gPackager )
					)
					( objectStatus "J9M1.41" )
				)
				( pin "dqs12p"
					( attribute "PN" "40"
						( Origin gPackager )
					)
					( objectStatus "J9M1.40" )
				)
				( pin "dqs13n"
					( attribute "PN" "100"
						( Origin gPackager )
					)
					( objectStatus "J9M1.100" )
				)
				( pin "dqs13p"
					( attribute "PN" "99"
						( Origin gPackager )
					)
					( objectStatus "J9M1.99" )
				)
				( pin "dqs14n"
					( attribute "PN" "111"
						( Origin gPackager )
					)
					( objectStatus "J9M1.111" )
				)
				( pin "dqs14p"
					( attribute "PN" "110"
						( Origin gPackager )
					)
					( objectStatus "J9M1.110" )
				)
				( pin "dqs15n"
					( attribute "PN" "122"
						( Origin gPackager )
					)
					( objectStatus "J9M1.122" )
				)
				( pin "dqs15p"
					( attribute "PN" "121"
						( Origin gPackager )
					)
					( objectStatus "J9M1.121" )
				)
				( pin "dqs16n"
					( attribute "PN" "133"
						( Origin gPackager )
					)
					( objectStatus "J9M1.133" )
				)
				( pin "dqs16p"
					( attribute "PN" "132"
						( Origin gPackager )
					)
					( objectStatus "J9M1.132" )
				)
				( pin "dqs17n"
					( attribute "PN" "52"
						( Origin gPackager )
					)
					( objectStatus "J9M1.52" )
				)
				( pin "dqs17p"
					( attribute "PN" "51"
						( Origin gPackager )
					)
					( objectStatus "J9M1.51" )
				)
			)
			( gate "@baseboard_fab2_lib.baseboard_fab2(sch_1):page84_i138"
				( attribute "BOM_COST" "MEM"
					( Origin gFrontEnd )
				)
				( attribute "CDS_LIB" "mstr_sconn"
					( Origin gPackager )
				)
				( attribute "CDS_LOCATION" "J9M1"
					( Origin gPackager )
				)
				( attribute "CDS_SEC" "3"
					( Origin gPackager )
				)
				( attribute "LOCATION" "J9M1"
					( Origin gFrontEnd )
				)
				( attribute "MATERIAL" "SCONN"
					( Origin gFrontEnd )
				)
				( attribute "PACK_TYPE" "PIP"
					( Origin gFrontEnd )
				)
				( attribute "PART_NUMBER" "H44441-003"
					( Origin gFrontEnd )
				)
				( attribute "PHYS_PAGE" "84"
					( Origin gFrontEnd )
				)
				( attribute "ROOM" "DDR4_CH_K"
					( Origin gFrontEnd )
				)
				( attribute "ROT" "0"
					( Origin gFrontEnd )
				)
				( attribute "SEC" "3"
					( Origin gFrontEnd )
				)
				( attribute "SEC_TYPE" "PIP"
					( Origin gFrontEnd )
				)
				( attribute "VER" "3"
					( Origin gFrontEnd )
				)
				( attribute "XY" "(3400,2025)"
					( Origin gFrontEnd )
				)
				( attribute "CHIPS_PART_NAME" "SCONN288_H44441003"
					( Origin gPackager )
				)
				( attribute "CDS_PART_NAME" "SCONN288_H44441003_PIP-SCONN,HA"
					( Origin gPackager )
				)
				( objectStatus "J9M1" )
				( pin "vss(0)"
					( attribute "PN" "283"
						( Origin gPackager )
					)
					( objectStatus "J9M1.283" )
				)
				( pin "vss(1)"
					( attribute "PN" "281"
						( Origin gPackager )
					)
					( objectStatus "J9M1.281" )
				)
				( pin "vss(2)"
					( attribute "PN" "279"
						( Origin gPackager )
					)
					( objectStatus "J9M1.279" )
				)
				( pin "vss(3)"
					( attribute "PN" "276"
						( Origin gPackager )
					)
					( objectStatus "J9M1.276" )
				)
				( pin "vss(4)"
					( attribute "PN" "274"
						( Origin gPackager )
					)
					( objectStatus "J9M1.274" )
				)
				( pin "vss(5)"
					( attribute "PN" "272"
						( Origin gPackager )
					)
					( objectStatus "J9M1.272" )
				)
				( pin "vss(6)"
					( attribute "PN" "270"
						( Origin gPackager )
					)
					( objectStatus "J9M1.270" )
				)
				( pin "vss(7)"
					( attribute "PN" "268"
						( Origin gPackager )
					)
					( objectStatus "J9M1.268" )
				)
				( pin "vss(8)"
					( attribute "PN" "265"
						( Origin gPackager )
					)
					( objectStatus "J9M1.265" )
				)
				( pin "vss(9)"
					( attribute "PN" "263"
						( Origin gPackager )
					)
					( objectStatus "J9M1.263" )
				)
				( pin "vss(10)"
					( attribute "PN" "261"
						( Origin gPackager )
					)
					( objectStatus "J9M1.261" )
				)
				( pin "vss(11)"
					( attribute "PN" "259"
						( Origin gPackager )
					)
					( objectStatus "J9M1.259" )
				)
				( pin "vss(12)"
					( attribute "PN" "257"
						( Origin gPackager )
					)
					( objectStatus "J9M1.257" )
				)
				( pin "vss(13)"
					( attribute "PN" "254"
						( Origin gPackager )
					)
					( objectStatus "J9M1.254" )
				)
				( pin "vss(14)"
					( attribute "PN" "252"
						( Origin gPackager )
					)
					( objectStatus "J9M1.252" )
				)
				( pin "vss(15)"
					( attribute "PN" "250"
						( Origin gPackager )
					)
					( objectStatus "J9M1.250" )
				)
				( pin "vss(16)"
					( attribute "PN" "248"
						( Origin gPackager )
					)
					( objectStatus "J9M1.248" )
				)
				( pin "vss(17)"
					( attribute "PN" "246"
						( Origin gPackager )
					)
					( objectStatus "J9M1.246" )
				)
				( pin "vss(18)"
					( attribute "PN" "243"
						( Origin gPackager )
					)
					( objectStatus "J9M1.243" )
				)
				( pin "vss(19)"
					( attribute "PN" "241"
						( Origin gPackager )
					)
					( objectStatus "J9M1.241" )
				)
				( pin "vss(20)"
					( attribute "PN" "239"
						( Origin gPackager )
					)
					( objectStatus "J9M1.239" )
				)
				( pin "vss(21)"
					( attribute "PN" "202"
						( Origin gPackager )
					)
					( objectStatus "J9M1.202" )
				)
				( pin "vss(22)"
					( attribute "PN" "200"
						( Origin gPackager )
					)
					( objectStatus "J9M1.200" )
				)
				( pin "vss(23)"
					( attribute "PN" "198"
						( Origin gPackager )
					)
					( objectStatus "J9M1.198" )
				)
				( pin "vss(24)"
					( attribute "PN" "195"
						( Origin gPackager )
					)
					( objectStatus "J9M1.195" )
				)
				( pin "vss(25)"
					( attribute "PN" "193"
						( Origin gPackager )
					)
					( objectStatus "J9M1.193" )
				)
				( pin "vss(26)"
					( attribute "PN" "191"
						( Origin gPackager )
					)
					( objectStatus "J9M1.191" )
				)
				( pin "vss(27)"
					( attribute "PN" "189"
						( Origin gPackager )
					)
					( objectStatus "J9M1.189" )
				)
				( pin "vss(28)"
					( attribute "PN" "187"
						( Origin gPackager )
					)
					( objectStatus "J9M1.187" )
				)
				( pin "vss(29)"
					( attribute "PN" "184"
						( Origin gPackager )
					)
					( objectStatus "J9M1.184" )
				)
				( pin "vss(30)"
					( attribute "PN" "182"
						( Origin gPackager )
					)
					( objectStatus "J9M1.182" )
				)
				( pin "vss(31)"
					( attribute "PN" "180"
						( Origin gPackager )
					)
					( objectStatus "J9M1.180" )
				)
				( pin "vss(32)"
					( attribute "PN" "178"
						( Origin gPackager )
					)
					( objectStatus "J9M1.178" )
				)
				( pin "vss(33)"
					( attribute "PN" "176"
						( Origin gPackager )
					)
					( objectStatus "J9M1.176" )
				)
				( pin "vss(34)"
					( attribute "PN" "173"
						( Origin gPackager )
					)
					( objectStatus "J9M1.173" )
				)
				( pin "vss(35)"
					( attribute "PN" "171"
						( Origin gPackager )
					)
					( objectStatus "J9M1.171" )
				)
				( pin "vss(36)"
					( attribute "PN" "169"
						( Origin gPackager )
					)
					( objectStatus "J9M1.169" )
				)
				( pin "vss(37)"
					( attribute "PN" "167"
						( Origin gPackager )
					)
					( objectStatus "J9M1.167" )
				)
				( pin "vss(38)"
					( attribute "PN" "165"
						( Origin gPackager )
					)
					( objectStatus "J9M1.165" )
				)
				( pin "vss(39)"
					( attribute "PN" "162"
						( Origin gPackager )
					)
					( objectStatus "J9M1.162" )
				)
				( pin "vss(40)"
					( attribute "PN" "160"
						( Origin gPackager )
					)
					( objectStatus "J9M1.160" )
				)
				( pin "vss(41)"
					( attribute "PN" "158"
						( Origin gPackager )
					)
					( objectStatus "J9M1.158" )
				)
				( pin "vss(42)"
					( attribute "PN" "156"
						( Origin gPackager )
					)
					( objectStatus "J9M1.156" )
				)
				( pin "vss(43)"
					( attribute "PN" "154"
						( Origin gPackager )
					)
					( objectStatus "J9M1.154" )
				)
				( pin "vss(44)"
					( attribute "PN" "151"
						( Origin gPackager )
					)
					( objectStatus "J9M1.151" )
				)
				( pin "vss(45)"
					( attribute "PN" "149"
						( Origin gPackager )
					)
					( objectStatus "J9M1.149" )
				)
				( pin "vss(46)"
					( attribute "PN" "147"
						( Origin gPackager )
					)
					( objectStatus "J9M1.147" )
				)
				( pin "vss(47)"
					( attribute "PN" "138"
						( Origin gPackager )
					)
					( objectStatus "J9M1.138" )
				)
				( pin "vss(48)"
					( attribute "PN" "136"
						( Origin gPackager )
					)
					( objectStatus "J9M1.136" )
				)
				( pin "vss(49)"
					( attribute "PN" "134"
						( Origin gPackager )
					)
					( objectStatus "J9M1.134" )
				)
				( pin "vss(50)"
					( attribute "PN" "131"
						( Origin gPackager )
					)
					( objectStatus "J9M1.131" )
				)
				( pin "vss(51)"
					( attribute "PN" "129"
						( Origin gPackager )
					)
					( objectStatus "J9M1.129" )
				)
				( pin "vss(52)"
					( attribute "PN" "127"
						( Origin gPackager )
					)
					( objectStatus "J9M1.127" )
				)
				( pin "vss(53)"
					( attribute "PN" "125"
						( Origin gPackager )
					)
					( objectStatus "J9M1.125" )
				)
				( pin "vss(54)"
					( attribute "PN" "123"
						( Origin gPackager )
					)
					( objectStatus "J9M1.123" )
				)
				( pin "vss(55)"
					( attribute "PN" "120"
						( Origin gPackager )
					)
					( objectStatus "J9M1.120" )
				)
				( pin "vss(56)"
					( attribute "PN" "118"
						( Origin gPackager )
					)
					( objectStatus "J9M1.118" )
				)
				( pin "vss(57)"
					( attribute "PN" "116"
						( Origin gPackager )
					)
					( objectStatus "J9M1.116" )
				)
				( pin "vss(58)"
					( attribute "PN" "114"
						( Origin gPackager )
					)
					( objectStatus "J9M1.114" )
				)
				( pin "vss(59)"
					( attribute "PN" "112"
						( Origin gPackager )
					)
					( objectStatus "J9M1.112" )
				)
				( pin "vss(60)"
					( attribute "PN" "109"
						( Origin gPackager )
					)
					( objectStatus "J9M1.109" )
				)
				( pin "vss(61)"
					( attribute "PN" "107"
						( Origin gPackager )
					)
					( objectStatus "J9M1.107" )
				)
				( pin "vss(62)"
					( attribute "PN" "105"
						( Origin gPackager )
					)
					( objectStatus "J9M1.105" )
				)
				( pin "vss(63)"
					( attribute "PN" "103"
						( Origin gPackager )
					)
					( objectStatus "J9M1.103" )
				)
				( pin "vss(64)"
					( attribute "PN" "101"
						( Origin gPackager )
					)
					( objectStatus "J9M1.101" )
				)
				( pin "vss(65)"
					( attribute "PN" "98"
						( Origin gPackager )
					)
					( objectStatus "J9M1.98" )
				)
				( pin "vss(66)"
					( attribute "PN" "96"
						( Origin gPackager )
					)
					( objectStatus "J9M1.96" )
				)
				( pin "vss(67)"
					( attribute "PN" "94"
						( Origin gPackager )
					)
					( objectStatus "J9M1.94" )
				)
				( pin "vss(68)"
					( attribute "PN" "57"
						( Origin gPackager )
					)
					( objectStatus "J9M1.57" )
				)
				( pin "vss(69)"
					( attribute "PN" "55"
						( Origin gPackager )
					)
					( objectStatus "J9M1.55" )
				)
				( pin "vss(70)"
					( attribute "PN" "53"
						( Origin gPackager )
					)
					( objectStatus "J9M1.53" )
				)
				( pin "vss(71)"
					( attribute "PN" "50"
						( Origin gPackager )
					)
					( objectStatus "J9M1.50" )
				)
				( pin "vss(72)"
					( attribute "PN" "48"
						( Origin gPackager )
					)
					( objectStatus "J9M1.48" )
				)
				( pin "vss(73)"
					( attribute "PN" "46"
						( Origin gPackager )
					)
					( objectStatus "J9M1.46" )
				)
				( pin "vss(74)"
					( attribute "PN" "44"
						( Origin gPackager )
					)
					( objectStatus "J9M1.44" )
				)
				( pin "vss(75)"
					( attribute "PN" "42"
						( Origin gPackager )
					)
					( objectStatus "J9M1.42" )
				)
				( pin "vss(76)"
					( attribute "PN" "39"
						( Origin gPackager )
					)
					( objectStatus "J9M1.39" )
				)
				( pin "vss(77)"
					( attribute "PN" "37"
						( Origin gPackager )
					)
					( objectStatus "J9M1.37" )
				)
				( pin "vss(78)"
					( attribute "PN" "35"
						( Origin gPackager )
					)
					( objectStatus "J9M1.35" )
				)
				( pin "vss(79)"
					( attribute "PN" "33"
						( Origin gPackager )
					)
					( objectStatus "J9M1.33" )
				)
				( pin "vss(80)"
					( attribute "PN" "31"
						( Origin gPackager )
					)
					( objectStatus "J9M1.31" )
				)
				( pin "vss(81)"
					( attribute "PN" "28"
						( Origin gPackager )
					)
					( objectStatus "J9M1.28" )
				)
				( pin "vss(82)"
					( attribute "PN" "26"
						( Origin gPackager )
					)
					( objectStatus "J9M1.26" )
				)
				( pin "vss(83)"
					( attribute "PN" "24"
						( Origin gPackager )
					)
					( objectStatus "J9M1.24" )
				)
				( pin "vss(84)"
					( attribute "PN" "22"
						( Origin gPackager )
					)
					( objectStatus "J9M1.22" )
				)
				( pin "vss(85)"
					( attribute "PN" "20"
						( Origin gPackager )
					)
					( objectStatus "J9M1.20" )
				)
				( pin "vss(86)"
					( attribute "PN" "17"
						( Origin gPackager )
					)
					( objectStatus "J9M1.17" )
				)
				( pin "vss(87)"
					( attribute "PN" "15"
						( Origin gPackager )
					)
					( objectStatus "J9M1.15" )
				)
				( pin "vss(88)"
					( attribute "PN" "13"
						( Origin gPackager )
					)
					( objectStatus "J9M1.13" )
				)
				( pin "vss(89)"
					( attribute "PN" "11"
						( Origin gPackager )
					)
					( objectStatus "J9M1.11" )
				)
				( pin "vss(90)"
					( attribute "PN" "9"
						( Origin gPackager )
					)
					( objectStatus "J9M1.9" )
				)
				( pin "vss(91)"
					( attribute "PN" "6"
						( Origin gPackager )
					)
					( objectStatus "J9M1.6" )
				)
				( pin "vss(92)"
					( attribute "PN" "4"
						( Origin gPackager )
					)
					( objectStatus "J9M1.4" )
				)
				( pin "vss(93)"
					( attribute "PN" "2"
						( Origin gPackager )
					)
					( objectStatus "J9M1.2" )
				)
			)
			( gate "@baseboard_fab2_lib.baseboard_fab2(sch_1):page85_i43"
				( attribute "BOM_COST" "MEM"
					( Origin gFrontEnd )
				)
				( attribute "CDS_LIB" "mstr_sconn"
					( Origin gPackager )
				)
				( attribute "CDS_LOCATION" "J1A2"
					( Origin gPackager )
				)
				( attribute "CDS_SEC" "3"
					( Origin gPackager )
				)
				( attribute "LOCATION" "J1A2"
					( Origin gFrontEnd )
				)
				( attribute "MATERIAL" "SCONN"
					( Origin gFrontEnd )
				)
				( attribute "PACK_TYPE" "PIP"
					( Origin gFrontEnd )
				)
				( attribute "PART_NUMBER" "H44441-004"
					( Origin gFrontEnd )
				)
				( attribute "PHYS_PAGE" "85"
					( Origin gFrontEnd )
				)
				( attribute "ROOM" "DDR4_CH_L"
					( Origin gFrontEnd )
				)
				( attribute "ROT" "0"
					( Origin gFrontEnd )
				)
				( attribute "SEC" "3"
					( Origin gFrontEnd )
				)
				( attribute "SEC_TYPE" "PIP"
					( Origin gFrontEnd )
				)
				( attribute "VER" "3"
					( Origin gFrontEnd )
				)
				( attribute "XY" "(1800,2400)"
					( Origin gFrontEnd )
				)
				( attribute "CHIPS_PART_NAME" "SCONN288_H44441004"
					( Origin gPackager )
				)
				( attribute "CDS_PART_NAME" "SCONN288_H44441004_PIP-SCONN,HA"
					( Origin gPackager )
				)
				( objectStatus "J1A2" )
				( pin "vss(0)"
					( attribute "PN" "283"
						( Origin gPackager )
					)
					( objectStatus "J1A2.283" )
				)
				( pin "vss(1)"
					( attribute "PN" "281"
						( Origin gPackager )
					)
					( objectStatus "J1A2.281" )
				)
				( pin "vss(2)"
					( attribute "PN" "279"
						( Origin gPackager )
					)
					( objectStatus "J1A2.279" )
				)
				( pin "vss(3)"
					( attribute "PN" "276"
						( Origin gPackager )
					)
					( objectStatus "J1A2.276" )
				)
				( pin "vss(4)"
					( attribute "PN" "274"
						( Origin gPackager )
					)
					( objectStatus "J1A2.274" )
				)
				( pin "vss(5)"
					( attribute "PN" "272"
						( Origin gPackager )
					)
					( objectStatus "J1A2.272" )
				)
				( pin "vss(6)"
					( attribute "PN" "270"
						( Origin gPackager )
					)
					( objectStatus "J1A2.270" )
				)
				( pin "vss(7)"
					( attribute "PN" "268"
						( Origin gPackager )
					)
					( objectStatus "J1A2.268" )
				)
				( pin "vss(8)"
					( attribute "PN" "265"
						( Origin gPackager )
					)
					( objectStatus "J1A2.265" )
				)
				( pin "vss(9)"
					( attribute "PN" "263"
						( Origin gPackager )
					)
					( objectStatus "J1A2.263" )
				)
				( pin "vss(10)"
					( attribute "PN" "261"
						( Origin gPackager )
					)
					( objectStatus "J1A2.261" )
				)
				( pin "vss(11)"
					( attribute "PN" "259"
						( Origin gPackager )
					)
					( objectStatus "J1A2.259" )
				)
				( pin "vss(12)"
					( attribute "PN" "257"
						( Origin gPackager )
					)
					( objectStatus "J1A2.257" )
				)
				( pin "vss(13)"
					( attribute "PN" "254"
						( Origin gPackager )
					)
					( objectStatus "J1A2.254" )
				)
				( pin "vss(14)"
					( attribute "PN" "252"
						( Origin gPackager )
					)
					( objectStatus "J1A2.252" )
				)
				( pin "vss(15)"
					( attribute "PN" "250"
						( Origin gPackager )
					)
					( objectStatus "J1A2.250" )
				)
				( pin "vss(16)"
					( attribute "PN" "248"
						( Origin gPackager )
					)
					( objectStatus "J1A2.248" )
				)
				( pin "vss(17)"
					( attribute "PN" "246"
						( Origin gPackager )
					)
					( objectStatus "J1A2.246" )
				)
				( pin "vss(18)"
					( attribute "PN" "243"
						( Origin gPackager )
					)
					( objectStatus "J1A2.243" )
				)
				( pin "vss(19)"
					( attribute "PN" "241"
						( Origin gPackager )
					)
					( objectStatus "J1A2.241" )
				)
				( pin "vss(20)"
					( attribute "PN" "239"
						( Origin gPackager )
					)
					( objectStatus "J1A2.239" )
				)
				( pin "vss(21)"
					( attribute "PN" "202"
						( Origin gPackager )
					)
					( objectStatus "J1A2.202" )
				)
				( pin "vss(22)"
					( attribute "PN" "200"
						( Origin gPackager )
					)
					( objectStatus "J1A2.200" )
				)
				( pin "vss(23)"
					( attribute "PN" "198"
						( Origin gPackager )
					)
					( objectStatus "J1A2.198" )
				)
				( pin "vss(24)"
					( attribute "PN" "195"
						( Origin gPackager )
					)
					( objectStatus "J1A2.195" )
				)
				( pin "vss(25)"
					( attribute "PN" "193"
						( Origin gPackager )
					)
					( objectStatus "J1A2.193" )
				)
				( pin "vss(26)"
					( attribute "PN" "191"
						( Origin gPackager )
					)
					( objectStatus "J1A2.191" )
				)
				( pin "vss(27)"
					( attribute "PN" "189"
						( Origin gPackager )
					)
					( objectStatus "J1A2.189" )
				)
				( pin "vss(28)"
					( attribute "PN" "187"
						( Origin gPackager )
					)
					( objectStatus "J1A2.187" )
				)
				( pin "vss(29)"
					( attribute "PN" "184"
						( Origin gPackager )
					)
					( objectStatus "J1A2.184" )
				)
				( pin "vss(30)"
					( attribute "PN" "182"
						( Origin gPackager )
					)
					( objectStatus "J1A2.182" )
				)
				( pin "vss(31)"
					( attribute "PN" "180"
						( Origin gPackager )
					)
					( objectStatus "J1A2.180" )
				)
				( pin "vss(32)"
					( attribute "PN" "178"
						( Origin gPackager )
					)
					( objectStatus "J1A2.178" )
				)
				( pin "vss(33)"
					( attribute "PN" "176"
						( Origin gPackager )
					)
					( objectStatus "J1A2.176" )
				)
				( pin "vss(34)"
					( attribute "PN" "173"
						( Origin gPackager )
					)
					( objectStatus "J1A2.173" )
				)
				( pin "vss(35)"
					( attribute "PN" "171"
						( Origin gPackager )
					)
					( objectStatus "J1A2.171" )
				)
				( pin "vss(36)"
					( attribute "PN" "169"
						( Origin gPackager )
					)
					( objectStatus "J1A2.169" )
				)
				( pin "vss(37)"
					( attribute "PN" "167"
						( Origin gPackager )
					)
					( objectStatus "J1A2.167" )
				)
				( pin "vss(38)"
					( attribute "PN" "165"
						( Origin gPackager )
					)
					( objectStatus "J1A2.165" )
				)
				( pin "vss(39)"
					( attribute "PN" "162"
						( Origin gPackager )
					)
					( objectStatus "J1A2.162" )
				)
				( pin "vss(40)"
					( attribute "PN" "160"
						( Origin gPackager )
					)
					( objectStatus "J1A2.160" )
				)
				( pin "vss(41)"
					( attribute "PN" "158"
						( Origin gPackager )
					)
					( objectStatus "J1A2.158" )
				)
				( pin "vss(42)"
					( attribute "PN" "156"
						( Origin gPackager )
					)
					( objectStatus "J1A2.156" )
				)
				( pin "vss(43)"
					( attribute "PN" "154"
						( Origin gPackager )
					)
					( objectStatus "J1A2.154" )
				)
				( pin "vss(44)"
					( attribute "PN" "151"
						( Origin gPackager )
					)
					( objectStatus "J1A2.151" )
				)
				( pin "vss(45)"
					( attribute "PN" "149"
						( Origin gPackager )
					)
					( objectStatus "J1A2.149" )
				)
				( pin "vss(46)"
					( attribute "PN" "147"
						( Origin gPackager )
					)
					( objectStatus "J1A2.147" )
				)
				( pin "vss(47)"
					( attribute "PN" "138"
						( Origin gPackager )
					)
					( objectStatus "J1A2.138" )
				)
				( pin "vss(48)"
					( attribute "PN" "136"
						( Origin gPackager )
					)
					( objectStatus "J1A2.136" )
				)
				( pin "vss(49)"
					( attribute "PN" "134"
						( Origin gPackager )
					)
					( objectStatus "J1A2.134" )
				)
				( pin "vss(50)"
					( attribute "PN" "131"
						( Origin gPackager )
					)
					( objectStatus "J1A2.131" )
				)
				( pin "vss(51)"
					( attribute "PN" "129"
						( Origin gPackager )
					)
					( objectStatus "J1A2.129" )
				)
				( pin "vss(52)"
					( attribute "PN" "127"
						( Origin gPackager )
					)
					( objectStatus "J1A2.127" )
				)
				( pin "vss(53)"
					( attribute "PN" "125"
						( Origin gPackager )
					)
					( objectStatus "J1A2.125" )
				)
				( pin "vss(54)"
					( attribute "PN" "123"
						( Origin gPackager )
					)
					( objectStatus "J1A2.123" )
				)
				( pin "vss(55)"
					( attribute "PN" "120"
						( Origin gPackager )
					)
					( objectStatus "J1A2.120" )
				)
				( pin "vss(56)"
					( attribute "PN" "118"
						( Origin gPackager )
					)
					( objectStatus "J1A2.118" )
				)
				( pin "vss(57)"
					( attribute "PN" "116"
						( Origin gPackager )
					)
					( objectStatus "J1A2.116" )
				)
				( pin "vss(58)"
					( attribute "PN" "114"
						( Origin gPackager )
					)
					( objectStatus "J1A2.114" )
				)
				( pin "vss(59)"
					( attribute "PN" "112"
						( Origin gPackager )
					)
					( objectStatus "J1A2.112" )
				)
				( pin "vss(60)"
					( attribute "PN" "109"
						( Origin gPackager )
					)
					( objectStatus "J1A2.109" )
				)
				( pin "vss(61)"
					( attribute "PN" "107"
						( Origin gPackager )
					)
					( objectStatus "J1A2.107" )
				)
				( pin "vss(62)"
					( attribute "PN" "105"
						( Origin gPackager )
					)
					( objectStatus "J1A2.105" )
				)
				( pin "vss(63)"
					( attribute "PN" "103"
						( Origin gPackager )
					)
					( objectStatus "J1A2.103" )
				)
				( pin "vss(64)"
					( attribute "PN" "101"
						( Origin gPackager )
					)
					( objectStatus "J1A2.101" )
				)
				( pin "vss(65)"
					( attribute "PN" "98"
						( Origin gPackager )
					)
					( objectStatus "J1A2.98" )
				)
				( pin "vss(66)"
					( attribute "PN" "96"
						( Origin gPackager )
					)
					( objectStatus "J1A2.96" )
				)
				( pin "vss(67)"
					( attribute "PN" "94"
						( Origin gPackager )
					)
					( objectStatus "J1A2.94" )
				)
				( pin "vss(68)"
					( attribute "PN" "57"
						( Origin gPackager )
					)
					( objectStatus "J1A2.57" )
				)
				( pin "vss(69)"
					( attribute "PN" "55"
						( Origin gPackager )
					)
					( objectStatus "J1A2.55" )
				)
				( pin "vss(70)"
					( attribute "PN" "53"
						( Origin gPackager )
					)
					( objectStatus "J1A2.53" )
				)
				( pin "vss(71)"
					( attribute "PN" "50"
						( Origin gPackager )
					)
					( objectStatus "J1A2.50" )
				)
				( pin "vss(72)"
					( attribute "PN" "48"
						( Origin gPackager )
					)
					( objectStatus "J1A2.48" )
				)
				( pin "vss(73)"
					( attribute "PN" "46"
						( Origin gPackager )
					)
					( objectStatus "J1A2.46" )
				)
				( pin "vss(74)"
					( attribute "PN" "44"
						( Origin gPackager )
					)
					( objectStatus "J1A2.44" )
				)
				( pin "vss(75)"
					( attribute "PN" "42"
						( Origin gPackager )
					)
					( objectStatus "J1A2.42" )
				)
				( pin "vss(76)"
					( attribute "PN" "39"
						( Origin gPackager )
					)
					( objectStatus "J1A2.39" )
				)
				( pin "vss(77)"
					( attribute "PN" "37"
						( Origin gPackager )
					)
					( objectStatus "J1A2.37" )
				)
				( pin "vss(78)"
					( attribute "PN" "35"
						( Origin gPackager )
					)
					( objectStatus "J1A2.35" )
				)
				( pin "vss(79)"
					( attribute "PN" "33"
						( Origin gPackager )
					)
					( objectStatus "J1A2.33" )
				)
				( pin "vss(80)"
					( attribute "PN" "31"
						( Origin gPackager )
					)
					( objectStatus "J1A2.31" )
				)
				( pin "vss(81)"
					( attribute "PN" "28"
						( Origin gPackager )
					)
					( objectStatus "J1A2.28" )
				)
				( pin "vss(82)"
					( attribute "PN" "26"
						( Origin gPackager )
					)
					( objectStatus "J1A2.26" )
				)
				( pin "vss(83)"
					( attribute "PN" "24"
						( Origin gPackager )
					)
					( objectStatus "J1A2.24" )
				)
				( pin "vss(84)"
					( attribute "PN" "22"
						( Origin gPackager )
					)
					( objectStatus "J1A2.22" )
				)
				( pin "vss(85)"
					( attribute "PN" "20"
						( Origin gPackager )
					)
					( objectStatus "J1A2.20" )
				)
				( pin "vss(86)"
					( attribute "PN" "17"
						( Origin gPackager )
					)
					( objectStatus "J1A2.17" )
				)
				( pin "vss(87)"
					( attribute "PN" "15"
						( Origin gPackager )
					)
					( objectStatus "J1A2.15" )
				)
				( pin "vss(88)"
					( attribute "PN" "13"
						( Origin gPackager )
					)
					( objectStatus "J1A2.13" )
				)
				( pin "vss(89)"
					( attribute "PN" "11"
						( Origin gPackager )
					)
					( objectStatus "J1A2.11" )
				)
				( pin "vss(90)"
					( attribute "PN" "9"
						( Origin gPackager )
					)
					( objectStatus "J1A2.9" )
				)
				( pin "vss(91)"
					( attribute "PN" "6"
						( Origin gPackager )
					)
					( objectStatus "J1A2.6" )
				)
				( pin "vss(92)"
					( attribute "PN" "4"
						( Origin gPackager )
					)
					( objectStatus "J1A2.4" )
				)
				( pin "vss(93)"
					( attribute "PN" "2"
						( Origin gPackager )
					)
					( objectStatus "J1A2.2" )
				)
			)
			( gate "@baseboard_fab2_lib.baseboard_fab2(sch_1):page85_i66"
				( attribute "BOM_COST" "MEM"
					( Origin gFrontEnd )
				)
				( attribute "CDS_LIB" "mstr_sconn"
					( Origin gPackager )
				)
				( attribute "CDS_LOCATION" "J1A2"
					( Origin gPackager )
				)
				( attribute "CDS_SEC" "2"
					( Origin gPackager )
				)
				( attribute "LOCATION" "J1A2"
					( Origin gFrontEnd )
				)
				( attribute "MATERIAL" "SCONN"
					( Origin gFrontEnd )
				)
				( attribute "PACK_TYPE" "PIP"
					( Origin gFrontEnd )
				)
				( attribute "PART_NUMBER" "H44441-004"
					( Origin gFrontEnd )
				)
				( attribute "PHYS_PAGE" "85"
					( Origin gFrontEnd )
				)
				( attribute "ROOM" "DDR4_CH_L"
					( Origin gFrontEnd )
				)
				( attribute "ROT" "0"
					( Origin gFrontEnd )
				)
				( attribute "SEC" "2"
					( Origin gFrontEnd )
				)
				( attribute "SEC_TYPE" "PIP"
					( Origin gFrontEnd )
				)
				( attribute "VER" "2"
					( Origin gFrontEnd )
				)
				( attribute "XY" "(0,4300)"
					( Origin gFrontEnd )
				)
				( attribute "CHIPS_PART_NAME" "SCONN288_H44441004"
					( Origin gPackager )
				)
				( attribute "CDS_PART_NAME" "SCONN288_H44441004_PIP-SCONN,HA"
					( Origin gPackager )
				)
				( objectStatus "J1A2" )
				( pin "dqs0n"
					( attribute "PN" "152"
						( Origin gPackager )
					)
					( objectStatus "J1A2.152" )
				)
				( pin "dqs0p"
					( attribute "PN" "153"
						( Origin gPackager )
					)
					( objectStatus "J1A2.153" )
				)
				( pin "dqs1n"
					( attribute "PN" "163"
						( Origin gPackager )
					)
					( objectStatus "J1A2.163" )
				)
				( pin "dqs1p"
					( attribute "PN" "164"
						( Origin gPackager )
					)
					( objectStatus "J1A2.164" )
				)
				( pin "dqs2n"
					( attribute "PN" "174"
						( Origin gPackager )
					)
					( objectStatus "J1A2.174" )
				)
				( pin "dqs2p"
					( attribute "PN" "175"
						( Origin gPackager )
					)
					( objectStatus "J1A2.175" )
				)
				( pin "dqs3n"
					( attribute "PN" "185"
						( Origin gPackager )
					)
					( objectStatus "J1A2.185" )
				)
				( pin "dqs3p"
					( attribute "PN" "186"
						( Origin gPackager )
					)
					( objectStatus "J1A2.186" )
				)
				( pin "dqs4n"
					( attribute "PN" "244"
						( Origin gPackager )
					)
					( objectStatus "J1A2.244" )
				)
				( pin "dqs4p"
					( attribute "PN" "245"
						( Origin gPackager )
					)
					( objectStatus "J1A2.245" )
				)
				( pin "dqs5n"
					( attribute "PN" "255"
						( Origin gPackager )
					)
					( objectStatus "J1A2.255" )
				)
				( pin "dqs5p"
					( attribute "PN" "256"
						( Origin gPackager )
					)
					( objectStatus "J1A2.256" )
				)
				( pin "dqs6n"
					( attribute "PN" "266"
						( Origin gPackager )
					)
					( objectStatus "J1A2.266" )
				)
				( pin "dqs6p"
					( attribute "PN" "267"
						( Origin gPackager )
					)
					( objectStatus "J1A2.267" )
				)
				( pin "dqs7n"
					( attribute "PN" "277"
						( Origin gPackager )
					)
					( objectStatus "J1A2.277" )
				)
				( pin "dqs7p"
					( attribute "PN" "278"
						( Origin gPackager )
					)
					( objectStatus "J1A2.278" )
				)
				( pin "dqs8n"
					( attribute "PN" "196"
						( Origin gPackager )
					)
					( objectStatus "J1A2.196" )
				)
				( pin "dqs8p"
					( attribute "PN" "197"
						( Origin gPackager )
					)
					( objectStatus "J1A2.197" )
				)
				( pin "dqs9n"
					( attribute "PN" "8"
						( Origin gPackager )
					)
					( objectStatus "J1A2.8" )
				)
				( pin "dqs9p"
					( attribute "PN" "7"
						( Origin gPackager )
					)
					( objectStatus "J1A2.7" )
				)
				( pin "dqs10n"
					( attribute "PN" "19"
						( Origin gPackager )
					)
					( objectStatus "J1A2.19" )
				)
				( pin "dqs10p"
					( attribute "PN" "18"
						( Origin gPackager )
					)
					( objectStatus "J1A2.18" )
				)
				( pin "dqs11n"
					( attribute "PN" "30"
						( Origin gPackager )
					)
					( objectStatus "J1A2.30" )
				)
				( pin "dqs11p"
					( attribute "PN" "29"
						( Origin gPackager )
					)
					( objectStatus "J1A2.29" )
				)
				( pin "dqs12n"
					( attribute "PN" "41"
						( Origin gPackager )
					)
					( objectStatus "J1A2.41" )
				)
				( pin "dqs12p"
					( attribute "PN" "40"
						( Origin gPackager )
					)
					( objectStatus "J1A2.40" )
				)
				( pin "dqs13n"
					( attribute "PN" "100"
						( Origin gPackager )
					)
					( objectStatus "J1A2.100" )
				)
				( pin "dqs13p"
					( attribute "PN" "99"
						( Origin gPackager )
					)
					( objectStatus "J1A2.99" )
				)
				( pin "dqs14n"
					( attribute "PN" "111"
						( Origin gPackager )
					)
					( objectStatus "J1A2.111" )
				)
				( pin "dqs14p"
					( attribute "PN" "110"
						( Origin gPackager )
					)
					( objectStatus "J1A2.110" )
				)
				( pin "dqs15n"
					( attribute "PN" "122"
						( Origin gPackager )
					)
					( objectStatus "J1A2.122" )
				)
				( pin "dqs15p"
					( attribute "PN" "121"
						( Origin gPackager )
					)
					( objectStatus "J1A2.121" )
				)
				( pin "dqs16n"
					( attribute "PN" "133"
						( Origin gPackager )
					)
					( objectStatus "J1A2.133" )
				)
				( pin "dqs16p"
					( attribute "PN" "132"
						( Origin gPackager )
					)
					( objectStatus "J1A2.132" )
				)
				( pin "dqs17n"
					( attribute "PN" "52"
						( Origin gPackager )
					)
					( objectStatus "J1A2.52" )
				)
				( pin "dqs17p"
					( attribute "PN" "51"
						( Origin gPackager )
					)
					( objectStatus "J1A2.51" )
				)
			)
			( gate "@baseboard_fab2_lib.baseboard_fab2(sch_1):page85_i111"
				( attribute "BOM_COST" "MEM"
					( Origin gFrontEnd )
				)
				( attribute "CDS_LIB" "mstr_sconn"
					( Origin gPackager )
				)
				( attribute "CDS_LOCATION" "J1A2"
					( Origin gPackager )
				)
				( attribute "CDS_SEC" "1"
					( Origin gPackager )
				)
				( attribute "LOCATION" "J1A2"
					( Origin gFrontEnd )
				)
				( attribute "MATERIAL" "SCONN"
					( Origin gFrontEnd )
				)
				( attribute "PACK_TYPE" "PIP"
					( Origin gFrontEnd )
				)
				( attribute "PART_NUMBER" "H44441-004"
					( Origin gFrontEnd )
				)
				( attribute "PHYS_PAGE" "85"
					( Origin gFrontEnd )
				)
				( attribute "ROOM" "DDR4_CH_L"
					( Origin gFrontEnd )
				)
				( attribute "ROT" "0"
					( Origin gFrontEnd )
				)
				( attribute "SEC" "1"
					( Origin gFrontEnd )
				)
				( attribute "SEC_TYPE" "PIP"
					( Origin gFrontEnd )
				)
				( attribute "VER" "1"
					( Origin gFrontEnd )
				)
				( attribute "XY" "(-2500,3250)"
					( Origin gFrontEnd )
				)
				( attribute "CHIPS_PART_NAME" "SCONN288_H44441004"
					( Origin gPackager )
				)
				( attribute "CDS_PART_NAME" "SCONN288_H44441004_PIP-SCONN,HA"
					( Origin gPackager )
				)
				( objectStatus "J1A2" )
				( pin "a0"
					( attribute "PN" "79"
						( Origin gPackager )
					)
					( objectStatus "J1A2.79" )
				)
				( pin "a1"
					( attribute "PN" "72"
						( Origin gPackager )
					)
					( objectStatus "J1A2.72" )
				)
				( pin "a2"
					( attribute "PN" "216"
						( Origin gPackager )
					)
					( objectStatus "J1A2.216" )
				)
				( pin "a3"
					( attribute "PN" "71"
						( Origin gPackager )
					)
					( objectStatus "J1A2.71" )
				)
				( pin "a4"
					( attribute "PN" "214"
						( Origin gPackager )
					)
					( objectStatus "J1A2.214" )
				)
				( pin "a5"
					( attribute "PN" "213"
						( Origin gPackager )
					)
					( objectStatus "J1A2.213" )
				)
				( pin "a6"
					( attribute "PN" "69"
						( Origin gPackager )
					)
					( objectStatus "J1A2.69" )
				)
				( pin "a7"
					( attribute "PN" "211"
						( Origin gPackager )
					)
					( objectStatus "J1A2.211" )
				)
				( pin "a8"
					( attribute "PN" "68"
						( Origin gPackager )
					)
					( objectStatus "J1A2.68" )
				)
				( pin "a9"
					( attribute "PN" "66"
						( Origin gPackager )
					)
					( objectStatus "J1A2.66" )
				)
				( pin "a10"
					( attribute "PN" "225"
						( Origin gPackager )
					)
					( objectStatus "J1A2.225" )
				)
				( pin "a11"
					( attribute "PN" "210"
						( Origin gPackager )
					)
					( objectStatus "J1A2.210" )
				)
				( pin "a12"
					( attribute "PN" "65"
						( Origin gPackager )
					)
					( objectStatus "J1A2.65" )
				)
				( pin "a13"
					( attribute "PN" "232"
						( Origin gPackager )
					)
					( objectStatus "J1A2.232" )
				)
				( pin "a14_we_n"
					( attribute "PN" "228"
						( Origin gPackager )
					)
					( objectStatus "J1A2.228" )
				)
				( pin "a15_cas_n"
					( attribute "PN" "86"
						( Origin gPackager )
					)
					( objectStatus "J1A2.86" )
				)
				( pin "a16_ras_n"
					( attribute "PN" "82"
						( Origin gPackager )
					)
					( objectStatus "J1A2.82" )
				)
				( pin "a17"
					( attribute "PN" "234"
						( Origin gPackager )
					)
					( objectStatus "J1A2.234" )
				)
				( pin "act_n"
					( attribute "PN" "62"
						( Origin gPackager )
					)
					( objectStatus "J1A2.62" )
				)
				( pin "alert_n"
					( attribute "PN" "208"
						( Origin gPackager )
					)
					( objectStatus "J1A2.208" )
				)
				( pin "ba(0)"
					( attribute "PN" "81"
						( Origin gPackager )
					)
					( objectStatus "J1A2.81" )
				)
				( pin "ba(1)"
					( attribute "PN" "224"
						( Origin gPackager )
					)
					( objectStatus "J1A2.224" )
				)
				( pin "bg(0)"
					( attribute "PN" "63"
						( Origin gPackager )
					)
					( objectStatus "J1A2.63" )
				)
				( pin "bg(1)"
					( attribute "PN" "207"
						( Origin gPackager )
					)
					( objectStatus "J1A2.207" )
				)
				( pin "c(2)"
					( attribute "PN" "235"
						( Origin gPackager )
					)
					( objectStatus "J1A2.235" )
				)
				( pin "cb(0)"
					( attribute "PN" "49"
						( Origin gPackager )
					)
					( objectStatus "J1A2.49" )
				)
				( pin "cb(1)"
					( attribute "PN" "194"
						( Origin gPackager )
					)
					( objectStatus "J1A2.194" )
				)
				( pin "cb(2)"
					( attribute "PN" "56"
						( Origin gPackager )
					)
					( objectStatus "J1A2.56" )
				)
				( pin "cb(3)"
					( attribute "PN" "201"
						( Origin gPackager )
					)
					( objectStatus "J1A2.201" )
				)
				( pin "cb(4)"
					( attribute "PN" "47"
						( Origin gPackager )
					)
					( objectStatus "J1A2.47" )
				)
				( pin "cb(5)"
					( attribute "PN" "192"
						( Origin gPackager )
					)
					( objectStatus "J1A2.192" )
				)
				( pin "cb(6)"
					( attribute "PN" "54"
						( Origin gPackager )
					)
					( objectStatus "J1A2.54" )
				)
				( pin "cb(7)"
					( attribute "PN" "199"
						( Origin gPackager )
					)
					( objectStatus "J1A2.199" )
				)
				( pin "ck0n"
					( attribute "PN" "75"
						( Origin gPackager )
					)
					( objectStatus "J1A2.75" )
				)
				( pin "ck0p"
					( attribute "PN" "74"
						( Origin gPackager )
					)
					( objectStatus "J1A2.74" )
				)
				( pin "ck1n"
					( attribute "PN" "219"
						( Origin gPackager )
					)
					( objectStatus "J1A2.219" )
				)
				( pin "ck1p"
					( attribute "PN" "218"
						( Origin gPackager )
					)
					( objectStatus "J1A2.218" )
				)
				( pin "cke(0)"
					( attribute "PN" "60"
						( Origin gPackager )
					)
					( objectStatus "J1A2.60" )
				)
				( pin "cke(1)"
					( attribute "PN" "203"
						( Origin gPackager )
					)
					( objectStatus "J1A2.203" )
				)
				( pin "dq(0)"
					( attribute "PN" "5"
						( Origin gPackager )
					)
					( objectStatus "J1A2.5" )
				)
				( pin "dq(1)"
					( attribute "PN" "150"
						( Origin gPackager )
					)
					( objectStatus "J1A2.150" )
				)
				( pin "dq(2)"
					( attribute "PN" "12"
						( Origin gPackager )
					)
					( objectStatus "J1A2.12" )
				)
				( pin "dq(3)"
					( attribute "PN" "157"
						( Origin gPackager )
					)
					( objectStatus "J1A2.157" )
				)
				( pin "dq(4)"
					( attribute "PN" "3"
						( Origin gPackager )
					)
					( objectStatus "J1A2.3" )
				)
				( pin "dq(5)"
					( attribute "PN" "148"
						( Origin gPackager )
					)
					( objectStatus "J1A2.148" )
				)
				( pin "dq(6)"
					( attribute "PN" "10"
						( Origin gPackager )
					)
					( objectStatus "J1A2.10" )
				)
				( pin "dq(7)"
					( attribute "PN" "155"
						( Origin gPackager )
					)
					( objectStatus "J1A2.155" )
				)
				( pin "dq(8)"
					( attribute "PN" "16"
						( Origin gPackager )
					)
					( objectStatus "J1A2.16" )
				)
				( pin "dq(9)"
					( attribute "PN" "161"
						( Origin gPackager )
					)
					( objectStatus "J1A2.161" )
				)
				( pin "dq(10)"
					( attribute "PN" "23"
						( Origin gPackager )
					)
					( objectStatus "J1A2.23" )
				)
				( pin "dq(11)"
					( attribute "PN" "168"
						( Origin gPackager )
					)
					( objectStatus "J1A2.168" )
				)
				( pin "dq(12)"
					( attribute "PN" "14"
						( Origin gPackager )
					)
					( objectStatus "J1A2.14" )
				)
				( pin "dq(13)"
					( attribute "PN" "159"
						( Origin gPackager )
					)
					( objectStatus "J1A2.159" )
				)
				( pin "dq(14)"
					( attribute "PN" "21"
						( Origin gPackager )
					)
					( objectStatus "J1A2.21" )
				)
				( pin "dq(15)"
					( attribute "PN" "166"
						( Origin gPackager )
					)
					( objectStatus "J1A2.166" )
				)
				( pin "dq(16)"
					( attribute "PN" "27"
						( Origin gPackager )
					)
					( objectStatus "J1A2.27" )
				)
				( pin "dq(17)"
					( attribute "PN" "172"
						( Origin gPackager )
					)
					( objectStatus "J1A2.172" )
				)
				( pin "dq(18)"
					( attribute "PN" "34"
						( Origin gPackager )
					)
					( objectStatus "J1A2.34" )
				)
				( pin "dq(19)"
					( attribute "PN" "179"
						( Origin gPackager )
					)
					( objectStatus "J1A2.179" )
				)
				( pin "dq(20)"
					( attribute "PN" "25"
						( Origin gPackager )
					)
					( objectStatus "J1A2.25" )
				)
				( pin "dq(21)"
					( attribute "PN" "170"
						( Origin gPackager )
					)
					( objectStatus "J1A2.170" )
				)
				( pin "dq(22)"
					( attribute "PN" "32"
						( Origin gPackager )
					)
					( objectStatus "J1A2.32" )
				)
				( pin "dq(23)"
					( attribute "PN" "177"
						( Origin gPackager )
					)
					( objectStatus "J1A2.177" )
				)
				( pin "dq(24)"
					( attribute "PN" "38"
						( Origin gPackager )
					)
					( objectStatus "J1A2.38" )
				)
				( pin "dq(25)"
					( attribute "PN" "183"
						( Origin gPackager )
					)
					( objectStatus "J1A2.183" )
				)
				( pin "dq(26)"
					( attribute "PN" "45"
						( Origin gPackager )
					)
					( objectStatus "J1A2.45" )
				)
				( pin "dq(27)"
					( attribute "PN" "190"
						( Origin gPackager )
					)
					( objectStatus "J1A2.190" )
				)
				( pin "dq(28)"
					( attribute "PN" "36"
						( Origin gPackager )
					)
					( objectStatus "J1A2.36" )
				)
				( pin "dq(29)"
					( attribute "PN" "181"
						( Origin gPackager )
					)
					( objectStatus "J1A2.181" )
				)
				( pin "dq(30)"
					( attribute "PN" "43"
						( Origin gPackager )
					)
					( objectStatus "J1A2.43" )
				)
				( pin "dq(31)"
					( attribute "PN" "188"
						( Origin gPackager )
					)
					( objectStatus "J1A2.188" )
				)
				( pin "dq(32)"
					( attribute "PN" "97"
						( Origin gPackager )
					)
					( objectStatus "J1A2.97" )
				)
				( pin "dq(33)"
					( attribute "PN" "242"
						( Origin gPackager )
					)
					( objectStatus "J1A2.242" )
				)
				( pin "dq(34)"
					( attribute "PN" "104"
						( Origin gPackager )
					)
					( objectStatus "J1A2.104" )
				)
				( pin "dq(35)"
					( attribute "PN" "249"
						( Origin gPackager )
					)
					( objectStatus "J1A2.249" )
				)
				( pin "dq(36)"
					( attribute "PN" "95"
						( Origin gPackager )
					)
					( objectStatus "J1A2.95" )
				)
				( pin "dq(37)"
					( attribute "PN" "240"
						( Origin gPackager )
					)
					( objectStatus "J1A2.240" )
				)
				( pin "dq(38)"
					( attribute "PN" "102"
						( Origin gPackager )
					)
					( objectStatus "J1A2.102" )
				)
				( pin "dq(39)"
					( attribute "PN" "247"
						( Origin gPackager )
					)
					( objectStatus "J1A2.247" )
				)
				( pin "dq(40)"
					( attribute "PN" "108"
						( Origin gPackager )
					)
					( objectStatus "J1A2.108" )
				)
				( pin "dq(41)"
					( attribute "PN" "253"
						( Origin gPackager )
					)
					( objectStatus "J1A2.253" )
				)
				( pin "dq(42)"
					( attribute "PN" "115"
						( Origin gPackager )
					)
					( objectStatus "J1A2.115" )
				)
				( pin "dq(43)"
					( attribute "PN" "260"
						( Origin gPackager )
					)
					( objectStatus "J1A2.260" )
				)
				( pin "dq(44)"
					( attribute "PN" "106"
						( Origin gPackager )
					)
					( objectStatus "J1A2.106" )
				)
				( pin "dq(45)"
					( attribute "PN" "251"
						( Origin gPackager )
					)
					( objectStatus "J1A2.251" )
				)
				( pin "dq(46)"
					( attribute "PN" "113"
						( Origin gPackager )
					)
					( objectStatus "J1A2.113" )
				)
				( pin "dq(47)"
					( attribute "PN" "258"
						( Origin gPackager )
					)
					( objectStatus "J1A2.258" )
				)
				( pin "dq(48)"
					( attribute "PN" "119"
						( Origin gPackager )
					)
					( objectStatus "J1A2.119" )
				)
				( pin "dq(49)"
					( attribute "PN" "264"
						( Origin gPackager )
					)
					( objectStatus "J1A2.264" )
				)
				( pin "dq(50)"
					( attribute "PN" "126"
						( Origin gPackager )
					)
					( objectStatus "J1A2.126" )
				)
				( pin "dq(51)"
					( attribute "PN" "271"
						( Origin gPackager )
					)
					( objectStatus "J1A2.271" )
				)
				( pin "dq(52)"
					( attribute "PN" "117"
						( Origin gPackager )
					)
					( objectStatus "J1A2.117" )
				)
				( pin "dq(53)"
					( attribute "PN" "262"
						( Origin gPackager )
					)
					( objectStatus "J1A2.262" )
				)
				( pin "dq(54)"
					( attribute "PN" "124"
						( Origin gPackager )
					)
					( objectStatus "J1A2.124" )
				)
				( pin "dq(55)"
					( attribute "PN" "269"
						( Origin gPackager )
					)
					( objectStatus "J1A2.269" )
				)
				( pin "dq(56)"
					( attribute "PN" "130"
						( Origin gPackager )
					)
					( objectStatus "J1A2.130" )
				)
				( pin "dq(57)"
					( attribute "PN" "275"
						( Origin gPackager )
					)
					( objectStatus "J1A2.275" )
				)
				( pin "dq(58)"
					( attribute "PN" "137"
						( Origin gPackager )
					)
					( objectStatus "J1A2.137" )
				)
				( pin "dq(59)"
					( attribute "PN" "282"
						( Origin gPackager )
					)
					( objectStatus "J1A2.282" )
				)
				( pin "dq(60)"
					( attribute "PN" "128"
						( Origin gPackager )
					)
					( objectStatus "J1A2.128" )
				)
				( pin "dq(61)"
					( attribute "PN" "273"
						( Origin gPackager )
					)
					( objectStatus "J1A2.273" )
				)
				( pin "dq(62)"
					( attribute "PN" "135"
						( Origin gPackager )
					)
					( objectStatus "J1A2.135" )
				)
				( pin "dq(63)"
					( attribute "PN" "280"
						( Origin gPackager )
					)
					( objectStatus "J1A2.280" )
				)
				( pin "event_n"
					( attribute "PN" "78"
						( Origin gPackager )
					)
					( objectStatus "J1A2.78" )
				)
				( pin "odt(0)"
					( attribute "PN" "87"
						( Origin gPackager )
					)
					( objectStatus "J1A2.87" )
				)
				( pin "odt(1)"
					( attribute "PN" "91"
						( Origin gPackager )
					)
					( objectStatus "J1A2.91" )
				)
				( pin "par"
					( attribute "PN" "222"
						( Origin gPackager )
					)
					( objectStatus "J1A2.222" )
				)
				( pin "reset_n"
					( attribute "PN" "58"
						( Origin gPackager )
					)
					( objectStatus "J1A2.58" )
				)
				( pin "rfu(0)"
					( attribute "PN" "205"
						( Origin gPackager )
					)
					( objectStatus "J1A2.205" )
				)
				( pin "rfu(1)"
					( attribute "PN" "227"
						( Origin gPackager )
					)
					( objectStatus "J1A2.227" )
				)
				( pin "rfu(2)"
					( attribute "PN" "144"
						( Origin gPackager )
					)
					( objectStatus "J1A2.144" )
				)
				( pin "s0_n"
					( attribute "PN" "84"
						( Origin gPackager )
					)
					( objectStatus "J1A2.84" )
				)
				( pin "s1_n"
					( attribute "PN" "89"
						( Origin gPackager )
					)
					( objectStatus "J1A2.89" )
				)
				( pin "s2_n_c(0)"
					( attribute "PN" "93"
						( Origin gPackager )
					)
					( objectStatus "J1A2.93" )
				)
				( pin "s3_n_c(1)"
					( attribute "PN" "237"
						( Origin gPackager )
					)
					( objectStatus "J1A2.237" )
				)
				( pin "sa(0)"
					( attribute "PN" "139"
						( Origin gPackager )
					)
					( objectStatus "J1A2.139" )
				)
				( pin "sa(1)"
					( attribute "PN" "140"
						( Origin gPackager )
					)
					( objectStatus "J1A2.140" )
				)
				( pin "sa(2)"
					( attribute "PN" "238"
						( Origin gPackager )
					)
					( objectStatus "J1A2.238" )
				)
				( pin "save_n_nc"
					( attribute "PN" "230"
						( Origin gPackager )
					)
					( objectStatus "J1A2.230" )
				)
				( pin "scl"
					( attribute "PN" "141"
						( Origin gPackager )
					)
					( objectStatus "J1A2.141" )
				)
				( pin "sda"
					( attribute "PN" "285"
						( Origin gPackager )
					)
					( objectStatus "J1A2.285" )
				)
				( pin "vddspd"
					( attribute "PN" "284"
						( Origin gPackager )
					)
					( objectStatus "J1A2.284" )
				)
				( pin "vrefca"
					( attribute "PN" "146"
						( Origin gPackager )
					)
					( objectStatus "J1A2.146" )
				)
			)
			( gate "@baseboard_fab2_lib.baseboard_fab2(sch_1):page85_i172"
				( attribute "BOM_COST" "MEM"
					( Origin gFrontEnd )
				)
				( attribute "CDS_LIB" "mstr_sconn"
					( Origin gPackager )
				)
				( attribute "CDS_LOCATION" "J1A2"
					( Origin gPackager )
				)
				( attribute "CDS_SEC" "4"
					( Origin gPackager )
				)
				( attribute "LOCATION" "J1A2"
					( Origin gFrontEnd )
				)
				( attribute "MATERIAL" "SCONN"
					( Origin gFrontEnd )
				)
				( attribute "PACK_TYPE" "PIP"
					( Origin gFrontEnd )
				)
				( attribute "PART_NUMBER" "H44441-004"
					( Origin gFrontEnd )
				)
				( attribute "PHYS_PAGE" "85"
					( Origin gFrontEnd )
				)
				( attribute "ROOM" "DDR4_CH_L"
					( Origin gFrontEnd )
				)
				( attribute "ROT" "0"
					( Origin gFrontEnd )
				)
				( attribute "SEC" "4"
					( Origin gFrontEnd )
				)
				( attribute "SEC_TYPE" "PIP"
					( Origin gFrontEnd )
				)
				( attribute "VER" "4"
					( Origin gFrontEnd )
				)
				( attribute "XY" "(-250,2050)"
					( Origin gFrontEnd )
				)
				( attribute "CHIPS_PART_NAME" "SCONN288_H44441004"
					( Origin gPackager )
				)
				( attribute "CDS_PART_NAME" "SCONN288_H44441004_PIP-SCONN,HA"
					( Origin gPackager )
				)
				( objectStatus "J1A2" )
				( pin "\12v\(0)"
					( attribute "PN" "145"
						( Origin gPackager )
					)
					( objectStatus "J1A2.145" )
				)
				( pin "\12v\(1)"
					( attribute "PN" "1"
						( Origin gPackager )
					)
					( objectStatus "J1A2.1" )
				)
				( pin "vdd(0)"
					( attribute "PN" "236"
						( Origin gPackager )
					)
					( objectStatus "J1A2.236" )
				)
				( pin "vdd(1)"
					( attribute "PN" "233"
						( Origin gPackager )
					)
					( objectStatus "J1A2.233" )
				)
				( pin "vdd(2)"
					( attribute "PN" "231"
						( Origin gPackager )
					)
					( objectStatus "J1A2.231" )
				)
				( pin "vdd(3)"
					( attribute "PN" "229"
						( Origin gPackager )
					)
					( objectStatus "J1A2.229" )
				)
				( pin "vdd(4)"
					( attribute "PN" "226"
						( Origin gPackager )
					)
					( objectStatus "J1A2.226" )
				)
				( pin "vdd(5)"
					( attribute "PN" "223"
						( Origin gPackager )
					)
					( objectStatus "J1A2.223" )
				)
				( pin "vdd(6)"
					( attribute "PN" "220"
						( Origin gPackager )
					)
					( objectStatus "J1A2.220" )
				)
				( pin "vdd(7)"
					( attribute "PN" "217"
						( Origin gPackager )
					)
					( objectStatus "J1A2.217" )
				)
				( pin "vdd(8)"
					( attribute "PN" "215"
						( Origin gPackager )
					)
					( objectStatus "J1A2.215" )
				)
				( pin "vdd(9)"
					( attribute "PN" "212"
						( Origin gPackager )
					)
					( objectStatus "J1A2.212" )
				)
				( pin "vdd(10)"
					( attribute "PN" "209"
						( Origin gPackager )
					)
					( objectStatus "J1A2.209" )
				)
				( pin "vdd(11)"
					( attribute "PN" "206"
						( Origin gPackager )
					)
					( objectStatus "J1A2.206" )
				)
				( pin "vdd(12)"
					( attribute "PN" "204"
						( Origin gPackager )
					)
					( objectStatus "J1A2.204" )
				)
				( pin "vdd(13)"
					( attribute "PN" "92"
						( Origin gPackager )
					)
					( objectStatus "J1A2.92" )
				)
				( pin "vdd(14)"
					( attribute "PN" "90"
						( Origin gPackager )
					)
					( objectStatus "J1A2.90" )
				)
				( pin "vdd(15)"
					( attribute "PN" "88"
						( Origin gPackager )
					)
					( objectStatus "J1A2.88" )
				)
				( pin "vdd(16)"
					( attribute "PN" "85"
						( Origin gPackager )
					)
					( objectStatus "J1A2.85" )
				)
				( pin "vdd(17)"
					( attribute "PN" "83"
						( Origin gPackager )
					)
					( objectStatus "J1A2.83" )
				)
				( pin "vdd(18)"
					( attribute "PN" "80"
						( Origin gPackager )
					)
					( objectStatus "J1A2.80" )
				)
				( pin "vdd(19)"
					( attribute "PN" "76"
						( Origin gPackager )
					)
					( objectStatus "J1A2.76" )
				)
				( pin "vdd(20)"
					( attribute "PN" "73"
						( Origin gPackager )
					)
					( objectStatus "J1A2.73" )
				)
				( pin "vdd(21)"
					( attribute "PN" "70"
						( Origin gPackager )
					)
					( objectStatus "J1A2.70" )
				)
				( pin "vdd(22)"
					( attribute "PN" "67"
						( Origin gPackager )
					)
					( objectStatus "J1A2.67" )
				)
				( pin "vdd(23)"
					( attribute "PN" "64"
						( Origin gPackager )
					)
					( objectStatus "J1A2.64" )
				)
				( pin "vdd(24)"
					( attribute "PN" "61"
						( Origin gPackager )
					)
					( objectStatus "J1A2.61" )
				)
				( pin "vdd(25)"
					( attribute "PN" "59"
						( Origin gPackager )
					)
					( objectStatus "J1A2.59" )
				)
				( pin "vpp(0)"
					( attribute "PN" "287"
						( Origin gPackager )
					)
					( objectStatus "J1A2.287" )
				)
				( pin "vpp(1)"
					( attribute "PN" "286"
						( Origin gPackager )
					)
					( objectStatus "J1A2.286" )
				)
				( pin "vpp(2)"
					( attribute "PN" "288"
						( Origin gPackager )
					)
					( objectStatus "J1A2.288" )
				)
				( pin "vpp(3)"
					( attribute "PN" "143"
						( Origin gPackager )
					)
					( objectStatus "J1A2.143" )
				)
				( pin "vpp(4)"
					( attribute "PN" "142"
						( Origin gPackager )
					)
					( objectStatus "J1A2.142" )
				)
				( pin "vtt(0)"
					( attribute "PN" "221"
						( Origin gPackager )
					)
					( objectStatus "J1A2.221" )
				)
				( pin "vtt(1)"
					( attribute "PN" "77"
						( Origin gPackager )
					)
					( objectStatus "J1A2.77" )
				)
			)
			( gate "@baseboard_fab2_lib.baseboard_fab2(sch_1):page85_i181"
				( attribute "BOM_COST" "MEM"
					( Origin gFrontEnd )
				)
				( attribute "CDS_LIB" "dev_discrete"
					( Origin gPackager )
				)
				( attribute "CDS_LOCATION" "C9L7"
					( Origin gPackager )
				)
				( attribute "CDS_SEC" "1"
					( Origin gPackager )
				)
				( attribute "LOCATION" "C9L7"
					( Origin gFrontEnd )
				)
				( attribute "MATERIAL" "X7R"
					( Origin gFrontEnd )
				)
				( attribute "PACK_TYPE" "0402V"
					( Origin gFrontEnd )
				)
				( attribute "PART_NUMBER" "A36096-045"
					( Origin gFrontEnd )
				)
				( attribute "PHYS_PAGE" "85"
					( Origin gFrontEnd )
				)
				( attribute "ROOM" "DDR4_CH_L"
					( Origin gFrontEnd )
				)
				( attribute "ROT" "2"
					( Origin gFrontEnd )
				)
				( attribute "SEC" "1"
					( Origin gPackager )
				)
				( attribute "TOLERANCE" "10%"
					( Origin gFrontEnd )
				)
				( attribute "VALUE" "0.01UF"
					( Origin gFrontEnd )
				)
				( attribute "VER" "1"
					( Origin gFrontEnd )
				)
				( attribute "VOLTAGE" "25V"
					( Units "uVoltage" "V" 1.000000)
					( Origin gFrontEnd )
				)
				( attribute "XY" "(-4650,1550)"
					( Origin gFrontEnd )
				)
				( attribute "CHIPS_PART_NAME" "CAP_A"
					( Origin gPackager )
				)
				( attribute "CDS_PART_NAME" "CAP_A_0402V-0.01UF,25V,10%,X7RA"
					( Origin gPackager )
				)
				( objectStatus "C9L7" )
				( pin "a"
					( attribute "PN" "1"
						( Origin gPackager )
					)
					( objectStatus "C9L7.1" )
				)
				( pin "b"
					( attribute "PN" "2"
						( Origin gPackager )
					)
					( objectStatus "C9L7.2" )
				)
			)
			( gate "@baseboard_fab2_lib.baseboard_fab2(sch_1):page86_i12"
				( attribute "BOM_COST" "MEM"
					( Origin gFrontEnd )
				)
				( attribute "CDS_LIB" "mstr_sconn"
					( Origin gPackager )
				)
				( attribute "CDS_LOCATION" "J9L2"
					( Origin gPackager )
				)
				( attribute "CDS_SEC" "1"
					( Origin gPackager )
				)
				( attribute "LOCATION" "J9L2"
					( Origin gFrontEnd )
				)
				( attribute "MATERIAL" "SCONN"
					( Origin gFrontEnd )
				)
				( attribute "PACK_TYPE" "PIP"
					( Origin gFrontEnd )
				)
				( attribute "PART_NUMBER" "H44441-003"
					( Origin gFrontEnd )
				)
				( attribute "PHYS_PAGE" "86"
					( Origin gFrontEnd )
				)
				( attribute "ROOM" "DDR4_CH_L"
					( Origin gFrontEnd )
				)
				( attribute "ROT" "0"
					( Origin gFrontEnd )
				)
				( attribute "SEC" "1"
					( Origin gFrontEnd )
				)
				( attribute "SEC_TYPE" "PIP"
					( Origin gFrontEnd )
				)
				( attribute "VER" "1"
					( Origin gFrontEnd )
				)
				( attribute "XY" "(-875,2925)"
					( Origin gFrontEnd )
				)
				( attribute "CHIPS_PART_NAME" "SCONN288_H44441003"
					( Origin gPackager )
				)
				( attribute "CDS_PART_NAME" "SCONN288_H44441003_PIP-SCONN,HA"
					( Origin gPackager )
				)
				( objectStatus "J9L2" )
				( pin "a0"
					( attribute "PN" "79"
						( Origin gPackager )
					)
					( objectStatus "J9L2.79" )
				)
				( pin "a1"
					( attribute "PN" "72"
						( Origin gPackager )
					)
					( objectStatus "J9L2.72" )
				)
				( pin "a2"
					( attribute "PN" "216"
						( Origin gPackager )
					)
					( objectStatus "J9L2.216" )
				)
				( pin "a3"
					( attribute "PN" "71"
						( Origin gPackager )
					)
					( objectStatus "J9L2.71" )
				)
				( pin "a4"
					( attribute "PN" "214"
						( Origin gPackager )
					)
					( objectStatus "J9L2.214" )
				)
				( pin "a5"
					( attribute "PN" "213"
						( Origin gPackager )
					)
					( objectStatus "J9L2.213" )
				)
				( pin "a6"
					( attribute "PN" "69"
						( Origin gPackager )
					)
					( objectStatus "J9L2.69" )
				)
				( pin "a7"
					( attribute "PN" "211"
						( Origin gPackager )
					)
					( objectStatus "J9L2.211" )
				)
				( pin "a8"
					( attribute "PN" "68"
						( Origin gPackager )
					)
					( objectStatus "J9L2.68" )
				)
				( pin "a9"
					( attribute "PN" "66"
						( Origin gPackager )
					)
					( objectStatus "J9L2.66" )
				)
				( pin "a10"
					( attribute "PN" "225"
						( Origin gPackager )
					)
					( objectStatus "J9L2.225" )
				)
				( pin "a11"
					( attribute "PN" "210"
						( Origin gPackager )
					)
					( objectStatus "J9L2.210" )
				)
				( pin "a12"
					( attribute "PN" "65"
						( Origin gPackager )
					)
					( objectStatus "J9L2.65" )
				)
				( pin "a13"
					( attribute "PN" "232"
						( Origin gPackager )
					)
					( objectStatus "J9L2.232" )
				)
				( pin "a14_we_n"
					( attribute "PN" "228"
						( Origin gPackager )
					)
					( objectStatus "J9L2.228" )
				)
				( pin "a15_cas_n"
					( attribute "PN" "86"
						( Origin gPackager )
					)
					( objectStatus "J9L2.86" )
				)
				( pin "a16_ras_n"
					( attribute "PN" "82"
						( Origin gPackager )
					)
					( objectStatus "J9L2.82" )
				)
				( pin "a17"
					( attribute "PN" "234"
						( Origin gPackager )
					)
					( objectStatus "J9L2.234" )
				)
				( pin "act_n"
					( attribute "PN" "62"
						( Origin gPackager )
					)
					( objectStatus "J9L2.62" )
				)
				( pin "alert_n"
					( attribute "PN" "208"
						( Origin gPackager )
					)
					( objectStatus "J9L2.208" )
				)
				( pin "ba(0)"
					( attribute "PN" "81"
						( Origin gPackager )
					)
					( objectStatus "J9L2.81" )
				)
				( pin "ba(1)"
					( attribute "PN" "224"
						( Origin gPackager )
					)
					( objectStatus "J9L2.224" )
				)
				( pin "bg(0)"
					( attribute "PN" "63"
						( Origin gPackager )
					)
					( objectStatus "J9L2.63" )
				)
				( pin "bg(1)"
					( attribute "PN" "207"
						( Origin gPackager )
					)
					( objectStatus "J9L2.207" )
				)
				( pin "c(2)"
					( attribute "PN" "235"
						( Origin gPackager )
					)
					( objectStatus "J9L2.235" )
				)
				( pin "cb(0)"
					( attribute "PN" "49"
						( Origin gPackager )
					)
					( objectStatus "J9L2.49" )
				)
				( pin "cb(1)"
					( attribute "PN" "194"
						( Origin gPackager )
					)
					( objectStatus "J9L2.194" )
				)
				( pin "cb(2)"
					( attribute "PN" "56"
						( Origin gPackager )
					)
					( objectStatus "J9L2.56" )
				)
				( pin "cb(3)"
					( attribute "PN" "201"
						( Origin gPackager )
					)
					( objectStatus "J9L2.201" )
				)
				( pin "cb(4)"
					( attribute "PN" "47"
						( Origin gPackager )
					)
					( objectStatus "J9L2.47" )
				)
				( pin "cb(5)"
					( attribute "PN" "192"
						( Origin gPackager )
					)
					( objectStatus "J9L2.192" )
				)
				( pin "cb(6)"
					( attribute "PN" "54"
						( Origin gPackager )
					)
					( objectStatus "J9L2.54" )
				)
				( pin "cb(7)"
					( attribute "PN" "199"
						( Origin gPackager )
					)
					( objectStatus "J9L2.199" )
				)
				( pin "ck0n"
					( attribute "PN" "75"
						( Origin gPackager )
					)
					( objectStatus "J9L2.75" )
				)
				( pin "ck0p"
					( attribute "PN" "74"
						( Origin gPackager )
					)
					( objectStatus "J9L2.74" )
				)
				( pin "ck1n"
					( attribute "PN" "219"
						( Origin gPackager )
					)
					( objectStatus "J9L2.219" )
				)
				( pin "ck1p"
					( attribute "PN" "218"
						( Origin gPackager )
					)
					( objectStatus "J9L2.218" )
				)
				( pin "cke(0)"
					( attribute "PN" "60"
						( Origin gPackager )
					)
					( objectStatus "J9L2.60" )
				)
				( pin "cke(1)"
					( attribute "PN" "203"
						( Origin gPackager )
					)
					( objectStatus "J9L2.203" )
				)
				( pin "dq(0)"
					( attribute "PN" "5"
						( Origin gPackager )
					)
					( objectStatus "J9L2.5" )
				)
				( pin "dq(1)"
					( attribute "PN" "150"
						( Origin gPackager )
					)
					( objectStatus "J9L2.150" )
				)
				( pin "dq(2)"
					( attribute "PN" "12"
						( Origin gPackager )
					)
					( objectStatus "J9L2.12" )
				)
				( pin "dq(3)"
					( attribute "PN" "157"
						( Origin gPackager )
					)
					( objectStatus "J9L2.157" )
				)
				( pin "dq(4)"
					( attribute "PN" "3"
						( Origin gPackager )
					)
					( objectStatus "J9L2.3" )
				)
				( pin "dq(5)"
					( attribute "PN" "148"
						( Origin gPackager )
					)
					( objectStatus "J9L2.148" )
				)
				( pin "dq(6)"
					( attribute "PN" "10"
						( Origin gPackager )
					)
					( objectStatus "J9L2.10" )
				)
				( pin "dq(7)"
					( attribute "PN" "155"
						( Origin gPackager )
					)
					( objectStatus "J9L2.155" )
				)
				( pin "dq(8)"
					( attribute "PN" "16"
						( Origin gPackager )
					)
					( objectStatus "J9L2.16" )
				)
				( pin "dq(9)"
					( attribute "PN" "161"
						( Origin gPackager )
					)
					( objectStatus "J9L2.161" )
				)
				( pin "dq(10)"
					( attribute "PN" "23"
						( Origin gPackager )
					)
					( objectStatus "J9L2.23" )
				)
				( pin "dq(11)"
					( attribute "PN" "168"
						( Origin gPackager )
					)
					( objectStatus "J9L2.168" )
				)
				( pin "dq(12)"
					( attribute "PN" "14"
						( Origin gPackager )
					)
					( objectStatus "J9L2.14" )
				)
				( pin "dq(13)"
					( attribute "PN" "159"
						( Origin gPackager )
					)
					( objectStatus "J9L2.159" )
				)
				( pin "dq(14)"
					( attribute "PN" "21"
						( Origin gPackager )
					)
					( objectStatus "J9L2.21" )
				)
				( pin "dq(15)"
					( attribute "PN" "166"
						( Origin gPackager )
					)
					( objectStatus "J9L2.166" )
				)
				( pin "dq(16)"
					( attribute "PN" "27"
						( Origin gPackager )
					)
					( objectStatus "J9L2.27" )
				)
				( pin "dq(17)"
					( attribute "PN" "172"
						( Origin gPackager )
					)
					( objectStatus "J9L2.172" )
				)
				( pin "dq(18)"
					( attribute "PN" "34"
						( Origin gPackager )
					)
					( objectStatus "J9L2.34" )
				)
				( pin "dq(19)"
					( attribute "PN" "179"
						( Origin gPackager )
					)
					( objectStatus "J9L2.179" )
				)
				( pin "dq(20)"
					( attribute "PN" "25"
						( Origin gPackager )
					)
					( objectStatus "J9L2.25" )
				)
				( pin "dq(21)"
					( attribute "PN" "170"
						( Origin gPackager )
					)
					( objectStatus "J9L2.170" )
				)
				( pin "dq(22)"
					( attribute "PN" "32"
						( Origin gPackager )
					)
					( objectStatus "J9L2.32" )
				)
				( pin "dq(23)"
					( attribute "PN" "177"
						( Origin gPackager )
					)
					( objectStatus "J9L2.177" )
				)
				( pin "dq(24)"
					( attribute "PN" "38"
						( Origin gPackager )
					)
					( objectStatus "J9L2.38" )
				)
				( pin "dq(25)"
					( attribute "PN" "183"
						( Origin gPackager )
					)
					( objectStatus "J9L2.183" )
				)
				( pin "dq(26)"
					( attribute "PN" "45"
						( Origin gPackager )
					)
					( objectStatus "J9L2.45" )
				)
				( pin "dq(27)"
					( attribute "PN" "190"
						( Origin gPackager )
					)
					( objectStatus "J9L2.190" )
				)
				( pin "dq(28)"
					( attribute "PN" "36"
						( Origin gPackager )
					)
					( objectStatus "J9L2.36" )
				)
				( pin "dq(29)"
					( attribute "PN" "181"
						( Origin gPackager )
					)
					( objectStatus "J9L2.181" )
				)
				( pin "dq(30)"
					( attribute "PN" "43"
						( Origin gPackager )
					)
					( objectStatus "J9L2.43" )
				)
				( pin "dq(31)"
					( attribute "PN" "188"
						( Origin gPackager )
					)
					( objectStatus "J9L2.188" )
				)
				( pin "dq(32)"
					( attribute "PN" "97"
						( Origin gPackager )
					)
					( objectStatus "J9L2.97" )
				)
				( pin "dq(33)"
					( attribute "PN" "242"
						( Origin gPackager )
					)
					( objectStatus "J9L2.242" )
				)
				( pin "dq(34)"
					( attribute "PN" "104"
						( Origin gPackager )
					)
					( objectStatus "J9L2.104" )
				)
				( pin "dq(35)"
					( attribute "PN" "249"
						( Origin gPackager )
					)
					( objectStatus "J9L2.249" )
				)
				( pin "dq(36)"
					( attribute "PN" "95"
						( Origin gPackager )
					)
					( objectStatus "J9L2.95" )
				)
				( pin "dq(37)"
					( attribute "PN" "240"
						( Origin gPackager )
					)
					( objectStatus "J9L2.240" )
				)
				( pin "dq(38)"
					( attribute "PN" "102"
						( Origin gPackager )
					)
					( objectStatus "J9L2.102" )
				)
				( pin "dq(39)"
					( attribute "PN" "247"
						( Origin gPackager )
					)
					( objectStatus "J9L2.247" )
				)
				( pin "dq(40)"
					( attribute "PN" "108"
						( Origin gPackager )
					)
					( objectStatus "J9L2.108" )
				)
				( pin "dq(41)"
					( attribute "PN" "253"
						( Origin gPackager )
					)
					( objectStatus "J9L2.253" )
				)
				( pin "dq(42)"
					( attribute "PN" "115"
						( Origin gPackager )
					)
					( objectStatus "J9L2.115" )
				)
				( pin "dq(43)"
					( attribute "PN" "260"
						( Origin gPackager )
					)
					( objectStatus "J9L2.260" )
				)
				( pin "dq(44)"
					( attribute "PN" "106"
						( Origin gPackager )
					)
					( objectStatus "J9L2.106" )
				)
				( pin "dq(45)"
					( attribute "PN" "251"
						( Origin gPackager )
					)
					( objectStatus "J9L2.251" )
				)
				( pin "dq(46)"
					( attribute "PN" "113"
						( Origin gPackager )
					)
					( objectStatus "J9L2.113" )
				)
				( pin "dq(47)"
					( attribute "PN" "258"
						( Origin gPackager )
					)
					( objectStatus "J9L2.258" )
				)
				( pin "dq(48)"
					( attribute "PN" "119"
						( Origin gPackager )
					)
					( objectStatus "J9L2.119" )
				)
				( pin "dq(49)"
					( attribute "PN" "264"
						( Origin gPackager )
					)
					( objectStatus "J9L2.264" )
				)
				( pin "dq(50)"
					( attribute "PN" "126"
						( Origin gPackager )
					)
					( objectStatus "J9L2.126" )
				)
				( pin "dq(51)"
					( attribute "PN" "271"
						( Origin gPackager )
					)
					( objectStatus "J9L2.271" )
				)
				( pin "dq(52)"
					( attribute "PN" "117"
						( Origin gPackager )
					)
					( objectStatus "J9L2.117" )
				)
				( pin "dq(53)"
					( attribute "PN" "262"
						( Origin gPackager )
					)
					( objectStatus "J9L2.262" )
				)
				( pin "dq(54)"
					( attribute "PN" "124"
						( Origin gPackager )
					)
					( objectStatus "J9L2.124" )
				)
				( pin "dq(55)"
					( attribute "PN" "269"
						( Origin gPackager )
					)
					( objectStatus "J9L2.269" )
				)
				( pin "dq(56)"
					( attribute "PN" "130"
						( Origin gPackager )
					)
					( objectStatus "J9L2.130" )
				)
				( pin "dq(57)"
					( attribute "PN" "275"
						( Origin gPackager )
					)
					( objectStatus "J9L2.275" )
				)
				( pin "dq(58)"
					( attribute "PN" "137"
						( Origin gPackager )
					)
					( objectStatus "J9L2.137" )
				)
				( pin "dq(59)"
					( attribute "PN" "282"
						( Origin gPackager )
					)
					( objectStatus "J9L2.282" )
				)
				( pin "dq(60)"
					( attribute "PN" "128"
						( Origin gPackager )
					)
					( objectStatus "J9L2.128" )
				)
				( pin "dq(61)"
					( attribute "PN" "273"
						( Origin gPackager )
					)
					( objectStatus "J9L2.273" )
				)
				( pin "dq(62)"
					( attribute "PN" "135"
						( Origin gPackager )
					)
					( objectStatus "J9L2.135" )
				)
				( pin "dq(63)"
					( attribute "PN" "280"
						( Origin gPackager )
					)
					( objectStatus "J9L2.280" )
				)
				( pin "event_n"
					( attribute "PN" "78"
						( Origin gPackager )
					)
					( objectStatus "J9L2.78" )
				)
				( pin "odt(0)"
					( attribute "PN" "87"
						( Origin gPackager )
					)
					( objectStatus "J9L2.87" )
				)
				( pin "odt(1)"
					( attribute "PN" "91"
						( Origin gPackager )
					)
					( objectStatus "J9L2.91" )
				)
				( pin "par"
					( attribute "PN" "222"
						( Origin gPackager )
					)
					( objectStatus "J9L2.222" )
				)
				( pin "reset_n"
					( attribute "PN" "58"
						( Origin gPackager )
					)
					( objectStatus "J9L2.58" )
				)
				( pin "rfu(0)"
					( attribute "PN" "205"
						( Origin gPackager )
					)
					( objectStatus "J9L2.205" )
				)
				( pin "rfu(1)"
					( attribute "PN" "227"
						( Origin gPackager )
					)
					( objectStatus "J9L2.227" )
				)
				( pin "rfu(2)"
					( attribute "PN" "144"
						( Origin gPackager )
					)
					( objectStatus "J9L2.144" )
				)
				( pin "s0_n"
					( attribute "PN" "84"
						( Origin gPackager )
					)
					( objectStatus "J9L2.84" )
				)
				( pin "s1_n"
					( attribute "PN" "89"
						( Origin gPackager )
					)
					( objectStatus "J9L2.89" )
				)
				( pin "s2_n_c(0)"
					( attribute "PN" "93"
						( Origin gPackager )
					)
					( objectStatus "J9L2.93" )
				)
				( pin "s3_n_c(1)"
					( attribute "PN" "237"
						( Origin gPackager )
					)
					( objectStatus "J9L2.237" )
				)
				( pin "sa(0)"
					( attribute "PN" "139"
						( Origin gPackager )
					)
					( objectStatus "J9L2.139" )
				)
				( pin "sa(1)"
					( attribute "PN" "140"
						( Origin gPackager )
					)
					( objectStatus "J9L2.140" )
				)
				( pin "sa(2)"
					( attribute "PN" "238"
						( Origin gPackager )
					)
					( objectStatus "J9L2.238" )
				)
				( pin "save_n_nc"
					( attribute "PN" "230"
						( Origin gPackager )
					)
					( objectStatus "J9L2.230" )
				)
				( pin "scl"
					( attribute "PN" "141"
						( Origin gPackager )
					)
					( objectStatus "J9L2.141" )
				)
				( pin "sda"
					( attribute "PN" "285"
						( Origin gPackager )
					)
					( objectStatus "J9L2.285" )
				)
				( pin "vddspd"
					( attribute "PN" "284"
						( Origin gPackager )
					)
					( objectStatus "J9L2.284" )
				)
				( pin "vrefca"
					( attribute "PN" "146"
						( Origin gPackager )
					)
					( objectStatus "J9L2.146" )
				)
			)
			( gate "@baseboard_fab2_lib.baseboard_fab2(sch_1):page86_i55"
				( attribute "BOM_COST" "MEM"
					( Origin gFrontEnd )
				)
				( attribute "CDS_LIB" "mstr_sconn"
					( Origin gPackager )
				)
				( attribute "CDS_LOCATION" "J9L2"
					( Origin gPackager )
				)
				( attribute "CDS_SEC" "4"
					( Origin gPackager )
				)
				( attribute "LOCATION" "J9L2"
					( Origin gFrontEnd )
				)
				( attribute "MATERIAL" "SCONN"
					( Origin gFrontEnd )
				)
				( attribute "PACK_TYPE" "PIP"
					( Origin gFrontEnd )
				)
				( attribute "PART_NUMBER" "H44441-003"
					( Origin gFrontEnd )
				)
				( attribute "PHYS_PAGE" "86"
					( Origin gFrontEnd )
				)
				( attribute "ROOM" "DDR4_CH_L"
					( Origin gFrontEnd )
				)
				( attribute "ROT" "0"
					( Origin gFrontEnd )
				)
				( attribute "SEC" "4"
					( Origin gFrontEnd )
				)
				( attribute "SEC_TYPE" "PIP"
					( Origin gFrontEnd )
				)
				( attribute "VER" "4"
					( Origin gFrontEnd )
				)
				( attribute "XY" "(1375,1725)"
					( Origin gFrontEnd )
				)
				( attribute "CHIPS_PART_NAME" "SCONN288_H44441003"
					( Origin gPackager )
				)
				( attribute "CDS_PART_NAME" "SCONN288_H44441003_PIP-SCONN,HA"
					( Origin gPackager )
				)
				( objectStatus "J9L2" )
				( pin "\12v\(0)"
					( attribute "PN" "145"
						( Origin gPackager )
					)
					( objectStatus "J9L2.145" )
				)
				( pin "\12v\(1)"
					( attribute "PN" "1"
						( Origin gPackager )
					)
					( objectStatus "J9L2.1" )
				)
				( pin "vdd(0)"
					( attribute "PN" "236"
						( Origin gPackager )
					)
					( objectStatus "J9L2.236" )
				)
				( pin "vdd(1)"
					( attribute "PN" "233"
						( Origin gPackager )
					)
					( objectStatus "J9L2.233" )
				)
				( pin "vdd(2)"
					( attribute "PN" "231"
						( Origin gPackager )
					)
					( objectStatus "J9L2.231" )
				)
				( pin "vdd(3)"
					( attribute "PN" "229"
						( Origin gPackager )
					)
					( objectStatus "J9L2.229" )
				)
				( pin "vdd(4)"
					( attribute "PN" "226"
						( Origin gPackager )
					)
					( objectStatus "J9L2.226" )
				)
				( pin "vdd(5)"
					( attribute "PN" "223"
						( Origin gPackager )
					)
					( objectStatus "J9L2.223" )
				)
				( pin "vdd(6)"
					( attribute "PN" "220"
						( Origin gPackager )
					)
					( objectStatus "J9L2.220" )
				)
				( pin "vdd(7)"
					( attribute "PN" "217"
						( Origin gPackager )
					)
					( objectStatus "J9L2.217" )
				)
				( pin "vdd(8)"
					( attribute "PN" "215"
						( Origin gPackager )
					)
					( objectStatus "J9L2.215" )
				)
				( pin "vdd(9)"
					( attribute "PN" "212"
						( Origin gPackager )
					)
					( objectStatus "J9L2.212" )
				)
				( pin "vdd(10)"
					( attribute "PN" "209"
						( Origin gPackager )
					)
					( objectStatus "J9L2.209" )
				)
				( pin "vdd(11)"
					( attribute "PN" "206"
						( Origin gPackager )
					)
					( objectStatus "J9L2.206" )
				)
				( pin "vdd(12)"
					( attribute "PN" "204"
						( Origin gPackager )
					)
					( objectStatus "J9L2.204" )
				)
				( pin "vdd(13)"
					( attribute "PN" "92"
						( Origin gPackager )
					)
					( objectStatus "J9L2.92" )
				)
				( pin "vdd(14)"
					( attribute "PN" "90"
						( Origin gPackager )
					)
					( objectStatus "J9L2.90" )
				)
				( pin "vdd(15)"
					( attribute "PN" "88"
						( Origin gPackager )
					)
					( objectStatus "J9L2.88" )
				)
				( pin "vdd(16)"
					( attribute "PN" "85"
						( Origin gPackager )
					)
					( objectStatus "J9L2.85" )
				)
				( pin "vdd(17)"
					( attribute "PN" "83"
						( Origin gPackager )
					)
					( objectStatus "J9L2.83" )
				)
				( pin "vdd(18)"
					( attribute "PN" "80"
						( Origin gPackager )
					)
					( objectStatus "J9L2.80" )
				)
				( pin "vdd(19)"
					( attribute "PN" "76"
						( Origin gPackager )
					)
					( objectStatus "J9L2.76" )
				)
				( pin "vdd(20)"
					( attribute "PN" "73"
						( Origin gPackager )
					)
					( objectStatus "J9L2.73" )
				)
				( pin "vdd(21)"
					( attribute "PN" "70"
						( Origin gPackager )
					)
					( objectStatus "J9L2.70" )
				)
				( pin "vdd(22)"
					( attribute "PN" "67"
						( Origin gPackager )
					)
					( objectStatus "J9L2.67" )
				)
				( pin "vdd(23)"
					( attribute "PN" "64"
						( Origin gPackager )
					)
					( objectStatus "J9L2.64" )
				)
				( pin "vdd(24)"
					( attribute "PN" "61"
						( Origin gPackager )
					)
					( objectStatus "J9L2.61" )
				)
				( pin "vdd(25)"
					( attribute "PN" "59"
						( Origin gPackager )
					)
					( objectStatus "J9L2.59" )
				)
				( pin "vpp(0)"
					( attribute "PN" "287"
						( Origin gPackager )
					)
					( objectStatus "J9L2.287" )
				)
				( pin "vpp(1)"
					( attribute "PN" "286"
						( Origin gPackager )
					)
					( objectStatus "J9L2.286" )
				)
				( pin "vpp(2)"
					( attribute "PN" "288"
						( Origin gPackager )
					)
					( objectStatus "J9L2.288" )
				)
				( pin "vpp(3)"
					( attribute "PN" "143"
						( Origin gPackager )
					)
					( objectStatus "J9L2.143" )
				)
				( pin "vpp(4)"
					( attribute "PN" "142"
						( Origin gPackager )
					)
					( objectStatus "J9L2.142" )
				)
				( pin "vtt(0)"
					( attribute "PN" "221"
						( Origin gPackager )
					)
					( objectStatus "J9L2.221" )
				)
				( pin "vtt(1)"
					( attribute "PN" "77"
						( Origin gPackager )
					)
					( objectStatus "J9L2.77" )
				)
			)
			( gate "@baseboard_fab2_lib.baseboard_fab2(sch_1):page86_i100"
				( attribute "BOM_COST" "MEM"
					( Origin gFrontEnd )
				)
				( attribute "CDS_LIB" "mstr_sconn"
					( Origin gPackager )
				)
				( attribute "CDS_LOCATION" "J9L2"
					( Origin gPackager )
				)
				( attribute "CDS_SEC" "2"
					( Origin gPackager )
				)
				( attribute "LOCATION" "J9L2"
					( Origin gFrontEnd )
				)
				( attribute "MATERIAL" "SCONN"
					( Origin gFrontEnd )
				)
				( attribute "PACK_TYPE" "PIP"
					( Origin gFrontEnd )
				)
				( attribute "PART_NUMBER" "H44441-003"
					( Origin gFrontEnd )
				)
				( attribute "PHYS_PAGE" "86"
					( Origin gFrontEnd )
				)
				( attribute "ROOM" "DDR4_CH_L"
					( Origin gFrontEnd )
				)
				( attribute "ROT" "0"
					( Origin gFrontEnd )
				)
				( attribute "SEC" "2"
					( Origin gFrontEnd )
				)
				( attribute "SEC_TYPE" "PIP"
					( Origin gFrontEnd )
				)
				( attribute "VER" "2"
					( Origin gFrontEnd )
				)
				( attribute "XY" "(1625,3975)"
					( Origin gFrontEnd )
				)
				( attribute "CHIPS_PART_NAME" "SCONN288_H44441003"
					( Origin gPackager )
				)
				( attribute "CDS_PART_NAME" "SCONN288_H44441003_PIP-SCONN,HA"
					( Origin gPackager )
				)
				( objectStatus "J9L2" )
				( pin "dqs0n"
					( attribute "PN" "152"
						( Origin gPackager )
					)
					( objectStatus "J9L2.152" )
				)
				( pin "dqs0p"
					( attribute "PN" "153"
						( Origin gPackager )
					)
					( objectStatus "J9L2.153" )
				)
				( pin "dqs1n"
					( attribute "PN" "163"
						( Origin gPackager )
					)
					( objectStatus "J9L2.163" )
				)
				( pin "dqs1p"
					( attribute "PN" "164"
						( Origin gPackager )
					)
					( objectStatus "J9L2.164" )
				)
				( pin "dqs2n"
					( attribute "PN" "174"
						( Origin gPackager )
					)
					( objectStatus "J9L2.174" )
				)
				( pin "dqs2p"
					( attribute "PN" "175"
						( Origin gPackager )
					)
					( objectStatus "J9L2.175" )
				)
				( pin "dqs3n"
					( attribute "PN" "185"
						( Origin gPackager )
					)
					( objectStatus "J9L2.185" )
				)
				( pin "dqs3p"
					( attribute "PN" "186"
						( Origin gPackager )
					)
					( objectStatus "J9L2.186" )
				)
				( pin "dqs4n"
					( attribute "PN" "244"
						( Origin gPackager )
					)
					( objectStatus "J9L2.244" )
				)
				( pin "dqs4p"
					( attribute "PN" "245"
						( Origin gPackager )
					)
					( objectStatus "J9L2.245" )
				)
				( pin "dqs5n"
					( attribute "PN" "255"
						( Origin gPackager )
					)
					( objectStatus "J9L2.255" )
				)
				( pin "dqs5p"
					( attribute "PN" "256"
						( Origin gPackager )
					)
					( objectStatus "J9L2.256" )
				)
				( pin "dqs6n"
					( attribute "PN" "266"
						( Origin gPackager )
					)
					( objectStatus "J9L2.266" )
				)
				( pin "dqs6p"
					( attribute "PN" "267"
						( Origin gPackager )
					)
					( objectStatus "J9L2.267" )
				)
				( pin "dqs7n"
					( attribute "PN" "277"
						( Origin gPackager )
					)
					( objectStatus "J9L2.277" )
				)
				( pin "dqs7p"
					( attribute "PN" "278"
						( Origin gPackager )
					)
					( objectStatus "J9L2.278" )
				)
				( pin "dqs8n"
					( attribute "PN" "196"
						( Origin gPackager )
					)
					( objectStatus "J9L2.196" )
				)
				( pin "dqs8p"
					( attribute "PN" "197"
						( Origin gPackager )
					)
					( objectStatus "J9L2.197" )
				)
				( pin "dqs9n"
					( attribute "PN" "8"
						( Origin gPackager )
					)
					( objectStatus "J9L2.8" )
				)
				( pin "dqs9p"
					( attribute "PN" "7"
						( Origin gPackager )
					)
					( objectStatus "J9L2.7" )
				)
				( pin "dqs10n"
					( attribute "PN" "19"
						( Origin gPackager )
					)
					( objectStatus "J9L2.19" )
				)
				( pin "dqs10p"
					( attribute "PN" "18"
						( Origin gPackager )
					)
					( objectStatus "J9L2.18" )
				)
				( pin "dqs11n"
					( attribute "PN" "30"
						( Origin gPackager )
					)
					( objectStatus "J9L2.30" )
				)
				( pin "dqs11p"
					( attribute "PN" "29"
						( Origin gPackager )
					)
					( objectStatus "J9L2.29" )
				)
				( pin "dqs12n"
					( attribute "PN" "41"
						( Origin gPackager )
					)
					( objectStatus "J9L2.41" )
				)
				( pin "dqs12p"
					( attribute "PN" "40"
						( Origin gPackager )
					)
					( objectStatus "J9L2.40" )
				)
				( pin "dqs13n"
					( attribute "PN" "100"
						( Origin gPackager )
					)
					( objectStatus "J9L2.100" )
				)
				( pin "dqs13p"
					( attribute "PN" "99"
						( Origin gPackager )
					)
					( objectStatus "J9L2.99" )
				)
				( pin "dqs14n"
					( attribute "PN" "111"
						( Origin gPackager )
					)
					( objectStatus "J9L2.111" )
				)
				( pin "dqs14p"
					( attribute "PN" "110"
						( Origin gPackager )
					)
					( objectStatus "J9L2.110" )
				)
				( pin "dqs15n"
					( attribute "PN" "122"
						( Origin gPackager )
					)
					( objectStatus "J9L2.122" )
				)
				( pin "dqs15p"
					( attribute "PN" "121"
						( Origin gPackager )
					)
					( objectStatus "J9L2.121" )
				)
				( pin "dqs16n"
					( attribute "PN" "133"
						( Origin gPackager )
					)
					( objectStatus "J9L2.133" )
				)
				( pin "dqs16p"
					( attribute "PN" "132"
						( Origin gPackager )
					)
					( objectStatus "J9L2.132" )
				)
				( pin "dqs17n"
					( attribute "PN" "52"
						( Origin gPackager )
					)
					( objectStatus "J9L2.52" )
				)
				( pin "dqs17p"
					( attribute "PN" "51"
						( Origin gPackager )
					)
					( objectStatus "J9L2.51" )
				)
			)
			( gate "@baseboard_fab2_lib.baseboard_fab2(sch_1):page86_i138"
				( attribute "BOM_COST" "MEM"
					( Origin gFrontEnd )
				)
				( attribute "CDS_LIB" "mstr_sconn"
					( Origin gPackager )
				)
				( attribute "CDS_LOCATION" "J9L2"
					( Origin gPackager )
				)
				( attribute "CDS_SEC" "3"
					( Origin gPackager )
				)
				( attribute "LOCATION" "J9L2"
					( Origin gFrontEnd )
				)
				( attribute "MATERIAL" "SCONN"
					( Origin gFrontEnd )
				)
				( attribute "PACK_TYPE" "PIP"
					( Origin gFrontEnd )
				)
				( attribute "PART_NUMBER" "H44441-003"
					( Origin gFrontEnd )
				)
				( attribute "PHYS_PAGE" "86"
					( Origin gFrontEnd )
				)
				( attribute "ROOM" "DDR4_CH_L"
					( Origin gFrontEnd )
				)
				( attribute "ROT" "0"
					( Origin gFrontEnd )
				)
				( attribute "SEC" "3"
					( Origin gFrontEnd )
				)
				( attribute "SEC_TYPE" "PIP"
					( Origin gFrontEnd )
				)
				( attribute "VER" "3"
					( Origin gFrontEnd )
				)
				( attribute "XY" "(3425,2075)"
					( Origin gFrontEnd )
				)
				( attribute "CHIPS_PART_NAME" "SCONN288_H44441003"
					( Origin gPackager )
				)
				( attribute "CDS_PART_NAME" "SCONN288_H44441003_PIP-SCONN,HA"
					( Origin gPackager )
				)
				( objectStatus "J9L2" )
				( pin "vss(0)"
					( attribute "PN" "283"
						( Origin gPackager )
					)
					( objectStatus "J9L2.283" )
				)
				( pin "vss(1)"
					( attribute "PN" "281"
						( Origin gPackager )
					)
					( objectStatus "J9L2.281" )
				)
				( pin "vss(2)"
					( attribute "PN" "279"
						( Origin gPackager )
					)
					( objectStatus "J9L2.279" )
				)
				( pin "vss(3)"
					( attribute "PN" "276"
						( Origin gPackager )
					)
					( objectStatus "J9L2.276" )
				)
				( pin "vss(4)"
					( attribute "PN" "274"
						( Origin gPackager )
					)
					( objectStatus "J9L2.274" )
				)
				( pin "vss(5)"
					( attribute "PN" "272"
						( Origin gPackager )
					)
					( objectStatus "J9L2.272" )
				)
				( pin "vss(6)"
					( attribute "PN" "270"
						( Origin gPackager )
					)
					( objectStatus "J9L2.270" )
				)
				( pin "vss(7)"
					( attribute "PN" "268"
						( Origin gPackager )
					)
					( objectStatus "J9L2.268" )
				)
				( pin "vss(8)"
					( attribute "PN" "265"
						( Origin gPackager )
					)
					( objectStatus "J9L2.265" )
				)
				( pin "vss(9)"
					( attribute "PN" "263"
						( Origin gPackager )
					)
					( objectStatus "J9L2.263" )
				)
				( pin "vss(10)"
					( attribute "PN" "261"
						( Origin gPackager )
					)
					( objectStatus "J9L2.261" )
				)
				( pin "vss(11)"
					( attribute "PN" "259"
						( Origin gPackager )
					)
					( objectStatus "J9L2.259" )
				)
				( pin "vss(12)"
					( attribute "PN" "257"
						( Origin gPackager )
					)
					( objectStatus "J9L2.257" )
				)
				( pin "vss(13)"
					( attribute "PN" "254"
						( Origin gPackager )
					)
					( objectStatus "J9L2.254" )
				)
				( pin "vss(14)"
					( attribute "PN" "252"
						( Origin gPackager )
					)
					( objectStatus "J9L2.252" )
				)
				( pin "vss(15)"
					( attribute "PN" "250"
						( Origin gPackager )
					)
					( objectStatus "J9L2.250" )
				)
				( pin "vss(16)"
					( attribute "PN" "248"
						( Origin gPackager )
					)
					( objectStatus "J9L2.248" )
				)
				( pin "vss(17)"
					( attribute "PN" "246"
						( Origin gPackager )
					)
					( objectStatus "J9L2.246" )
				)
				( pin "vss(18)"
					( attribute "PN" "243"
						( Origin gPackager )
					)
					( objectStatus "J9L2.243" )
				)
				( pin "vss(19)"
					( attribute "PN" "241"
						( Origin gPackager )
					)
					( objectStatus "J9L2.241" )
				)
				( pin "vss(20)"
					( attribute "PN" "239"
						( Origin gPackager )
					)
					( objectStatus "J9L2.239" )
				)
				( pin "vss(21)"
					( attribute "PN" "202"
						( Origin gPackager )
					)
					( objectStatus "J9L2.202" )
				)
				( pin "vss(22)"
					( attribute "PN" "200"
						( Origin gPackager )
					)
					( objectStatus "J9L2.200" )
				)
				( pin "vss(23)"
					( attribute "PN" "198"
						( Origin gPackager )
					)
					( objectStatus "J9L2.198" )
				)
				( pin "vss(24)"
					( attribute "PN" "195"
						( Origin gPackager )
					)
					( objectStatus "J9L2.195" )
				)
				( pin "vss(25)"
					( attribute "PN" "193"
						( Origin gPackager )
					)
					( objectStatus "J9L2.193" )
				)
				( pin "vss(26)"
					( attribute "PN" "191"
						( Origin gPackager )
					)
					( objectStatus "J9L2.191" )
				)
				( pin "vss(27)"
					( attribute "PN" "189"
						( Origin gPackager )
					)
					( objectStatus "J9L2.189" )
				)
				( pin "vss(28)"
					( attribute "PN" "187"
						( Origin gPackager )
					)
					( objectStatus "J9L2.187" )
				)
				( pin "vss(29)"
					( attribute "PN" "184"
						( Origin gPackager )
					)
					( objectStatus "J9L2.184" )
				)
				( pin "vss(30)"
					( attribute "PN" "182"
						( Origin gPackager )
					)
					( objectStatus "J9L2.182" )
				)
				( pin "vss(31)"
					( attribute "PN" "180"
						( Origin gPackager )
					)
					( objectStatus "J9L2.180" )
				)
				( pin "vss(32)"
					( attribute "PN" "178"
						( Origin gPackager )
					)
					( objectStatus "J9L2.178" )
				)
				( pin "vss(33)"
					( attribute "PN" "176"
						( Origin gPackager )
					)
					( objectStatus "J9L2.176" )
				)
				( pin "vss(34)"
					( attribute "PN" "173"
						( Origin gPackager )
					)
					( objectStatus "J9L2.173" )
				)
				( pin "vss(35)"
					( attribute "PN" "171"
						( Origin gPackager )
					)
					( objectStatus "J9L2.171" )
				)
				( pin "vss(36)"
					( attribute "PN" "169"
						( Origin gPackager )
					)
					( objectStatus "J9L2.169" )
				)
				( pin "vss(37)"
					( attribute "PN" "167"
						( Origin gPackager )
					)
					( objectStatus "J9L2.167" )
				)
				( pin "vss(38)"
					( attribute "PN" "165"
						( Origin gPackager )
					)
					( objectStatus "J9L2.165" )
				)
				( pin "vss(39)"
					( attribute "PN" "162"
						( Origin gPackager )
					)
					( objectStatus "J9L2.162" )
				)
				( pin "vss(40)"
					( attribute "PN" "160"
						( Origin gPackager )
					)
					( objectStatus "J9L2.160" )
				)
				( pin "vss(41)"
					( attribute "PN" "158"
						( Origin gPackager )
					)
					( objectStatus "J9L2.158" )
				)
				( pin "vss(42)"
					( attribute "PN" "156"
						( Origin gPackager )
					)
					( objectStatus "J9L2.156" )
				)
				( pin "vss(43)"
					( attribute "PN" "154"
						( Origin gPackager )
					)
					( objectStatus "J9L2.154" )
				)
				( pin "vss(44)"
					( attribute "PN" "151"
						( Origin gPackager )
					)
					( objectStatus "J9L2.151" )
				)
				( pin "vss(45)"
					( attribute "PN" "149"
						( Origin gPackager )
					)
					( objectStatus "J9L2.149" )
				)
				( pin "vss(46)"
					( attribute "PN" "147"
						( Origin gPackager )
					)
					( objectStatus "J9L2.147" )
				)
				( pin "vss(47)"
					( attribute "PN" "138"
						( Origin gPackager )
					)
					( objectStatus "J9L2.138" )
				)
				( pin "vss(48)"
					( attribute "PN" "136"
						( Origin gPackager )
					)
					( objectStatus "J9L2.136" )
				)
				( pin "vss(49)"
					( attribute "PN" "134"
						( Origin gPackager )
					)
					( objectStatus "J9L2.134" )
				)
				( pin "vss(50)"
					( attribute "PN" "131"
						( Origin gPackager )
					)
					( objectStatus "J9L2.131" )
				)
				( pin "vss(51)"
					( attribute "PN" "129"
						( Origin gPackager )
					)
					( objectStatus "J9L2.129" )
				)
				( pin "vss(52)"
					( attribute "PN" "127"
						( Origin gPackager )
					)
					( objectStatus "J9L2.127" )
				)
				( pin "vss(53)"
					( attribute "PN" "125"
						( Origin gPackager )
					)
					( objectStatus "J9L2.125" )
				)
				( pin "vss(54)"
					( attribute "PN" "123"
						( Origin gPackager )
					)
					( objectStatus "J9L2.123" )
				)
				( pin "vss(55)"
					( attribute "PN" "120"
						( Origin gPackager )
					)
					( objectStatus "J9L2.120" )
				)
				( pin "vss(56)"
					( attribute "PN" "118"
						( Origin gPackager )
					)
					( objectStatus "J9L2.118" )
				)
				( pin "vss(57)"
					( attribute "PN" "116"
						( Origin gPackager )
					)
					( objectStatus "J9L2.116" )
				)
				( pin "vss(58)"
					( attribute "PN" "114"
						( Origin gPackager )
					)
					( objectStatus "J9L2.114" )
				)
				( pin "vss(59)"
					( attribute "PN" "112"
						( Origin gPackager )
					)
					( objectStatus "J9L2.112" )
				)
				( pin "vss(60)"
					( attribute "PN" "109"
						( Origin gPackager )
					)
					( objectStatus "J9L2.109" )
				)
				( pin "vss(61)"
					( attribute "PN" "107"
						( Origin gPackager )
					)
					( objectStatus "J9L2.107" )
				)
				( pin "vss(62)"
					( attribute "PN" "105"
						( Origin gPackager )
					)
					( objectStatus "J9L2.105" )
				)
				( pin "vss(63)"
					( attribute "PN" "103"
						( Origin gPackager )
					)
					( objectStatus "J9L2.103" )
				)
				( pin "vss(64)"
					( attribute "PN" "101"
						( Origin gPackager )
					)
					( objectStatus "J9L2.101" )
				)
				( pin "vss(65)"
					( attribute "PN" "98"
						( Origin gPackager )
					)
					( objectStatus "J9L2.98" )
				)
				( pin "vss(66)"
					( attribute "PN" "96"
						( Origin gPackager )
					)
					( objectStatus "J9L2.96" )
				)
				( pin "vss(67)"
					( attribute "PN" "94"
						( Origin gPackager )
					)
					( objectStatus "J9L2.94" )
				)
				( pin "vss(68)"
					( attribute "PN" "57"
						( Origin gPackager )
					)
					( objectStatus "J9L2.57" )
				)
				( pin "vss(69)"
					( attribute "PN" "55"
						( Origin gPackager )
					)
					( objectStatus "J9L2.55" )
				)
				( pin "vss(70)"
					( attribute "PN" "53"
						( Origin gPackager )
					)
					( objectStatus "J9L2.53" )
				)
				( pin "vss(71)"
					( attribute "PN" "50"
						( Origin gPackager )
					)
					( objectStatus "J9L2.50" )
				)
				( pin "vss(72)"
					( attribute "PN" "48"
						( Origin gPackager )
					)
					( objectStatus "J9L2.48" )
				)
				( pin "vss(73)"
					( attribute "PN" "46"
						( Origin gPackager )
					)
					( objectStatus "J9L2.46" )
				)
				( pin "vss(74)"
					( attribute "PN" "44"
						( Origin gPackager )
					)
					( objectStatus "J9L2.44" )
				)
				( pin "vss(75)"
					( attribute "PN" "42"
						( Origin gPackager )
					)
					( objectStatus "J9L2.42" )
				)
				( pin "vss(76)"
					( attribute "PN" "39"
						( Origin gPackager )
					)
					( objectStatus "J9L2.39" )
				)
				( pin "vss(77)"
					( attribute "PN" "37"
						( Origin gPackager )
					)
					( objectStatus "J9L2.37" )
				)
				( pin "vss(78)"
					( attribute "PN" "35"
						( Origin gPackager )
					)
					( objectStatus "J9L2.35" )
				)
				( pin "vss(79)"
					( attribute "PN" "33"
						( Origin gPackager )
					)
					( objectStatus "J9L2.33" )
				)
				( pin "vss(80)"
					( attribute "PN" "31"
						( Origin gPackager )
					)
					( objectStatus "J9L2.31" )
				)
				( pin "vss(81)"
					( attribute "PN" "28"
						( Origin gPackager )
					)
					( objectStatus "J9L2.28" )
				)
				( pin "vss(82)"
					( attribute "PN" "26"
						( Origin gPackager )
					)
					( objectStatus "J9L2.26" )
				)
				( pin "vss(83)"
					( attribute "PN" "24"
						( Origin gPackager )
					)
					( objectStatus "J9L2.24" )
				)
				( pin "vss(84)"
					( attribute "PN" "22"
						( Origin gPackager )
					)
					( objectStatus "J9L2.22" )
				)
				( pin "vss(85)"
					( attribute "PN" "20"
						( Origin gPackager )
					)
					( objectStatus "J9L2.20" )
				)
				( pin "vss(86)"
					( attribute "PN" "17"
						( Origin gPackager )
					)
					( objectStatus "J9L2.17" )
				)
				( pin "vss(87)"
					( attribute "PN" "15"
						( Origin gPackager )
					)
					( objectStatus "J9L2.15" )
				)
				( pin "vss(88)"
					( attribute "PN" "13"
						( Origin gPackager )
					)
					( objectStatus "J9L2.13" )
				)
				( pin "vss(89)"
					( attribute "PN" "11"
						( Origin gPackager )
					)
					( objectStatus "J9L2.11" )
				)
				( pin "vss(90)"
					( attribute "PN" "9"
						( Origin gPackager )
					)
					( objectStatus "J9L2.9" )
				)
				( pin "vss(91)"
					( attribute "PN" "6"
						( Origin gPackager )
					)
					( objectStatus "J9L2.6" )
				)
				( pin "vss(92)"
					( attribute "PN" "4"
						( Origin gPackager )
					)
					( objectStatus "J9L2.4" )
				)
				( pin "vss(93)"
					( attribute "PN" "2"
						( Origin gPackager )
					)
					( objectStatus "J9L2.2" )
				)
			)
			( gate "@baseboard_fab2_lib.baseboard_fab2(sch_1):page86_i182"
				( attribute "BOM_COST" "MEM"
					( Origin gFrontEnd )
				)
				( attribute "CDS_LIB" "dev_discrete"
					( Origin gPackager )
				)
				( attribute "CDS_LOCATION" "C1A17"
					( Origin gPackager )
				)
				( attribute "CDS_SEC" "1"
					( Origin gPackager )
				)
				( attribute "LOCATION" "C1A17"
					( Origin gFrontEnd )
				)
				( attribute "MATERIAL" "X7R"
					( Origin gFrontEnd )
				)
				( attribute "PACK_TYPE" "0402V"
					( Origin gFrontEnd )
				)
				( attribute "PART_NUMBER" "A36096-045"
					( Origin gFrontEnd )
				)
				( attribute "PHYS_PAGE" "86"
					( Origin gFrontEnd )
				)
				( attribute "ROOM" "DDR4_CH_D"
					( Origin gFrontEnd )
				)
				( attribute "ROT" "2"
					( Origin gFrontEnd )
				)
				( attribute "SEC" "1"
					( Origin gPackager )
				)
				( attribute "TOLERANCE" "10%"
					( Origin gFrontEnd )
				)
				( attribute "VALUE" "0.01UF"
					( Origin gFrontEnd )
				)
				( attribute "VER" "1"
					( Origin gFrontEnd )
				)
				( attribute "VOLTAGE" "25V"
					( Units "uVoltage" "V" 1.000000)
					( Origin gFrontEnd )
				)
				( attribute "XY" "(-3025,1225)"
					( Origin gFrontEnd )
				)
				( attribute "CHIPS_PART_NAME" "CAP_A"
					( Origin gPackager )
				)
				( attribute "CDS_PART_NAME" "CAP_A_0402V-0.01UF,25V,10%,X7RA"
					( Origin gPackager )
				)
				( objectStatus "C1A17" )
				( pin "a"
					( attribute "PN" "1"
						( Origin gPackager )
					)
					( objectStatus "C1A17.1" )
				)
				( pin "b"
					( attribute "PN" "2"
						( Origin gPackager )
					)
					( objectStatus "C1A17.2" )
				)
			)
			( gate "@baseboard_fab2_lib.baseboard_fab2(sch_1):page87_i169"
				( attribute "BOM_COST" "MEM"
					( Origin gFrontEnd )
				)
				( attribute "CDS_LIB" "mstr_sconn"
					( Origin gPackager )
				)
				( attribute "CDS_LOCATION" "J1A1"
					( Origin gPackager )
				)
				( attribute "CDS_SEC" "4"
					( Origin gPackager )
				)
				( attribute "LOCATION" "J1A1"
					( Origin gFrontEnd )
				)
				( attribute "MATERIAL" "SCONN"
					( Origin gFrontEnd )
				)
				( attribute "PACK_TYPE" "PIP"
					( Origin gFrontEnd )
				)
				( attribute "PART_NUMBER" "H44441-004"
					( Origin gFrontEnd )
				)
				( attribute "PHYS_PAGE" "87"
					( Origin gFrontEnd )
				)
				( attribute "ROOM" "DDR4_CH_M"
					( Origin gFrontEnd )
				)
				( attribute "ROT" "0"
					( Origin gFrontEnd )
				)
				( attribute "SEC" "4"
					( Origin gFrontEnd )
				)
				( attribute "SEC_TYPE" "PIP"
					( Origin gFrontEnd )
				)
				( attribute "VER" "4"
					( Origin gFrontEnd )
				)
				( attribute "XY" "(-400,2050)"
					( Origin gFrontEnd )
				)
				( attribute "CHIPS_PART_NAME" "SCONN288_H44441004"
					( Origin gPackager )
				)
				( attribute "CDS_PART_NAME" "SCONN288_H44441004_PIP-SCONN,HA"
					( Origin gPackager )
				)
				( objectStatus "J1A1" )
				( pin "\12v\(0)"
					( attribute "PN" "145"
						( Origin gPackager )
					)
					( objectStatus "J1A1.145" )
				)
				( pin "\12v\(1)"
					( attribute "PN" "1"
						( Origin gPackager )
					)
					( objectStatus "J1A1.1" )
				)
				( pin "vdd(0)"
					( attribute "PN" "236"
						( Origin gPackager )
					)
					( objectStatus "J1A1.236" )
				)
				( pin "vdd(1)"
					( attribute "PN" "233"
						( Origin gPackager )
					)
					( objectStatus "J1A1.233" )
				)
				( pin "vdd(2)"
					( attribute "PN" "231"
						( Origin gPackager )
					)
					( objectStatus "J1A1.231" )
				)
				( pin "vdd(3)"
					( attribute "PN" "229"
						( Origin gPackager )
					)
					( objectStatus "J1A1.229" )
				)
				( pin "vdd(4)"
					( attribute "PN" "226"
						( Origin gPackager )
					)
					( objectStatus "J1A1.226" )
				)
				( pin "vdd(5)"
					( attribute "PN" "223"
						( Origin gPackager )
					)
					( objectStatus "J1A1.223" )
				)
				( pin "vdd(6)"
					( attribute "PN" "220"
						( Origin gPackager )
					)
					( objectStatus "J1A1.220" )
				)
				( pin "vdd(7)"
					( attribute "PN" "217"
						( Origin gPackager )
					)
					( objectStatus "J1A1.217" )
				)
				( pin "vdd(8)"
					( attribute "PN" "215"
						( Origin gPackager )
					)
					( objectStatus "J1A1.215" )
				)
				( pin "vdd(9)"
					( attribute "PN" "212"
						( Origin gPackager )
					)
					( objectStatus "J1A1.212" )
				)
				( pin "vdd(10)"
					( attribute "PN" "209"
						( Origin gPackager )
					)
					( objectStatus "J1A1.209" )
				)
				( pin "vdd(11)"
					( attribute "PN" "206"
						( Origin gPackager )
					)
					( objectStatus "J1A1.206" )
				)
				( pin "vdd(12)"
					( attribute "PN" "204"
						( Origin gPackager )
					)
					( objectStatus "J1A1.204" )
				)
				( pin "vdd(13)"
					( attribute "PN" "92"
						( Origin gPackager )
					)
					( objectStatus "J1A1.92" )
				)
				( pin "vdd(14)"
					( attribute "PN" "90"
						( Origin gPackager )
					)
					( objectStatus "J1A1.90" )
				)
				( pin "vdd(15)"
					( attribute "PN" "88"
						( Origin gPackager )
					)
					( objectStatus "J1A1.88" )
				)
				( pin "vdd(16)"
					( attribute "PN" "85"
						( Origin gPackager )
					)
					( objectStatus "J1A1.85" )
				)
				( pin "vdd(17)"
					( attribute "PN" "83"
						( Origin gPackager )
					)
					( objectStatus "J1A1.83" )
				)
				( pin "vdd(18)"
					( attribute "PN" "80"
						( Origin gPackager )
					)
					( objectStatus "J1A1.80" )
				)
				( pin "vdd(19)"
					( attribute "PN" "76"
						( Origin gPackager )
					)
					( objectStatus "J1A1.76" )
				)
				( pin "vdd(20)"
					( attribute "PN" "73"
						( Origin gPackager )
					)
					( objectStatus "J1A1.73" )
				)
				( pin "vdd(21)"
					( attribute "PN" "70"
						( Origin gPackager )
					)
					( objectStatus "J1A1.70" )
				)
				( pin "vdd(22)"
					( attribute "PN" "67"
						( Origin gPackager )
					)
					( objectStatus "J1A1.67" )
				)
				( pin "vdd(23)"
					( attribute "PN" "64"
						( Origin gPackager )
					)
					( objectStatus "J1A1.64" )
				)
				( pin "vdd(24)"
					( attribute "PN" "61"
						( Origin gPackager )
					)
					( objectStatus "J1A1.61" )
				)
				( pin "vdd(25)"
					( attribute "PN" "59"
						( Origin gPackager )
					)
					( objectStatus "J1A1.59" )
				)
				( pin "vpp(0)"
					( attribute "PN" "287"
						( Origin gPackager )
					)
					( objectStatus "J1A1.287" )
				)
				( pin "vpp(1)"
					( attribute "PN" "286"
						( Origin gPackager )
					)
					( objectStatus "J1A1.286" )
				)
				( pin "vpp(2)"
					( attribute "PN" "288"
						( Origin gPackager )
					)
					( objectStatus "J1A1.288" )
				)
				( pin "vpp(3)"
					( attribute "PN" "143"
						( Origin gPackager )
					)
					( objectStatus "J1A1.143" )
				)
				( pin "vpp(4)"
					( attribute "PN" "142"
						( Origin gPackager )
					)
					( objectStatus "J1A1.142" )
				)
				( pin "vtt(0)"
					( attribute "PN" "221"
						( Origin gPackager )
					)
					( objectStatus "J1A1.221" )
				)
				( pin "vtt(1)"
					( attribute "PN" "77"
						( Origin gPackager )
					)
					( objectStatus "J1A1.77" )
				)
			)
			( gate "@baseboard_fab2_lib.baseboard_fab2(sch_1):page87_i178"
				( attribute "BOM_COST" "MEM"
					( Origin gFrontEnd )
				)
				( attribute "CDS_LIB" "dev_discrete"
					( Origin gPackager )
				)
				( attribute "CDS_LOCATION" "C1A5"
					( Origin gPackager )
				)
				( attribute "CDS_SEC" "1"
					( Origin gPackager )
				)
				( attribute "LOCATION" "C1A5"
					( Origin gFrontEnd )
				)
				( attribute "MATERIAL" "X7R"
					( Origin gFrontEnd )
				)
				( attribute "PACK_TYPE" "0402V"
					( Origin gFrontEnd )
				)
				( attribute "PART_NUMBER" "A36096-045"
					( Origin gFrontEnd )
				)
				( attribute "PHYS_PAGE" "87"
					( Origin gFrontEnd )
				)
				( attribute "ROOM" "DDR4_CH_M"
					( Origin gFrontEnd )
				)
				( attribute "ROT" "2"
					( Origin gFrontEnd )
				)
				( attribute "SEC" "1"
					( Origin gFrontEnd )
				)
				( attribute "SEC_TYPE" "0402V"
					( Origin gFrontEnd )
				)
				( attribute "TOLERANCE" "10%"
					( Origin gFrontEnd )
				)
				( attribute "VALUE" "0.01UF"
					( Origin gFrontEnd )
				)
				( attribute "VER" "1"
					( Origin gFrontEnd )
				)
				( attribute "VOLTAGE" "25V"
					( Units "uVoltage" "V" 1.000000)
					( Origin gFrontEnd )
				)
				( attribute "XY" "(-4650,1550)"
					( Origin gFrontEnd )
				)
				( attribute "CHIPS_PART_NAME" "CAP_A"
					( Origin gPackager )
				)
				( attribute "CDS_PART_NAME" "CAP_A_0402V-0.01UF,25V,10%,X7RA"
					( Origin gPackager )
				)
				( objectStatus "C1A5" )
				( pin "a"
					( attribute "PN" "1"
						( Origin gPackager )
					)
					( objectStatus "C1A5.1" )
				)
				( pin "b"
					( attribute "PN" "2"
						( Origin gPackager )
					)
					( objectStatus "C1A5.2" )
				)
			)
			( gate "@baseboard_fab2_lib.baseboard_fab2(sch_1):page87_i185"
				( attribute "BOM_COST" "MEM"
					( Origin gFrontEnd )
				)
				( attribute "CDS_LIB" "mstr_sconn"
					( Origin gPackager )
				)
				( attribute "CDS_LOCATION" "J1A1"
					( Origin gPackager )
				)
				( attribute "CDS_SEC" "3"
					( Origin gPackager )
				)
				( attribute "LOCATION" "J1A1"
					( Origin gFrontEnd )
				)
				( attribute "MATERIAL" "SCONN"
					( Origin gFrontEnd )
				)
				( attribute "PACK_TYPE" "PIP"
					( Origin gFrontEnd )
				)
				( attribute "PART_NUMBER" "H44441-004"
					( Origin gFrontEnd )
				)
				( attribute "PHYS_PAGE" "87"
					( Origin gFrontEnd )
				)
				( attribute "ROOM" "DDR4_CH_M"
					( Origin gFrontEnd )
				)
				( attribute "ROT" "0"
					( Origin gFrontEnd )
				)
				( attribute "SEC" "3"
					( Origin gFrontEnd )
				)
				( attribute "SEC_TYPE" "PIP"
					( Origin gFrontEnd )
				)
				( attribute "VER" "3"
					( Origin gFrontEnd )
				)
				( attribute "XY" "(1800,2450)"
					( Origin gFrontEnd )
				)
				( attribute "CHIPS_PART_NAME" "SCONN288_H44441004"
					( Origin gPackager )
				)
				( attribute "CDS_PART_NAME" "SCONN288_H44441004_PIP-SCONN,HA"
					( Origin gPackager )
				)
				( objectStatus "J1A1" )
				( pin "vss(0)"
					( attribute "PN" "283"
						( Origin gPackager )
					)
					( objectStatus "J1A1.283" )
				)
				( pin "vss(1)"
					( attribute "PN" "281"
						( Origin gPackager )
					)
					( objectStatus "J1A1.281" )
				)
				( pin "vss(2)"
					( attribute "PN" "279"
						( Origin gPackager )
					)
					( objectStatus "J1A1.279" )
				)
				( pin "vss(3)"
					( attribute "PN" "276"
						( Origin gPackager )
					)
					( objectStatus "J1A1.276" )
				)
				( pin "vss(4)"
					( attribute "PN" "274"
						( Origin gPackager )
					)
					( objectStatus "J1A1.274" )
				)
				( pin "vss(5)"
					( attribute "PN" "272"
						( Origin gPackager )
					)
					( objectStatus "J1A1.272" )
				)
				( pin "vss(6)"
					( attribute "PN" "270"
						( Origin gPackager )
					)
					( objectStatus "J1A1.270" )
				)
				( pin "vss(7)"
					( attribute "PN" "268"
						( Origin gPackager )
					)
					( objectStatus "J1A1.268" )
				)
				( pin "vss(8)"
					( attribute "PN" "265"
						( Origin gPackager )
					)
					( objectStatus "J1A1.265" )
				)
				( pin "vss(9)"
					( attribute "PN" "263"
						( Origin gPackager )
					)
					( objectStatus "J1A1.263" )
				)
				( pin "vss(10)"
					( attribute "PN" "261"
						( Origin gPackager )
					)
					( objectStatus "J1A1.261" )
				)
				( pin "vss(11)"
					( attribute "PN" "259"
						( Origin gPackager )
					)
					( objectStatus "J1A1.259" )
				)
				( pin "vss(12)"
					( attribute "PN" "257"
						( Origin gPackager )
					)
					( objectStatus "J1A1.257" )
				)
				( pin "vss(13)"
					( attribute "PN" "254"
						( Origin gPackager )
					)
					( objectStatus "J1A1.254" )
				)
				( pin "vss(14)"
					( attribute "PN" "252"
						( Origin gPackager )
					)
					( objectStatus "J1A1.252" )
				)
				( pin "vss(15)"
					( attribute "PN" "250"
						( Origin gPackager )
					)
					( objectStatus "J1A1.250" )
				)
				( pin "vss(16)"
					( attribute "PN" "248"
						( Origin gPackager )
					)
					( objectStatus "J1A1.248" )
				)
				( pin "vss(17)"
					( attribute "PN" "246"
						( Origin gPackager )
					)
					( objectStatus "J1A1.246" )
				)
				( pin "vss(18)"
					( attribute "PN" "243"
						( Origin gPackager )
					)
					( objectStatus "J1A1.243" )
				)
				( pin "vss(19)"
					( attribute "PN" "241"
						( Origin gPackager )
					)
					( objectStatus "J1A1.241" )
				)
				( pin "vss(20)"
					( attribute "PN" "239"
						( Origin gPackager )
					)
					( objectStatus "J1A1.239" )
				)
				( pin "vss(21)"
					( attribute "PN" "202"
						( Origin gPackager )
					)
					( objectStatus "J1A1.202" )
				)
				( pin "vss(22)"
					( attribute "PN" "200"
						( Origin gPackager )
					)
					( objectStatus "J1A1.200" )
				)
				( pin "vss(23)"
					( attribute "PN" "198"
						( Origin gPackager )
					)
					( objectStatus "J1A1.198" )
				)
				( pin "vss(24)"
					( attribute "PN" "195"
						( Origin gPackager )
					)
					( objectStatus "J1A1.195" )
				)
				( pin "vss(25)"
					( attribute "PN" "193"
						( Origin gPackager )
					)
					( objectStatus "J1A1.193" )
				)
				( pin "vss(26)"
					( attribute "PN" "191"
						( Origin gPackager )
					)
					( objectStatus "J1A1.191" )
				)
				( pin "vss(27)"
					( attribute "PN" "189"
						( Origin gPackager )
					)
					( objectStatus "J1A1.189" )
				)
				( pin "vss(28)"
					( attribute "PN" "187"
						( Origin gPackager )
					)
					( objectStatus "J1A1.187" )
				)
				( pin "vss(29)"
					( attribute "PN" "184"
						( Origin gPackager )
					)
					( objectStatus "J1A1.184" )
				)
				( pin "vss(30)"
					( attribute "PN" "182"
						( Origin gPackager )
					)
					( objectStatus "J1A1.182" )
				)
				( pin "vss(31)"
					( attribute "PN" "180"
						( Origin gPackager )
					)
					( objectStatus "J1A1.180" )
				)
				( pin "vss(32)"
					( attribute "PN" "178"
						( Origin gPackager )
					)
					( objectStatus "J1A1.178" )
				)
				( pin "vss(33)"
					( attribute "PN" "176"
						( Origin gPackager )
					)
					( objectStatus "J1A1.176" )
				)
				( pin "vss(34)"
					( attribute "PN" "173"
						( Origin gPackager )
					)
					( objectStatus "J1A1.173" )
				)
				( pin "vss(35)"
					( attribute "PN" "171"
						( Origin gPackager )
					)
					( objectStatus "J1A1.171" )
				)
				( pin "vss(36)"
					( attribute "PN" "169"
						( Origin gPackager )
					)
					( objectStatus "J1A1.169" )
				)
				( pin "vss(37)"
					( attribute "PN" "167"
						( Origin gPackager )
					)
					( objectStatus "J1A1.167" )
				)
				( pin "vss(38)"
					( attribute "PN" "165"
						( Origin gPackager )
					)
					( objectStatus "J1A1.165" )
				)
				( pin "vss(39)"
					( attribute "PN" "162"
						( Origin gPackager )
					)
					( objectStatus "J1A1.162" )
				)
				( pin "vss(40)"
					( attribute "PN" "160"
						( Origin gPackager )
					)
					( objectStatus "J1A1.160" )
				)
				( pin "vss(41)"
					( attribute "PN" "158"
						( Origin gPackager )
					)
					( objectStatus "J1A1.158" )
				)
				( pin "vss(42)"
					( attribute "PN" "156"
						( Origin gPackager )
					)
					( objectStatus "J1A1.156" )
				)
				( pin "vss(43)"
					( attribute "PN" "154"
						( Origin gPackager )
					)
					( objectStatus "J1A1.154" )
				)
				( pin "vss(44)"
					( attribute "PN" "151"
						( Origin gPackager )
					)
					( objectStatus "J1A1.151" )
				)
				( pin "vss(45)"
					( attribute "PN" "149"
						( Origin gPackager )
					)
					( objectStatus "J1A1.149" )
				)
				( pin "vss(46)"
					( attribute "PN" "147"
						( Origin gPackager )
					)
					( objectStatus "J1A1.147" )
				)
				( pin "vss(47)"
					( attribute "PN" "138"
						( Origin gPackager )
					)
					( objectStatus "J1A1.138" )
				)
				( pin "vss(48)"
					( attribute "PN" "136"
						( Origin gPackager )
					)
					( objectStatus "J1A1.136" )
				)
				( pin "vss(49)"
					( attribute "PN" "134"
						( Origin gPackager )
					)
					( objectStatus "J1A1.134" )
				)
				( pin "vss(50)"
					( attribute "PN" "131"
						( Origin gPackager )
					)
					( objectStatus "J1A1.131" )
				)
				( pin "vss(51)"
					( attribute "PN" "129"
						( Origin gPackager )
					)
					( objectStatus "J1A1.129" )
				)
				( pin "vss(52)"
					( attribute "PN" "127"
						( Origin gPackager )
					)
					( objectStatus "J1A1.127" )
				)
				( pin "vss(53)"
					( attribute "PN" "125"
						( Origin gPackager )
					)
					( objectStatus "J1A1.125" )
				)
				( pin "vss(54)"
					( attribute "PN" "123"
						( Origin gPackager )
					)
					( objectStatus "J1A1.123" )
				)
				( pin "vss(55)"
					( attribute "PN" "120"
						( Origin gPackager )
					)
					( objectStatus "J1A1.120" )
				)
				( pin "vss(56)"
					( attribute "PN" "118"
						( Origin gPackager )
					)
					( objectStatus "J1A1.118" )
				)
				( pin "vss(57)"
					( attribute "PN" "116"
						( Origin gPackager )
					)
					( objectStatus "J1A1.116" )
				)
				( pin "vss(58)"
					( attribute "PN" "114"
						( Origin gPackager )
					)
					( objectStatus "J1A1.114" )
				)
				( pin "vss(59)"
					( attribute "PN" "112"
						( Origin gPackager )
					)
					( objectStatus "J1A1.112" )
				)
				( pin "vss(60)"
					( attribute "PN" "109"
						( Origin gPackager )
					)
					( objectStatus "J1A1.109" )
				)
				( pin "vss(61)"
					( attribute "PN" "107"
						( Origin gPackager )
					)
					( objectStatus "J1A1.107" )
				)
				( pin "vss(62)"
					( attribute "PN" "105"
						( Origin gPackager )
					)
					( objectStatus "J1A1.105" )
				)
				( pin "vss(63)"
					( attribute "PN" "103"
						( Origin gPackager )
					)
					( objectStatus "J1A1.103" )
				)
				( pin "vss(64)"
					( attribute "PN" "101"
						( Origin gPackager )
					)
					( objectStatus "J1A1.101" )
				)
				( pin "vss(65)"
					( attribute "PN" "98"
						( Origin gPackager )
					)
					( objectStatus "J1A1.98" )
				)
				( pin "vss(66)"
					( attribute "PN" "96"
						( Origin gPackager )
					)
					( objectStatus "J1A1.96" )
				)
				( pin "vss(67)"
					( attribute "PN" "94"
						( Origin gPackager )
					)
					( objectStatus "J1A1.94" )
				)
				( pin "vss(68)"
					( attribute "PN" "57"
						( Origin gPackager )
					)
					( objectStatus "J1A1.57" )
				)
				( pin "vss(69)"
					( attribute "PN" "55"
						( Origin gPackager )
					)
					( objectStatus "J1A1.55" )
				)
				( pin "vss(70)"
					( attribute "PN" "53"
						( Origin gPackager )
					)
					( objectStatus "J1A1.53" )
				)
				( pin "vss(71)"
					( attribute "PN" "50"
						( Origin gPackager )
					)
					( objectStatus "J1A1.50" )
				)
				( pin "vss(72)"
					( attribute "PN" "48"
						( Origin gPackager )
					)
					( objectStatus "J1A1.48" )
				)
				( pin "vss(73)"
					( attribute "PN" "46"
						( Origin gPackager )
					)
					( objectStatus "J1A1.46" )
				)
				( pin "vss(74)"
					( attribute "PN" "44"
						( Origin gPackager )
					)
					( objectStatus "J1A1.44" )
				)
				( pin "vss(75)"
					( attribute "PN" "42"
						( Origin gPackager )
					)
					( objectStatus "J1A1.42" )
				)
				( pin "vss(76)"
					( attribute "PN" "39"
						( Origin gPackager )
					)
					( objectStatus "J1A1.39" )
				)
				( pin "vss(77)"
					( attribute "PN" "37"
						( Origin gPackager )
					)
					( objectStatus "J1A1.37" )
				)
				( pin "vss(78)"
					( attribute "PN" "35"
						( Origin gPackager )
					)
					( objectStatus "J1A1.35" )
				)
				( pin "vss(79)"
					( attribute "PN" "33"
						( Origin gPackager )
					)
					( objectStatus "J1A1.33" )
				)
				( pin "vss(80)"
					( attribute "PN" "31"
						( Origin gPackager )
					)
					( objectStatus "J1A1.31" )
				)
				( pin "vss(81)"
					( attribute "PN" "28"
						( Origin gPackager )
					)
					( objectStatus "J1A1.28" )
				)
				( pin "vss(82)"
					( attribute "PN" "26"
						( Origin gPackager )
					)
					( objectStatus "J1A1.26" )
				)
				( pin "vss(83)"
					( attribute "PN" "24"
						( Origin gPackager )
					)
					( objectStatus "J1A1.24" )
				)
				( pin "vss(84)"
					( attribute "PN" "22"
						( Origin gPackager )
					)
					( objectStatus "J1A1.22" )
				)
				( pin "vss(85)"
					( attribute "PN" "20"
						( Origin gPackager )
					)
					( objectStatus "J1A1.20" )
				)
				( pin "vss(86)"
					( attribute "PN" "17"
						( Origin gPackager )
					)
					( objectStatus "J1A1.17" )
				)
				( pin "vss(87)"
					( attribute "PN" "15"
						( Origin gPackager )
					)
					( objectStatus "J1A1.15" )
				)
				( pin "vss(88)"
					( attribute "PN" "13"
						( Origin gPackager )
					)
					( objectStatus "J1A1.13" )
				)
				( pin "vss(89)"
					( attribute "PN" "11"
						( Origin gPackager )
					)
					( objectStatus "J1A1.11" )
				)
				( pin "vss(90)"
					( attribute "PN" "9"
						( Origin gPackager )
					)
					( objectStatus "J1A1.9" )
				)
				( pin "vss(91)"
					( attribute "PN" "6"
						( Origin gPackager )
					)
					( objectStatus "J1A1.6" )
				)
				( pin "vss(92)"
					( attribute "PN" "4"
						( Origin gPackager )
					)
					( objectStatus "J1A1.4" )
				)
				( pin "vss(93)"
					( attribute "PN" "2"
						( Origin gPackager )
					)
					( objectStatus "J1A1.2" )
				)
			)
			( gate "@baseboard_fab2_lib.baseboard_fab2(sch_1):page87_i186"
				( attribute "BOM_COST" "MEM"
					( Origin gFrontEnd )
				)
				( attribute "CDS_LIB" "mstr_sconn"
					( Origin gPackager )
				)
				( attribute "CDS_LOCATION" "J1A1"
					( Origin gPackager )
				)
				( attribute "CDS_SEC" "1"
					( Origin gPackager )
				)
				( attribute "LOCATION" "J1A1"
					( Origin gFrontEnd )
				)
				( attribute "MATERIAL" "SCONN"
					( Origin gFrontEnd )
				)
				( attribute "PACK_TYPE" "PIP"
					( Origin gFrontEnd )
				)
				( attribute "PART_NUMBER" "H44441-004"
					( Origin gFrontEnd )
				)
				( attribute "PHYS_PAGE" "87"
					( Origin gFrontEnd )
				)
				( attribute "ROOM" "DDR4_CH_M"
					( Origin gFrontEnd )
				)
				( attribute "ROT" "0"
					( Origin gFrontEnd )
				)
				( attribute "SEC" "1"
					( Origin gFrontEnd )
				)
				( attribute "SEC_TYPE" "PIP"
					( Origin gFrontEnd )
				)
				( attribute "VER" "1"
					( Origin gFrontEnd )
				)
				( attribute "XY" "(-2500,3250)"
					( Origin gFrontEnd )
				)
				( attribute "CHIPS_PART_NAME" "SCONN288_H44441004"
					( Origin gPackager )
				)
				( attribute "CDS_PART_NAME" "SCONN288_H44441004_PIP-SCONN,HA"
					( Origin gPackager )
				)
				( objectStatus "J1A1" )
				( pin "a0"
					( attribute "PN" "79"
						( Origin gPackager )
					)
					( objectStatus "J1A1.79" )
				)
				( pin "a1"
					( attribute "PN" "72"
						( Origin gPackager )
					)
					( objectStatus "J1A1.72" )
				)
				( pin "a2"
					( attribute "PN" "216"
						( Origin gPackager )
					)
					( objectStatus "J1A1.216" )
				)
				( pin "a3"
					( attribute "PN" "71"
						( Origin gPackager )
					)
					( objectStatus "J1A1.71" )
				)
				( pin "a4"
					( attribute "PN" "214"
						( Origin gPackager )
					)
					( objectStatus "J1A1.214" )
				)
				( pin "a5"
					( attribute "PN" "213"
						( Origin gPackager )
					)
					( objectStatus "J1A1.213" )
				)
				( pin "a6"
					( attribute "PN" "69"
						( Origin gPackager )
					)
					( objectStatus "J1A1.69" )
				)
				( pin "a7"
					( attribute "PN" "211"
						( Origin gPackager )
					)
					( objectStatus "J1A1.211" )
				)
				( pin "a8"
					( attribute "PN" "68"
						( Origin gPackager )
					)
					( objectStatus "J1A1.68" )
				)
				( pin "a9"
					( attribute "PN" "66"
						( Origin gPackager )
					)
					( objectStatus "J1A1.66" )
				)
				( pin "a10"
					( attribute "PN" "225"
						( Origin gPackager )
					)
					( objectStatus "J1A1.225" )
				)
				( pin "a11"
					( attribute "PN" "210"
						( Origin gPackager )
					)
					( objectStatus "J1A1.210" )
				)
				( pin "a12"
					( attribute "PN" "65"
						( Origin gPackager )
					)
					( objectStatus "J1A1.65" )
				)
				( pin "a13"
					( attribute "PN" "232"
						( Origin gPackager )
					)
					( objectStatus "J1A1.232" )
				)
				( pin "a14_we_n"
					( attribute "PN" "228"
						( Origin gPackager )
					)
					( objectStatus "J1A1.228" )
				)
				( pin "a15_cas_n"
					( attribute "PN" "86"
						( Origin gPackager )
					)
					( objectStatus "J1A1.86" )
				)
				( pin "a16_ras_n"
					( attribute "PN" "82"
						( Origin gPackager )
					)
					( objectStatus "J1A1.82" )
				)
				( pin "a17"
					( attribute "PN" "234"
						( Origin gPackager )
					)
					( objectStatus "J1A1.234" )
				)
				( pin "act_n"
					( attribute "PN" "62"
						( Origin gPackager )
					)
					( objectStatus "J1A1.62" )
				)
				( pin "alert_n"
					( attribute "PN" "208"
						( Origin gPackager )
					)
					( objectStatus "J1A1.208" )
				)
				( pin "ba(0)"
					( attribute "PN" "81"
						( Origin gPackager )
					)
					( objectStatus "J1A1.81" )
				)
				( pin "ba(1)"
					( attribute "PN" "224"
						( Origin gPackager )
					)
					( objectStatus "J1A1.224" )
				)
				( pin "bg(0)"
					( attribute "PN" "63"
						( Origin gPackager )
					)
					( objectStatus "J1A1.63" )
				)
				( pin "bg(1)"
					( attribute "PN" "207"
						( Origin gPackager )
					)
					( objectStatus "J1A1.207" )
				)
				( pin "c(2)"
					( attribute "PN" "235"
						( Origin gPackager )
					)
					( objectStatus "J1A1.235" )
				)
				( pin "cb(0)"
					( attribute "PN" "49"
						( Origin gPackager )
					)
					( objectStatus "J1A1.49" )
				)
				( pin "cb(1)"
					( attribute "PN" "194"
						( Origin gPackager )
					)
					( objectStatus "J1A1.194" )
				)
				( pin "cb(2)"
					( attribute "PN" "56"
						( Origin gPackager )
					)
					( objectStatus "J1A1.56" )
				)
				( pin "cb(3)"
					( attribute "PN" "201"
						( Origin gPackager )
					)
					( objectStatus "J1A1.201" )
				)
				( pin "cb(4)"
					( attribute "PN" "47"
						( Origin gPackager )
					)
					( objectStatus "J1A1.47" )
				)
				( pin "cb(5)"
					( attribute "PN" "192"
						( Origin gPackager )
					)
					( objectStatus "J1A1.192" )
				)
				( pin "cb(6)"
					( attribute "PN" "54"
						( Origin gPackager )
					)
					( objectStatus "J1A1.54" )
				)
				( pin "cb(7)"
					( attribute "PN" "199"
						( Origin gPackager )
					)
					( objectStatus "J1A1.199" )
				)
				( pin "ck0n"
					( attribute "PN" "75"
						( Origin gPackager )
					)
					( objectStatus "J1A1.75" )
				)
				( pin "ck0p"
					( attribute "PN" "74"
						( Origin gPackager )
					)
					( objectStatus "J1A1.74" )
				)
				( pin "ck1n"
					( attribute "PN" "219"
						( Origin gPackager )
					)
					( objectStatus "J1A1.219" )
				)
				( pin "ck1p"
					( attribute "PN" "218"
						( Origin gPackager )
					)
					( objectStatus "J1A1.218" )
				)
				( pin "cke(0)"
					( attribute "PN" "60"
						( Origin gPackager )
					)
					( objectStatus "J1A1.60" )
				)
				( pin "cke(1)"
					( attribute "PN" "203"
						( Origin gPackager )
					)
					( objectStatus "J1A1.203" )
				)
				( pin "dq(0)"
					( attribute "PN" "5"
						( Origin gPackager )
					)
					( objectStatus "J1A1.5" )
				)
				( pin "dq(1)"
					( attribute "PN" "150"
						( Origin gPackager )
					)
					( objectStatus "J1A1.150" )
				)
				( pin "dq(2)"
					( attribute "PN" "12"
						( Origin gPackager )
					)
					( objectStatus "J1A1.12" )
				)
				( pin "dq(3)"
					( attribute "PN" "157"
						( Origin gPackager )
					)
					( objectStatus "J1A1.157" )
				)
				( pin "dq(4)"
					( attribute "PN" "3"
						( Origin gPackager )
					)
					( objectStatus "J1A1.3" )
				)
				( pin "dq(5)"
					( attribute "PN" "148"
						( Origin gPackager )
					)
					( objectStatus "J1A1.148" )
				)
				( pin "dq(6)"
					( attribute "PN" "10"
						( Origin gPackager )
					)
					( objectStatus "J1A1.10" )
				)
				( pin "dq(7)"
					( attribute "PN" "155"
						( Origin gPackager )
					)
					( objectStatus "J1A1.155" )
				)
				( pin "dq(8)"
					( attribute "PN" "16"
						( Origin gPackager )
					)
					( objectStatus "J1A1.16" )
				)
				( pin "dq(9)"
					( attribute "PN" "161"
						( Origin gPackager )
					)
					( objectStatus "J1A1.161" )
				)
				( pin "dq(10)"
					( attribute "PN" "23"
						( Origin gPackager )
					)
					( objectStatus "J1A1.23" )
				)
				( pin "dq(11)"
					( attribute "PN" "168"
						( Origin gPackager )
					)
					( objectStatus "J1A1.168" )
				)
				( pin "dq(12)"
					( attribute "PN" "14"
						( Origin gPackager )
					)
					( objectStatus "J1A1.14" )
				)
				( pin "dq(13)"
					( attribute "PN" "159"
						( Origin gPackager )
					)
					( objectStatus "J1A1.159" )
				)
				( pin "dq(14)"
					( attribute "PN" "21"
						( Origin gPackager )
					)
					( objectStatus "J1A1.21" )
				)
				( pin "dq(15)"
					( attribute "PN" "166"
						( Origin gPackager )
					)
					( objectStatus "J1A1.166" )
				)
				( pin "dq(16)"
					( attribute "PN" "27"
						( Origin gPackager )
					)
					( objectStatus "J1A1.27" )
				)
				( pin "dq(17)"
					( attribute "PN" "172"
						( Origin gPackager )
					)
					( objectStatus "J1A1.172" )
				)
				( pin "dq(18)"
					( attribute "PN" "34"
						( Origin gPackager )
					)
					( objectStatus "J1A1.34" )
				)
				( pin "dq(19)"
					( attribute "PN" "179"
						( Origin gPackager )
					)
					( objectStatus "J1A1.179" )
				)
				( pin "dq(20)"
					( attribute "PN" "25"
						( Origin gPackager )
					)
					( objectStatus "J1A1.25" )
				)
				( pin "dq(21)"
					( attribute "PN" "170"
						( Origin gPackager )
					)
					( objectStatus "J1A1.170" )
				)
				( pin "dq(22)"
					( attribute "PN" "32"
						( Origin gPackager )
					)
					( objectStatus "J1A1.32" )
				)
				( pin "dq(23)"
					( attribute "PN" "177"
						( Origin gPackager )
					)
					( objectStatus "J1A1.177" )
				)
				( pin "dq(24)"
					( attribute "PN" "38"
						( Origin gPackager )
					)
					( objectStatus "J1A1.38" )
				)
				( pin "dq(25)"
					( attribute "PN" "183"
						( Origin gPackager )
					)
					( objectStatus "J1A1.183" )
				)
				( pin "dq(26)"
					( attribute "PN" "45"
						( Origin gPackager )
					)
					( objectStatus "J1A1.45" )
				)
				( pin "dq(27)"
					( attribute "PN" "190"
						( Origin gPackager )
					)
					( objectStatus "J1A1.190" )
				)
				( pin "dq(28)"
					( attribute "PN" "36"
						( Origin gPackager )
					)
					( objectStatus "J1A1.36" )
				)
				( pin "dq(29)"
					( attribute "PN" "181"
						( Origin gPackager )
					)
					( objectStatus "J1A1.181" )
				)
				( pin "dq(30)"
					( attribute "PN" "43"
						( Origin gPackager )
					)
					( objectStatus "J1A1.43" )
				)
				( pin "dq(31)"
					( attribute "PN" "188"
						( Origin gPackager )
					)
					( objectStatus "J1A1.188" )
				)
				( pin "dq(32)"
					( attribute "PN" "97"
						( Origin gPackager )
					)
					( objectStatus "J1A1.97" )
				)
				( pin "dq(33)"
					( attribute "PN" "242"
						( Origin gPackager )
					)
					( objectStatus "J1A1.242" )
				)
				( pin "dq(34)"
					( attribute "PN" "104"
						( Origin gPackager )
					)
					( objectStatus "J1A1.104" )
				)
				( pin "dq(35)"
					( attribute "PN" "249"
						( Origin gPackager )
					)
					( objectStatus "J1A1.249" )
				)
				( pin "dq(36)"
					( attribute "PN" "95"
						( Origin gPackager )
					)
					( objectStatus "J1A1.95" )
				)
				( pin "dq(37)"
					( attribute "PN" "240"
						( Origin gPackager )
					)
					( objectStatus "J1A1.240" )
				)
				( pin "dq(38)"
					( attribute "PN" "102"
						( Origin gPackager )
					)
					( objectStatus "J1A1.102" )
				)
				( pin "dq(39)"
					( attribute "PN" "247"
						( Origin gPackager )
					)
					( objectStatus "J1A1.247" )
				)
				( pin "dq(40)"
					( attribute "PN" "108"
						( Origin gPackager )
					)
					( objectStatus "J1A1.108" )
				)
				( pin "dq(41)"
					( attribute "PN" "253"
						( Origin gPackager )
					)
					( objectStatus "J1A1.253" )
				)
				( pin "dq(42)"
					( attribute "PN" "115"
						( Origin gPackager )
					)
					( objectStatus "J1A1.115" )
				)
				( pin "dq(43)"
					( attribute "PN" "260"
						( Origin gPackager )
					)
					( objectStatus "J1A1.260" )
				)
				( pin "dq(44)"
					( attribute "PN" "106"
						( Origin gPackager )
					)
					( objectStatus "J1A1.106" )
				)
				( pin "dq(45)"
					( attribute "PN" "251"
						( Origin gPackager )
					)
					( objectStatus "J1A1.251" )
				)
				( pin "dq(46)"
					( attribute "PN" "113"
						( Origin gPackager )
					)
					( objectStatus "J1A1.113" )
				)
				( pin "dq(47)"
					( attribute "PN" "258"
						( Origin gPackager )
					)
					( objectStatus "J1A1.258" )
				)
				( pin "dq(48)"
					( attribute "PN" "119"
						( Origin gPackager )
					)
					( objectStatus "J1A1.119" )
				)
				( pin "dq(49)"
					( attribute "PN" "264"
						( Origin gPackager )
					)
					( objectStatus "J1A1.264" )
				)
				( pin "dq(50)"
					( attribute "PN" "126"
						( Origin gPackager )
					)
					( objectStatus "J1A1.126" )
				)
				( pin "dq(51)"
					( attribute "PN" "271"
						( Origin gPackager )
					)
					( objectStatus "J1A1.271" )
				)
				( pin "dq(52)"
					( attribute "PN" "117"
						( Origin gPackager )
					)
					( objectStatus "J1A1.117" )
				)
				( pin "dq(53)"
					( attribute "PN" "262"
						( Origin gPackager )
					)
					( objectStatus "J1A1.262" )
				)
				( pin "dq(54)"
					( attribute "PN" "124"
						( Origin gPackager )
					)
					( objectStatus "J1A1.124" )
				)
				( pin "dq(55)"
					( attribute "PN" "269"
						( Origin gPackager )
					)
					( objectStatus "J1A1.269" )
				)
				( pin "dq(56)"
					( attribute "PN" "130"
						( Origin gPackager )
					)
					( objectStatus "J1A1.130" )
				)
				( pin "dq(57)"
					( attribute "PN" "275"
						( Origin gPackager )
					)
					( objectStatus "J1A1.275" )
				)
				( pin "dq(58)"
					( attribute "PN" "137"
						( Origin gPackager )
					)
					( objectStatus "J1A1.137" )
				)
				( pin "dq(59)"
					( attribute "PN" "282"
						( Origin gPackager )
					)
					( objectStatus "J1A1.282" )
				)
				( pin "dq(60)"
					( attribute "PN" "128"
						( Origin gPackager )
					)
					( objectStatus "J1A1.128" )
				)
				( pin "dq(61)"
					( attribute "PN" "273"
						( Origin gPackager )
					)
					( objectStatus "J1A1.273" )
				)
				( pin "dq(62)"
					( attribute "PN" "135"
						( Origin gPackager )
					)
					( objectStatus "J1A1.135" )
				)
				( pin "dq(63)"
					( attribute "PN" "280"
						( Origin gPackager )
					)
					( objectStatus "J1A1.280" )
				)
				( pin "event_n"
					( attribute "PN" "78"
						( Origin gPackager )
					)
					( objectStatus "J1A1.78" )
				)
				( pin "odt(0)"
					( attribute "PN" "87"
						( Origin gPackager )
					)
					( objectStatus "J1A1.87" )
				)
				( pin "odt(1)"
					( attribute "PN" "91"
						( Origin gPackager )
					)
					( objectStatus "J1A1.91" )
				)
				( pin "par"
					( attribute "PN" "222"
						( Origin gPackager )
					)
					( objectStatus "J1A1.222" )
				)
				( pin "reset_n"
					( attribute "PN" "58"
						( Origin gPackager )
					)
					( objectStatus "J1A1.58" )
				)
				( pin "rfu(0)"
					( attribute "PN" "205"
						( Origin gPackager )
					)
					( objectStatus "J1A1.205" )
				)
				( pin "rfu(1)"
					( attribute "PN" "227"
						( Origin gPackager )
					)
					( objectStatus "J1A1.227" )
				)
				( pin "rfu(2)"
					( attribute "PN" "144"
						( Origin gPackager )
					)
					( objectStatus "J1A1.144" )
				)
				( pin "s0_n"
					( attribute "PN" "84"
						( Origin gPackager )
					)
					( objectStatus "J1A1.84" )
				)
				( pin "s1_n"
					( attribute "PN" "89"
						( Origin gPackager )
					)
					( objectStatus "J1A1.89" )
				)
				( pin "s2_n_c(0)"
					( attribute "PN" "93"
						( Origin gPackager )
					)
					( objectStatus "J1A1.93" )
				)
				( pin "s3_n_c(1)"
					( attribute "PN" "237"
						( Origin gPackager )
					)
					( objectStatus "J1A1.237" )
				)
				( pin "sa(0)"
					( attribute "PN" "139"
						( Origin gPackager )
					)
					( objectStatus "J1A1.139" )
				)
				( pin "sa(1)"
					( attribute "PN" "140"
						( Origin gPackager )
					)
					( objectStatus "J1A1.140" )
				)
				( pin "sa(2)"
					( attribute "PN" "238"
						( Origin gPackager )
					)
					( objectStatus "J1A1.238" )
				)
				( pin "save_n_nc"
					( attribute "PN" "230"
						( Origin gPackager )
					)
					( objectStatus "J1A1.230" )
				)
				( pin "scl"
					( attribute "PN" "141"
						( Origin gPackager )
					)
					( objectStatus "J1A1.141" )
				)
				( pin "sda"
					( attribute "PN" "285"
						( Origin gPackager )
					)
					( objectStatus "J1A1.285" )
				)
				( pin "vddspd"
					( attribute "PN" "284"
						( Origin gPackager )
					)
					( objectStatus "J1A1.284" )
				)
				( pin "vrefca"
					( attribute "PN" "146"
						( Origin gPackager )
					)
					( objectStatus "J1A1.146" )
				)
			)
			( gate "@baseboard_fab2_lib.baseboard_fab2(sch_1):page87_i187"
				( attribute "BOM_COST" "MEM"
					( Origin gFrontEnd )
				)
				( attribute "CDS_LIB" "mstr_sconn"
					( Origin gPackager )
				)
				( attribute "CDS_LOCATION" "J1A1"
					( Origin gPackager )
				)
				( attribute "CDS_SEC" "2"
					( Origin gPackager )
				)
				( attribute "LOCATION" "J1A1"
					( Origin gFrontEnd )
				)
				( attribute "MATERIAL" "SCONN"
					( Origin gFrontEnd )
				)
				( attribute "PACK_TYPE" "PIP"
					( Origin gFrontEnd )
				)
				( attribute "PART_NUMBER" "H44441-004"
					( Origin gFrontEnd )
				)
				( attribute "PHYS_PAGE" "87"
					( Origin gFrontEnd )
				)
				( attribute "ROOM" "DDR4_CH_M"
					( Origin gFrontEnd )
				)
				( attribute "ROT" "0"
					( Origin gFrontEnd )
				)
				( attribute "SEC" "2"
					( Origin gFrontEnd )
				)
				( attribute "SEC_TYPE" "PIP"
					( Origin gFrontEnd )
				)
				( attribute "VER" "2"
					( Origin gFrontEnd )
				)
				( attribute "XY" "(0,4300)"
					( Origin gFrontEnd )
				)
				( attribute "CHIPS_PART_NAME" "SCONN288_H44441004"
					( Origin gPackager )
				)
				( attribute "CDS_PART_NAME" "SCONN288_H44441004_PIP-SCONN,HA"
					( Origin gPackager )
				)
				( objectStatus "J1A1" )
				( pin "dqs0n"
					( attribute "PN" "152"
						( Origin gPackager )
					)
					( objectStatus "J1A1.152" )
				)
				( pin "dqs0p"
					( attribute "PN" "153"
						( Origin gPackager )
					)
					( objectStatus "J1A1.153" )
				)
				( pin "dqs1n"
					( attribute "PN" "163"
						( Origin gPackager )
					)
					( objectStatus "J1A1.163" )
				)
				( pin "dqs1p"
					( attribute "PN" "164"
						( Origin gPackager )
					)
					( objectStatus "J1A1.164" )
				)
				( pin "dqs2n"
					( attribute "PN" "174"
						( Origin gPackager )
					)
					( objectStatus "J1A1.174" )
				)
				( pin "dqs2p"
					( attribute "PN" "175"
						( Origin gPackager )
					)
					( objectStatus "J1A1.175" )
				)
				( pin "dqs3n"
					( attribute "PN" "185"
						( Origin gPackager )
					)
					( objectStatus "J1A1.185" )
				)
				( pin "dqs3p"
					( attribute "PN" "186"
						( Origin gPackager )
					)
					( objectStatus "J1A1.186" )
				)
				( pin "dqs4n"
					( attribute "PN" "244"
						( Origin gPackager )
					)
					( objectStatus "J1A1.244" )
				)
				( pin "dqs4p"
					( attribute "PN" "245"
						( Origin gPackager )
					)
					( objectStatus "J1A1.245" )
				)
				( pin "dqs5n"
					( attribute "PN" "255"
						( Origin gPackager )
					)
					( objectStatus "J1A1.255" )
				)
				( pin "dqs5p"
					( attribute "PN" "256"
						( Origin gPackager )
					)
					( objectStatus "J1A1.256" )
				)
				( pin "dqs6n"
					( attribute "PN" "266"
						( Origin gPackager )
					)
					( objectStatus "J1A1.266" )
				)
				( pin "dqs6p"
					( attribute "PN" "267"
						( Origin gPackager )
					)
					( objectStatus "J1A1.267" )
				)
				( pin "dqs7n"
					( attribute "PN" "277"
						( Origin gPackager )
					)
					( objectStatus "J1A1.277" )
				)
				( pin "dqs7p"
					( attribute "PN" "278"
						( Origin gPackager )
					)
					( objectStatus "J1A1.278" )
				)
				( pin "dqs8n"
					( attribute "PN" "196"
						( Origin gPackager )
					)
					( objectStatus "J1A1.196" )
				)
				( pin "dqs8p"
					( attribute "PN" "197"
						( Origin gPackager )
					)
					( objectStatus "J1A1.197" )
				)
				( pin "dqs9n"
					( attribute "PN" "8"
						( Origin gPackager )
					)
					( objectStatus "J1A1.8" )
				)
				( pin "dqs9p"
					( attribute "PN" "7"
						( Origin gPackager )
					)
					( objectStatus "J1A1.7" )
				)
				( pin "dqs10n"
					( attribute "PN" "19"
						( Origin gPackager )
					)
					( objectStatus "J1A1.19" )
				)
				( pin "dqs10p"
					( attribute "PN" "18"
						( Origin gPackager )
					)
					( objectStatus "J1A1.18" )
				)
				( pin "dqs11n"
					( attribute "PN" "30"
						( Origin gPackager )
					)
					( objectStatus "J1A1.30" )
				)
				( pin "dqs11p"
					( attribute "PN" "29"
						( Origin gPackager )
					)
					( objectStatus "J1A1.29" )
				)
				( pin "dqs12n"
					( attribute "PN" "41"
						( Origin gPackager )
					)
					( objectStatus "J1A1.41" )
				)
				( pin "dqs12p"
					( attribute "PN" "40"
						( Origin gPackager )
					)
					( objectStatus "J1A1.40" )
				)
				( pin "dqs13n"
					( attribute "PN" "100"
						( Origin gPackager )
					)
					( objectStatus "J1A1.100" )
				)
				( pin "dqs13p"
					( attribute "PN" "99"
						( Origin gPackager )
					)
					( objectStatus "J1A1.99" )
				)
				( pin "dqs14n"
					( attribute "PN" "111"
						( Origin gPackager )
					)
					( objectStatus "J1A1.111" )
				)
				( pin "dqs14p"
					( attribute "PN" "110"
						( Origin gPackager )
					)
					( objectStatus "J1A1.110" )
				)
				( pin "dqs15n"
					( attribute "PN" "122"
						( Origin gPackager )
					)
					( objectStatus "J1A1.122" )
				)
				( pin "dqs15p"
					( attribute "PN" "121"
						( Origin gPackager )
					)
					( objectStatus "J1A1.121" )
				)
				( pin "dqs16n"
					( attribute "PN" "133"
						( Origin gPackager )
					)
					( objectStatus "J1A1.133" )
				)
				( pin "dqs16p"
					( attribute "PN" "132"
						( Origin gPackager )
					)
					( objectStatus "J1A1.132" )
				)
				( pin "dqs17n"
					( attribute "PN" "52"
						( Origin gPackager )
					)
					( objectStatus "J1A1.52" )
				)
				( pin "dqs17p"
					( attribute "PN" "51"
						( Origin gPackager )
					)
					( objectStatus "J1A1.51" )
				)
			)
			( gate "@baseboard_fab2_lib.baseboard_fab2(sch_1):page88_i25"
				( attribute "BOM_COST" "DDR4_CH_M"
					( Origin gFrontEnd )
				)
				( attribute "CDS_LIB" "mstr_sconn"
					( Origin gPackager )
				)
				( attribute "CDS_LOCATION" "J9L1"
					( Origin gPackager )
				)
				( attribute "CDS_SEC" "3"
					( Origin gPackager )
				)
				( attribute "LOCATION" "J9L1"
					( Origin gFrontEnd )
				)
				( attribute "MATERIAL" "SCONN"
					( Origin gFrontEnd )
				)
				( attribute "PACK_TYPE" "PIP"
					( Origin gFrontEnd )
				)
				( attribute "PART_NUMBER" "H44441-003"
					( Origin gFrontEnd )
				)
				( attribute "PHYS_PAGE" "88"
					( Origin gFrontEnd )
				)
				( attribute "ROOM" "DDR4_CH_M"
					( Origin gFrontEnd )
				)
				( attribute "ROT" "0"
					( Origin gFrontEnd )
				)
				( attribute "SEC" "3"
					( Origin gFrontEnd )
				)
				( attribute "SEC_TYPE" "PIP"
					( Origin gFrontEnd )
				)
				( attribute "VER" "3"
					( Origin gFrontEnd )
				)
				( attribute "XY" "(1800,2400)"
					( Origin gFrontEnd )
				)
				( attribute "CHIPS_PART_NAME" "SCONN288_H44441003"
					( Origin gPackager )
				)
				( attribute "CDS_PART_NAME" "SCONN288_H44441003_PIP-SCONN,HA"
					( Origin gPackager )
				)
				( objectStatus "J9L1" )
				( pin "vss(0)"
					( attribute "PN" "283"
						( Origin gPackager )
					)
					( objectStatus "J9L1.283" )
				)
				( pin "vss(1)"
					( attribute "PN" "281"
						( Origin gPackager )
					)
					( objectStatus "J9L1.281" )
				)
				( pin "vss(2)"
					( attribute "PN" "279"
						( Origin gPackager )
					)
					( objectStatus "J9L1.279" )
				)
				( pin "vss(3)"
					( attribute "PN" "276"
						( Origin gPackager )
					)
					( objectStatus "J9L1.276" )
				)
				( pin "vss(4)"
					( attribute "PN" "274"
						( Origin gPackager )
					)
					( objectStatus "J9L1.274" )
				)
				( pin "vss(5)"
					( attribute "PN" "272"
						( Origin gPackager )
					)
					( objectStatus "J9L1.272" )
				)
				( pin "vss(6)"
					( attribute "PN" "270"
						( Origin gPackager )
					)
					( objectStatus "J9L1.270" )
				)
				( pin "vss(7)"
					( attribute "PN" "268"
						( Origin gPackager )
					)
					( objectStatus "J9L1.268" )
				)
				( pin "vss(8)"
					( attribute "PN" "265"
						( Origin gPackager )
					)
					( objectStatus "J9L1.265" )
				)
				( pin "vss(9)"
					( attribute "PN" "263"
						( Origin gPackager )
					)
					( objectStatus "J9L1.263" )
				)
				( pin "vss(10)"
					( attribute "PN" "261"
						( Origin gPackager )
					)
					( objectStatus "J9L1.261" )
				)
				( pin "vss(11)"
					( attribute "PN" "259"
						( Origin gPackager )
					)
					( objectStatus "J9L1.259" )
				)
				( pin "vss(12)"
					( attribute "PN" "257"
						( Origin gPackager )
					)
					( objectStatus "J9L1.257" )
				)
				( pin "vss(13)"
					( attribute "PN" "254"
						( Origin gPackager )
					)
					( objectStatus "J9L1.254" )
				)
				( pin "vss(14)"
					( attribute "PN" "252"
						( Origin gPackager )
					)
					( objectStatus "J9L1.252" )
				)
				( pin "vss(15)"
					( attribute "PN" "250"
						( Origin gPackager )
					)
					( objectStatus "J9L1.250" )
				)
				( pin "vss(16)"
					( attribute "PN" "248"
						( Origin gPackager )
					)
					( objectStatus "J9L1.248" )
				)
				( pin "vss(17)"
					( attribute "PN" "246"
						( Origin gPackager )
					)
					( objectStatus "J9L1.246" )
				)
				( pin "vss(18)"
					( attribute "PN" "243"
						( Origin gPackager )
					)
					( objectStatus "J9L1.243" )
				)
				( pin "vss(19)"
					( attribute "PN" "241"
						( Origin gPackager )
					)
					( objectStatus "J9L1.241" )
				)
				( pin "vss(20)"
					( attribute "PN" "239"
						( Origin gPackager )
					)
					( objectStatus "J9L1.239" )
				)
				( pin "vss(21)"
					( attribute "PN" "202"
						( Origin gPackager )
					)
					( objectStatus "J9L1.202" )
				)
				( pin "vss(22)"
					( attribute "PN" "200"
						( Origin gPackager )
					)
					( objectStatus "J9L1.200" )
				)
				( pin "vss(23)"
					( attribute "PN" "198"
						( Origin gPackager )
					)
					( objectStatus "J9L1.198" )
				)
				( pin "vss(24)"
					( attribute "PN" "195"
						( Origin gPackager )
					)
					( objectStatus "J9L1.195" )
				)
				( pin "vss(25)"
					( attribute "PN" "193"
						( Origin gPackager )
					)
					( objectStatus "J9L1.193" )
				)
				( pin "vss(26)"
					( attribute "PN" "191"
						( Origin gPackager )
					)
					( objectStatus "J9L1.191" )
				)
				( pin "vss(27)"
					( attribute "PN" "189"
						( Origin gPackager )
					)
					( objectStatus "J9L1.189" )
				)
				( pin "vss(28)"
					( attribute "PN" "187"
						( Origin gPackager )
					)
					( objectStatus "J9L1.187" )
				)
				( pin "vss(29)"
					( attribute "PN" "184"
						( Origin gPackager )
					)
					( objectStatus "J9L1.184" )
				)
				( pin "vss(30)"
					( attribute "PN" "182"
						( Origin gPackager )
					)
					( objectStatus "J9L1.182" )
				)
				( pin "vss(31)"
					( attribute "PN" "180"
						( Origin gPackager )
					)
					( objectStatus "J9L1.180" )
				)
				( pin "vss(32)"
					( attribute "PN" "178"
						( Origin gPackager )
					)
					( objectStatus "J9L1.178" )
				)
				( pin "vss(33)"
					( attribute "PN" "176"
						( Origin gPackager )
					)
					( objectStatus "J9L1.176" )
				)
				( pin "vss(34)"
					( attribute "PN" "173"
						( Origin gPackager )
					)
					( objectStatus "J9L1.173" )
				)
				( pin "vss(35)"
					( attribute "PN" "171"
						( Origin gPackager )
					)
					( objectStatus "J9L1.171" )
				)
				( pin "vss(36)"
					( attribute "PN" "169"
						( Origin gPackager )
					)
					( objectStatus "J9L1.169" )
				)
				( pin "vss(37)"
					( attribute "PN" "167"
						( Origin gPackager )
					)
					( objectStatus "J9L1.167" )
				)
				( pin "vss(38)"
					( attribute "PN" "165"
						( Origin gPackager )
					)
					( objectStatus "J9L1.165" )
				)
				( pin "vss(39)"
					( attribute "PN" "162"
						( Origin gPackager )
					)
					( objectStatus "J9L1.162" )
				)
				( pin "vss(40)"
					( attribute "PN" "160"
						( Origin gPackager )
					)
					( objectStatus "J9L1.160" )
				)
				( pin "vss(41)"
					( attribute "PN" "158"
						( Origin gPackager )
					)
					( objectStatus "J9L1.158" )
				)
				( pin "vss(42)"
					( attribute "PN" "156"
						( Origin gPackager )
					)
					( objectStatus "J9L1.156" )
				)
				( pin "vss(43)"
					( attribute "PN" "154"
						( Origin gPackager )
					)
					( objectStatus "J9L1.154" )
				)
				( pin "vss(44)"
					( attribute "PN" "151"
						( Origin gPackager )
					)
					( objectStatus "J9L1.151" )
				)
				( pin "vss(45)"
					( attribute "PN" "149"
						( Origin gPackager )
					)
					( objectStatus "J9L1.149" )
				)
				( pin "vss(46)"
					( attribute "PN" "147"
						( Origin gPackager )
					)
					( objectStatus "J9L1.147" )
				)
				( pin "vss(47)"
					( attribute "PN" "138"
						( Origin gPackager )
					)
					( objectStatus "J9L1.138" )
				)
				( pin "vss(48)"
					( attribute "PN" "136"
						( Origin gPackager )
					)
					( objectStatus "J9L1.136" )
				)
				( pin "vss(49)"
					( attribute "PN" "134"
						( Origin gPackager )
					)
					( objectStatus "J9L1.134" )
				)
				( pin "vss(50)"
					( attribute "PN" "131"
						( Origin gPackager )
					)
					( objectStatus "J9L1.131" )
				)
				( pin "vss(51)"
					( attribute "PN" "129"
						( Origin gPackager )
					)
					( objectStatus "J9L1.129" )
				)
				( pin "vss(52)"
					( attribute "PN" "127"
						( Origin gPackager )
					)
					( objectStatus "J9L1.127" )
				)
				( pin "vss(53)"
					( attribute "PN" "125"
						( Origin gPackager )
					)
					( objectStatus "J9L1.125" )
				)
				( pin "vss(54)"
					( attribute "PN" "123"
						( Origin gPackager )
					)
					( objectStatus "J9L1.123" )
				)
				( pin "vss(55)"
					( attribute "PN" "120"
						( Origin gPackager )
					)
					( objectStatus "J9L1.120" )
				)
				( pin "vss(56)"
					( attribute "PN" "118"
						( Origin gPackager )
					)
					( objectStatus "J9L1.118" )
				)
				( pin "vss(57)"
					( attribute "PN" "116"
						( Origin gPackager )
					)
					( objectStatus "J9L1.116" )
				)
				( pin "vss(58)"
					( attribute "PN" "114"
						( Origin gPackager )
					)
					( objectStatus "J9L1.114" )
				)
				( pin "vss(59)"
					( attribute "PN" "112"
						( Origin gPackager )
					)
					( objectStatus "J9L1.112" )
				)
				( pin "vss(60)"
					( attribute "PN" "109"
						( Origin gPackager )
					)
					( objectStatus "J9L1.109" )
				)
				( pin "vss(61)"
					( attribute "PN" "107"
						( Origin gPackager )
					)
					( objectStatus "J9L1.107" )
				)
				( pin "vss(62)"
					( attribute "PN" "105"
						( Origin gPackager )
					)
					( objectStatus "J9L1.105" )
				)
				( pin "vss(63)"
					( attribute "PN" "103"
						( Origin gPackager )
					)
					( objectStatus "J9L1.103" )
				)
				( pin "vss(64)"
					( attribute "PN" "101"
						( Origin gPackager )
					)
					( objectStatus "J9L1.101" )
				)
				( pin "vss(65)"
					( attribute "PN" "98"
						( Origin gPackager )
					)
					( objectStatus "J9L1.98" )
				)
				( pin "vss(66)"
					( attribute "PN" "96"
						( Origin gPackager )
					)
					( objectStatus "J9L1.96" )
				)
				( pin "vss(67)"
					( attribute "PN" "94"
						( Origin gPackager )
					)
					( objectStatus "J9L1.94" )
				)
				( pin "vss(68)"
					( attribute "PN" "57"
						( Origin gPackager )
					)
					( objectStatus "J9L1.57" )
				)
				( pin "vss(69)"
					( attribute "PN" "55"
						( Origin gPackager )
					)
					( objectStatus "J9L1.55" )
				)
				( pin "vss(70)"
					( attribute "PN" "53"
						( Origin gPackager )
					)
					( objectStatus "J9L1.53" )
				)
				( pin "vss(71)"
					( attribute "PN" "50"
						( Origin gPackager )
					)
					( objectStatus "J9L1.50" )
				)
				( pin "vss(72)"
					( attribute "PN" "48"
						( Origin gPackager )
					)
					( objectStatus "J9L1.48" )
				)
				( pin "vss(73)"
					( attribute "PN" "46"
						( Origin gPackager )
					)
					( objectStatus "J9L1.46" )
				)
				( pin "vss(74)"
					( attribute "PN" "44"
						( Origin gPackager )
					)
					( objectStatus "J9L1.44" )
				)
				( pin "vss(75)"
					( attribute "PN" "42"
						( Origin gPackager )
					)
					( objectStatus "J9L1.42" )
				)
				( pin "vss(76)"
					( attribute "PN" "39"
						( Origin gPackager )
					)
					( objectStatus "J9L1.39" )
				)
				( pin "vss(77)"
					( attribute "PN" "37"
						( Origin gPackager )
					)
					( objectStatus "J9L1.37" )
				)
				( pin "vss(78)"
					( attribute "PN" "35"
						( Origin gPackager )
					)
					( objectStatus "J9L1.35" )
				)
				( pin "vss(79)"
					( attribute "PN" "33"
						( Origin gPackager )
					)
					( objectStatus "J9L1.33" )
				)
				( pin "vss(80)"
					( attribute "PN" "31"
						( Origin gPackager )
					)
					( objectStatus "J9L1.31" )
				)
				( pin "vss(81)"
					( attribute "PN" "28"
						( Origin gPackager )
					)
					( objectStatus "J9L1.28" )
				)
				( pin "vss(82)"
					( attribute "PN" "26"
						( Origin gPackager )
					)
					( objectStatus "J9L1.26" )
				)
				( pin "vss(83)"
					( attribute "PN" "24"
						( Origin gPackager )
					)
					( objectStatus "J9L1.24" )
				)
				( pin "vss(84)"
					( attribute "PN" "22"
						( Origin gPackager )
					)
					( objectStatus "J9L1.22" )
				)
				( pin "vss(85)"
					( attribute "PN" "20"
						( Origin gPackager )
					)
					( objectStatus "J9L1.20" )
				)
				( pin "vss(86)"
					( attribute "PN" "17"
						( Origin gPackager )
					)
					( objectStatus "J9L1.17" )
				)
				( pin "vss(87)"
					( attribute "PN" "15"
						( Origin gPackager )
					)
					( objectStatus "J9L1.15" )
				)
				( pin "vss(88)"
					( attribute "PN" "13"
						( Origin gPackager )
					)
					( objectStatus "J9L1.13" )
				)
				( pin "vss(89)"
					( attribute "PN" "11"
						( Origin gPackager )
					)
					( objectStatus "J9L1.11" )
				)
				( pin "vss(90)"
					( attribute "PN" "9"
						( Origin gPackager )
					)
					( objectStatus "J9L1.9" )
				)
				( pin "vss(91)"
					( attribute "PN" "6"
						( Origin gPackager )
					)
					( objectStatus "J9L1.6" )
				)
				( pin "vss(92)"
					( attribute "PN" "4"
						( Origin gPackager )
					)
					( objectStatus "J9L1.4" )
				)
				( pin "vss(93)"
					( attribute "PN" "2"
						( Origin gPackager )
					)
					( objectStatus "J9L1.2" )
				)
			)
			( gate "@baseboard_fab2_lib.baseboard_fab2(sch_1):page88_i87"
				( attribute "BOM_COST" "DDR4_CH_M"
					( Origin gFrontEnd )
				)
				( attribute "CDS_LIB" "mstr_sconn"
					( Origin gPackager )
				)
				( attribute "CDS_LOCATION" "J9L1"
					( Origin gPackager )
				)
				( attribute "CDS_SEC" "2"
					( Origin gPackager )
				)
				( attribute "LOCATION" "J9L1"
					( Origin gFrontEnd )
				)
				( attribute "MATERIAL" "SCONN"
					( Origin gFrontEnd )
				)
				( attribute "PACK_TYPE" "PIP"
					( Origin gFrontEnd )
				)
				( attribute "PART_NUMBER" "H44441-003"
					( Origin gFrontEnd )
				)
				( attribute "PHYS_PAGE" "88"
					( Origin gFrontEnd )
				)
				( attribute "ROOM" "DDR4_CH_M"
					( Origin gFrontEnd )
				)
				( attribute "ROT" "0"
					( Origin gFrontEnd )
				)
				( attribute "SEC" "2"
					( Origin gFrontEnd )
				)
				( attribute "SEC_TYPE" "PIP"
					( Origin gFrontEnd )
				)
				( attribute "VER" "2"
					( Origin gFrontEnd )
				)
				( attribute "XY" "(0,4300)"
					( Origin gFrontEnd )
				)
				( attribute "CHIPS_PART_NAME" "SCONN288_H44441003"
					( Origin gPackager )
				)
				( attribute "CDS_PART_NAME" "SCONN288_H44441003_PIP-SCONN,HA"
					( Origin gPackager )
				)
				( objectStatus "J9L1" )
				( pin "dqs0n"
					( attribute "PN" "152"
						( Origin gPackager )
					)
					( objectStatus "J9L1.152" )
				)
				( pin "dqs0p"
					( attribute "PN" "153"
						( Origin gPackager )
					)
					( objectStatus "J9L1.153" )
				)
				( pin "dqs1n"
					( attribute "PN" "163"
						( Origin gPackager )
					)
					( objectStatus "J9L1.163" )
				)
				( pin "dqs1p"
					( attribute "PN" "164"
						( Origin gPackager )
					)
					( objectStatus "J9L1.164" )
				)
				( pin "dqs2n"
					( attribute "PN" "174"
						( Origin gPackager )
					)
					( objectStatus "J9L1.174" )
				)
				( pin "dqs2p"
					( attribute "PN" "175"
						( Origin gPackager )
					)
					( objectStatus "J9L1.175" )
				)
				( pin "dqs3n"
					( attribute "PN" "185"
						( Origin gPackager )
					)
					( objectStatus "J9L1.185" )
				)
				( pin "dqs3p"
					( attribute "PN" "186"
						( Origin gPackager )
					)
					( objectStatus "J9L1.186" )
				)
				( pin "dqs4n"
					( attribute "PN" "244"
						( Origin gPackager )
					)
					( objectStatus "J9L1.244" )
				)
				( pin "dqs4p"
					( attribute "PN" "245"
						( Origin gPackager )
					)
					( objectStatus "J9L1.245" )
				)
				( pin "dqs5n"
					( attribute "PN" "255"
						( Origin gPackager )
					)
					( objectStatus "J9L1.255" )
				)
				( pin "dqs5p"
					( attribute "PN" "256"
						( Origin gPackager )
					)
					( objectStatus "J9L1.256" )
				)
				( pin "dqs6n"
					( attribute "PN" "266"
						( Origin gPackager )
					)
					( objectStatus "J9L1.266" )
				)
				( pin "dqs6p"
					( attribute "PN" "267"
						( Origin gPackager )
					)
					( objectStatus "J9L1.267" )
				)
				( pin "dqs7n"
					( attribute "PN" "277"
						( Origin gPackager )
					)
					( objectStatus "J9L1.277" )
				)
				( pin "dqs7p"
					( attribute "PN" "278"
						( Origin gPackager )
					)
					( objectStatus "J9L1.278" )
				)
				( pin "dqs8n"
					( attribute "PN" "196"
						( Origin gPackager )
					)
					( objectStatus "J9L1.196" )
				)
				( pin "dqs8p"
					( attribute "PN" "197"
						( Origin gPackager )
					)
					( objectStatus "J9L1.197" )
				)
				( pin "dqs9n"
					( attribute "PN" "8"
						( Origin gPackager )
					)
					( objectStatus "J9L1.8" )
				)
				( pin "dqs9p"
					( attribute "PN" "7"
						( Origin gPackager )
					)
					( objectStatus "J9L1.7" )
				)
				( pin "dqs10n"
					( attribute "PN" "19"
						( Origin gPackager )
					)
					( objectStatus "J9L1.19" )
				)
				( pin "dqs10p"
					( attribute "PN" "18"
						( Origin gPackager )
					)
					( objectStatus "J9L1.18" )
				)
				( pin "dqs11n"
					( attribute "PN" "30"
						( Origin gPackager )
					)
					( objectStatus "J9L1.30" )
				)
				( pin "dqs11p"
					( attribute "PN" "29"
						( Origin gPackager )
					)
					( objectStatus "J9L1.29" )
				)
				( pin "dqs12n"
					( attribute "PN" "41"
						( Origin gPackager )
					)
					( objectStatus "J9L1.41" )
				)
				( pin "dqs12p"
					( attribute "PN" "40"
						( Origin gPackager )
					)
					( objectStatus "J9L1.40" )
				)
				( pin "dqs13n"
					( attribute "PN" "100"
						( Origin gPackager )
					)
					( objectStatus "J9L1.100" )
				)
				( pin "dqs13p"
					( attribute "PN" "99"
						( Origin gPackager )
					)
					( objectStatus "J9L1.99" )
				)
				( pin "dqs14n"
					( attribute "PN" "111"
						( Origin gPackager )
					)
					( objectStatus "J9L1.111" )
				)
				( pin "dqs14p"
					( attribute "PN" "110"
						( Origin gPackager )
					)
					( objectStatus "J9L1.110" )
				)
				( pin "dqs15n"
					( attribute "PN" "122"
						( Origin gPackager )
					)
					( objectStatus "J9L1.122" )
				)
				( pin "dqs15p"
					( attribute "PN" "121"
						( Origin gPackager )
					)
					( objectStatus "J9L1.121" )
				)
				( pin "dqs16n"
					( attribute "PN" "133"
						( Origin gPackager )
					)
					( objectStatus "J9L1.133" )
				)
				( pin "dqs16p"
					( attribute "PN" "132"
						( Origin gPackager )
					)
					( objectStatus "J9L1.132" )
				)
				( pin "dqs17n"
					( attribute "PN" "52"
						( Origin gPackager )
					)
					( objectStatus "J9L1.52" )
				)
				( pin "dqs17p"
					( attribute "PN" "51"
						( Origin gPackager )
					)
					( objectStatus "J9L1.51" )
				)
			)
			( gate "@baseboard_fab2_lib.baseboard_fab2(sch_1):page88_i111"
				( attribute "BOM_COST" "DDR4_CH_M"
					( Origin gFrontEnd )
				)
				( attribute "CDS_LIB" "mstr_sconn"
					( Origin gPackager )
				)
				( attribute "CDS_LOCATION" "J9L1"
					( Origin gPackager )
				)
				( attribute "CDS_SEC" "1"
					( Origin gPackager )
				)
				( attribute "LOCATION" "J9L1"
					( Origin gFrontEnd )
				)
				( attribute "MATERIAL" "SCONN"
					( Origin gFrontEnd )
				)
				( attribute "PACK_TYPE" "PIP"
					( Origin gFrontEnd )
				)
				( attribute "PART_NUMBER" "H44441-003"
					( Origin gFrontEnd )
				)
				( attribute "PHYS_PAGE" "88"
					( Origin gFrontEnd )
				)
				( attribute "ROOM" "DDR4_CH_M"
					( Origin gFrontEnd )
				)
				( attribute "ROT" "0"
					( Origin gFrontEnd )
				)
				( attribute "SEC" "1"
					( Origin gFrontEnd )
				)
				( attribute "SEC_TYPE" "PIP"
					( Origin gFrontEnd )
				)
				( attribute "VER" "1"
					( Origin gFrontEnd )
				)
				( attribute "XY" "(-2450,3100)"
					( Origin gFrontEnd )
				)
				( attribute "CHIPS_PART_NAME" "SCONN288_H44441003"
					( Origin gPackager )
				)
				( attribute "CDS_PART_NAME" "SCONN288_H44441003_PIP-SCONN,HA"
					( Origin gPackager )
				)
				( objectStatus "J9L1" )
				( pin "a0"
					( attribute "PN" "79"
						( Origin gPackager )
					)
					( objectStatus "J9L1.79" )
				)
				( pin "a1"
					( attribute "PN" "72"
						( Origin gPackager )
					)
					( objectStatus "J9L1.72" )
				)
				( pin "a2"
					( attribute "PN" "216"
						( Origin gPackager )
					)
					( objectStatus "J9L1.216" )
				)
				( pin "a3"
					( attribute "PN" "71"
						( Origin gPackager )
					)
					( objectStatus "J9L1.71" )
				)
				( pin "a4"
					( attribute "PN" "214"
						( Origin gPackager )
					)
					( objectStatus "J9L1.214" )
				)
				( pin "a5"
					( attribute "PN" "213"
						( Origin gPackager )
					)
					( objectStatus "J9L1.213" )
				)
				( pin "a6"
					( attribute "PN" "69"
						( Origin gPackager )
					)
					( objectStatus "J9L1.69" )
				)
				( pin "a7"
					( attribute "PN" "211"
						( Origin gPackager )
					)
					( objectStatus "J9L1.211" )
				)
				( pin "a8"
					( attribute "PN" "68"
						( Origin gPackager )
					)
					( objectStatus "J9L1.68" )
				)
				( pin "a9"
					( attribute "PN" "66"
						( Origin gPackager )
					)
					( objectStatus "J9L1.66" )
				)
				( pin "a10"
					( attribute "PN" "225"
						( Origin gPackager )
					)
					( objectStatus "J9L1.225" )
				)
				( pin "a11"
					( attribute "PN" "210"
						( Origin gPackager )
					)
					( objectStatus "J9L1.210" )
				)
				( pin "a12"
					( attribute "PN" "65"
						( Origin gPackager )
					)
					( objectStatus "J9L1.65" )
				)
				( pin "a13"
					( attribute "PN" "232"
						( Origin gPackager )
					)
					( objectStatus "J9L1.232" )
				)
				( pin "a14_we_n"
					( attribute "PN" "228"
						( Origin gPackager )
					)
					( objectStatus "J9L1.228" )
				)
				( pin "a15_cas_n"
					( attribute "PN" "86"
						( Origin gPackager )
					)
					( objectStatus "J9L1.86" )
				)
				( pin "a16_ras_n"
					( attribute "PN" "82"
						( Origin gPackager )
					)
					( objectStatus "J9L1.82" )
				)
				( pin "a17"
					( attribute "PN" "234"
						( Origin gPackager )
					)
					( objectStatus "J9L1.234" )
				)
				( pin "act_n"
					( attribute "PN" "62"
						( Origin gPackager )
					)
					( objectStatus "J9L1.62" )
				)
				( pin "alert_n"
					( attribute "PN" "208"
						( Origin gPackager )
					)
					( objectStatus "J9L1.208" )
				)
				( pin "ba(0)"
					( attribute "PN" "81"
						( Origin gPackager )
					)
					( objectStatus "J9L1.81" )
				)
				( pin "ba(1)"
					( attribute "PN" "224"
						( Origin gPackager )
					)
					( objectStatus "J9L1.224" )
				)
				( pin "bg(0)"
					( attribute "PN" "63"
						( Origin gPackager )
					)
					( objectStatus "J9L1.63" )
				)
				( pin "bg(1)"
					( attribute "PN" "207"
						( Origin gPackager )
					)
					( objectStatus "J9L1.207" )
				)
				( pin "c(2)"
					( attribute "PN" "235"
						( Origin gPackager )
					)
					( objectStatus "J9L1.235" )
				)
				( pin "cb(0)"
					( attribute "PN" "49"
						( Origin gPackager )
					)
					( objectStatus "J9L1.49" )
				)
				( pin "cb(1)"
					( attribute "PN" "194"
						( Origin gPackager )
					)
					( objectStatus "J9L1.194" )
				)
				( pin "cb(2)"
					( attribute "PN" "56"
						( Origin gPackager )
					)
					( objectStatus "J9L1.56" )
				)
				( pin "cb(3)"
					( attribute "PN" "201"
						( Origin gPackager )
					)
					( objectStatus "J9L1.201" )
				)
				( pin "cb(4)"
					( attribute "PN" "47"
						( Origin gPackager )
					)
					( objectStatus "J9L1.47" )
				)
				( pin "cb(5)"
					( attribute "PN" "192"
						( Origin gPackager )
					)
					( objectStatus "J9L1.192" )
				)
				( pin "cb(6)"
					( attribute "PN" "54"
						( Origin gPackager )
					)
					( objectStatus "J9L1.54" )
				)
				( pin "cb(7)"
					( attribute "PN" "199"
						( Origin gPackager )
					)
					( objectStatus "J9L1.199" )
				)
				( pin "ck0n"
					( attribute "PN" "75"
						( Origin gPackager )
					)
					( objectStatus "J9L1.75" )
				)
				( pin "ck0p"
					( attribute "PN" "74"
						( Origin gPackager )
					)
					( objectStatus "J9L1.74" )
				)
				( pin "ck1n"
					( attribute "PN" "219"
						( Origin gPackager )
					)
					( objectStatus "J9L1.219" )
				)
				( pin "ck1p"
					( attribute "PN" "218"
						( Origin gPackager )
					)
					( objectStatus "J9L1.218" )
				)
				( pin "cke(0)"
					( attribute "PN" "60"
						( Origin gPackager )
					)
					( objectStatus "J9L1.60" )
				)
				( pin "cke(1)"
					( attribute "PN" "203"
						( Origin gPackager )
					)
					( objectStatus "J9L1.203" )
				)
				( pin "dq(0)"
					( attribute "PN" "5"
						( Origin gPackager )
					)
					( objectStatus "J9L1.5" )
				)
				( pin "dq(1)"
					( attribute "PN" "150"
						( Origin gPackager )
					)
					( objectStatus "J9L1.150" )
				)
				( pin "dq(2)"
					( attribute "PN" "12"
						( Origin gPackager )
					)
					( objectStatus "J9L1.12" )
				)
				( pin "dq(3)"
					( attribute "PN" "157"
						( Origin gPackager )
					)
					( objectStatus "J9L1.157" )
				)
				( pin "dq(4)"
					( attribute "PN" "3"
						( Origin gPackager )
					)
					( objectStatus "J9L1.3" )
				)
				( pin "dq(5)"
					( attribute "PN" "148"
						( Origin gPackager )
					)
					( objectStatus "J9L1.148" )
				)
				( pin "dq(6)"
					( attribute "PN" "10"
						( Origin gPackager )
					)
					( objectStatus "J9L1.10" )
				)
				( pin "dq(7)"
					( attribute "PN" "155"
						( Origin gPackager )
					)
					( objectStatus "J9L1.155" )
				)
				( pin "dq(8)"
					( attribute "PN" "16"
						( Origin gPackager )
					)
					( objectStatus "J9L1.16" )
				)
				( pin "dq(9)"
					( attribute "PN" "161"
						( Origin gPackager )
					)
					( objectStatus "J9L1.161" )
				)
				( pin "dq(10)"
					( attribute "PN" "23"
						( Origin gPackager )
					)
					( objectStatus "J9L1.23" )
				)
				( pin "dq(11)"
					( attribute "PN" "168"
						( Origin gPackager )
					)
					( objectStatus "J9L1.168" )
				)
				( pin "dq(12)"
					( attribute "PN" "14"
						( Origin gPackager )
					)
					( objectStatus "J9L1.14" )
				)
				( pin "dq(13)"
					( attribute "PN" "159"
						( Origin gPackager )
					)
					( objectStatus "J9L1.159" )
				)
				( pin "dq(14)"
					( attribute "PN" "21"
						( Origin gPackager )
					)
					( objectStatus "J9L1.21" )
				)
				( pin "dq(15)"
					( attribute "PN" "166"
						( Origin gPackager )
					)
					( objectStatus "J9L1.166" )
				)
				( pin "dq(16)"
					( attribute "PN" "27"
						( Origin gPackager )
					)
					( objectStatus "J9L1.27" )
				)
				( pin "dq(17)"
					( attribute "PN" "172"
						( Origin gPackager )
					)
					( objectStatus "J9L1.172" )
				)
				( pin "dq(18)"
					( attribute "PN" "34"
						( Origin gPackager )
					)
					( objectStatus "J9L1.34" )
				)
				( pin "dq(19)"
					( attribute "PN" "179"
						( Origin gPackager )
					)
					( objectStatus "J9L1.179" )
				)
				( pin "dq(20)"
					( attribute "PN" "25"
						( Origin gPackager )
					)
					( objectStatus "J9L1.25" )
				)
				( pin "dq(21)"
					( attribute "PN" "170"
						( Origin gPackager )
					)
					( objectStatus "J9L1.170" )
				)
				( pin "dq(22)"
					( attribute "PN" "32"
						( Origin gPackager )
					)
					( objectStatus "J9L1.32" )
				)
				( pin "dq(23)"
					( attribute "PN" "177"
						( Origin gPackager )
					)
					( objectStatus "J9L1.177" )
				)
				( pin "dq(24)"
					( attribute "PN" "38"
						( Origin gPackager )
					)
					( objectStatus "J9L1.38" )
				)
				( pin "dq(25)"
					( attribute "PN" "183"
						( Origin gPackager )
					)
					( objectStatus "J9L1.183" )
				)
				( pin "dq(26)"
					( attribute "PN" "45"
						( Origin gPackager )
					)
					( objectStatus "J9L1.45" )
				)
				( pin "dq(27)"
					( attribute "PN" "190"
						( Origin gPackager )
					)
					( objectStatus "J9L1.190" )
				)
				( pin "dq(28)"
					( attribute "PN" "36"
						( Origin gPackager )
					)
					( objectStatus "J9L1.36" )
				)
				( pin "dq(29)"
					( attribute "PN" "181"
						( Origin gPackager )
					)
					( objectStatus "J9L1.181" )
				)
				( pin "dq(30)"
					( attribute "PN" "43"
						( Origin gPackager )
					)
					( objectStatus "J9L1.43" )
				)
				( pin "dq(31)"
					( attribute "PN" "188"
						( Origin gPackager )
					)
					( objectStatus "J9L1.188" )
				)
				( pin "dq(32)"
					( attribute "PN" "97"
						( Origin gPackager )
					)
					( objectStatus "J9L1.97" )
				)
				( pin "dq(33)"
					( attribute "PN" "242"
						( Origin gPackager )
					)
					( objectStatus "J9L1.242" )
				)
				( pin "dq(34)"
					( attribute "PN" "104"
						( Origin gPackager )
					)
					( objectStatus "J9L1.104" )
				)
				( pin "dq(35)"
					( attribute "PN" "249"
						( Origin gPackager )
					)
					( objectStatus "J9L1.249" )
				)
				( pin "dq(36)"
					( attribute "PN" "95"
						( Origin gPackager )
					)
					( objectStatus "J9L1.95" )
				)
				( pin "dq(37)"
					( attribute "PN" "240"
						( Origin gPackager )
					)
					( objectStatus "J9L1.240" )
				)
				( pin "dq(38)"
					( attribute "PN" "102"
						( Origin gPackager )
					)
					( objectStatus "J9L1.102" )
				)
				( pin "dq(39)"
					( attribute "PN" "247"
						( Origin gPackager )
					)
					( objectStatus "J9L1.247" )
				)
				( pin "dq(40)"
					( attribute "PN" "108"
						( Origin gPackager )
					)
					( objectStatus "J9L1.108" )
				)
				( pin "dq(41)"
					( attribute "PN" "253"
						( Origin gPackager )
					)
					( objectStatus "J9L1.253" )
				)
				( pin "dq(42)"
					( attribute "PN" "115"
						( Origin gPackager )
					)
					( objectStatus "J9L1.115" )
				)
				( pin "dq(43)"
					( attribute "PN" "260"
						( Origin gPackager )
					)
					( objectStatus "J9L1.260" )
				)
				( pin "dq(44)"
					( attribute "PN" "106"
						( Origin gPackager )
					)
					( objectStatus "J9L1.106" )
				)
				( pin "dq(45)"
					( attribute "PN" "251"
						( Origin gPackager )
					)
					( objectStatus "J9L1.251" )
				)
				( pin "dq(46)"
					( attribute "PN" "113"
						( Origin gPackager )
					)
					( objectStatus "J9L1.113" )
				)
				( pin "dq(47)"
					( attribute "PN" "258"
						( Origin gPackager )
					)
					( objectStatus "J9L1.258" )
				)
				( pin "dq(48)"
					( attribute "PN" "119"
						( Origin gPackager )
					)
					( objectStatus "J9L1.119" )
				)
				( pin "dq(49)"
					( attribute "PN" "264"
						( Origin gPackager )
					)
					( objectStatus "J9L1.264" )
				)
				( pin "dq(50)"
					( attribute "PN" "126"
						( Origin gPackager )
					)
					( objectStatus "J9L1.126" )
				)
				( pin "dq(51)"
					( attribute "PN" "271"
						( Origin gPackager )
					)
					( objectStatus "J9L1.271" )
				)
				( pin "dq(52)"
					( attribute "PN" "117"
						( Origin gPackager )
					)
					( objectStatus "J9L1.117" )
				)
				( pin "dq(53)"
					( attribute "PN" "262"
						( Origin gPackager )
					)
					( objectStatus "J9L1.262" )
				)
				( pin "dq(54)"
					( attribute "PN" "124"
						( Origin gPackager )
					)
					( objectStatus "J9L1.124" )
				)
				( pin "dq(55)"
					( attribute "PN" "269"
						( Origin gPackager )
					)
					( objectStatus "J9L1.269" )
				)
				( pin "dq(56)"
					( attribute "PN" "130"
						( Origin gPackager )
					)
					( objectStatus "J9L1.130" )
				)
				( pin "dq(57)"
					( attribute "PN" "275"
						( Origin gPackager )
					)
					( objectStatus "J9L1.275" )
				)
				( pin "dq(58)"
					( attribute "PN" "137"
						( Origin gPackager )
					)
					( objectStatus "J9L1.137" )
				)
				( pin "dq(59)"
					( attribute "PN" "282"
						( Origin gPackager )
					)
					( objectStatus "J9L1.282" )
				)
				( pin "dq(60)"
					( attribute "PN" "128"
						( Origin gPackager )
					)
					( objectStatus "J9L1.128" )
				)
				( pin "dq(61)"
					( attribute "PN" "273"
						( Origin gPackager )
					)
					( objectStatus "J9L1.273" )
				)
				( pin "dq(62)"
					( attribute "PN" "135"
						( Origin gPackager )
					)
					( objectStatus "J9L1.135" )
				)
				( pin "dq(63)"
					( attribute "PN" "280"
						( Origin gPackager )
					)
					( objectStatus "J9L1.280" )
				)
				( pin "event_n"
					( attribute "PN" "78"
						( Origin gPackager )
					)
					( objectStatus "J9L1.78" )
				)
				( pin "odt(0)"
					( attribute "PN" "87"
						( Origin gPackager )
					)
					( objectStatus "J9L1.87" )
				)
				( pin "odt(1)"
					( attribute "PN" "91"
						( Origin gPackager )
					)
					( objectStatus "J9L1.91" )
				)
				( pin "par"
					( attribute "PN" "222"
						( Origin gPackager )
					)
					( objectStatus "J9L1.222" )
				)
				( pin "reset_n"
					( attribute "PN" "58"
						( Origin gPackager )
					)
					( objectStatus "J9L1.58" )
				)
				( pin "rfu(0)"
					( attribute "PN" "205"
						( Origin gPackager )
					)
					( objectStatus "J9L1.205" )
				)
				( pin "rfu(1)"
					( attribute "PN" "227"
						( Origin gPackager )
					)
					( objectStatus "J9L1.227" )
				)
				( pin "rfu(2)"
					( attribute "PN" "144"
						( Origin gPackager )
					)
					( objectStatus "J9L1.144" )
				)
				( pin "s0_n"
					( attribute "PN" "84"
						( Origin gPackager )
					)
					( objectStatus "J9L1.84" )
				)
				( pin "s1_n"
					( attribute "PN" "89"
						( Origin gPackager )
					)
					( objectStatus "J9L1.89" )
				)
				( pin "s2_n_c(0)"
					( attribute "PN" "93"
						( Origin gPackager )
					)
					( objectStatus "J9L1.93" )
				)
				( pin "s3_n_c(1)"
					( attribute "PN" "237"
						( Origin gPackager )
					)
					( objectStatus "J9L1.237" )
				)
				( pin "sa(0)"
					( attribute "PN" "139"
						( Origin gPackager )
					)
					( objectStatus "J9L1.139" )
				)
				( pin "sa(1)"
					( attribute "PN" "140"
						( Origin gPackager )
					)
					( objectStatus "J9L1.140" )
				)
				( pin "sa(2)"
					( attribute "PN" "238"
						( Origin gPackager )
					)
					( objectStatus "J9L1.238" )
				)
				( pin "save_n_nc"
					( attribute "PN" "230"
						( Origin gPackager )
					)
					( objectStatus "J9L1.230" )
				)
				( pin "scl"
					( attribute "PN" "141"
						( Origin gPackager )
					)
					( objectStatus "J9L1.141" )
				)
				( pin "sda"
					( attribute "PN" "285"
						( Origin gPackager )
					)
					( objectStatus "J9L1.285" )
				)
				( pin "vddspd"
					( attribute "PN" "284"
						( Origin gPackager )
					)
					( objectStatus "J9L1.284" )
				)
				( pin "vrefca"
					( attribute "PN" "146"
						( Origin gPackager )
					)
					( objectStatus "J9L1.146" )
				)
			)
			( gate "@baseboard_fab2_lib.baseboard_fab2(sch_1):page88_i168"
				( attribute "BOM_COST" "MEM"
					( Origin gFrontEnd )
				)
				( attribute "CDS_LIB" "mstr_sconn"
					( Origin gPackager )
				)
				( attribute "CDS_LOCATION" "J9L1"
					( Origin gPackager )
				)
				( attribute "CDS_SEC" "4"
					( Origin gPackager )
				)
				( attribute "LOCATION" "J9L1"
					( Origin gFrontEnd )
				)
				( attribute "MATERIAL" "SCONN"
					( Origin gFrontEnd )
				)
				( attribute "PACK_TYPE" "PIP"
					( Origin gFrontEnd )
				)
				( attribute "PART_NUMBER" "H44441-003"
					( Origin gFrontEnd )
				)
				( attribute "PHYS_PAGE" "88"
					( Origin gFrontEnd )
				)
				( attribute "ROOM" "DDR4_CH_M"
					( Origin gFrontEnd )
				)
				( attribute "ROT" "0"
					( Origin gFrontEnd )
				)
				( attribute "SEC" "4"
					( Origin gFrontEnd )
				)
				( attribute "SEC_TYPE" "PIP"
					( Origin gFrontEnd )
				)
				( attribute "VER" "4"
					( Origin gFrontEnd )
				)
				( attribute "XY" "(-300,2000)"
					( Origin gFrontEnd )
				)
				( attribute "CHIPS_PART_NAME" "SCONN288_H44441003"
					( Origin gPackager )
				)
				( attribute "CDS_PART_NAME" "SCONN288_H44441003_PIP-SCONN,HA"
					( Origin gPackager )
				)
				( objectStatus "J9L1" )
				( pin "\12v\(0)"
					( attribute "PN" "145"
						( Origin gPackager )
					)
					( objectStatus "J9L1.145" )
				)
				( pin "\12v\(1)"
					( attribute "PN" "1"
						( Origin gPackager )
					)
					( objectStatus "J9L1.1" )
				)
				( pin "vdd(0)"
					( attribute "PN" "236"
						( Origin gPackager )
					)
					( objectStatus "J9L1.236" )
				)
				( pin "vdd(1)"
					( attribute "PN" "233"
						( Origin gPackager )
					)
					( objectStatus "J9L1.233" )
				)
				( pin "vdd(2)"
					( attribute "PN" "231"
						( Origin gPackager )
					)
					( objectStatus "J9L1.231" )
				)
				( pin "vdd(3)"
					( attribute "PN" "229"
						( Origin gPackager )
					)
					( objectStatus "J9L1.229" )
				)
				( pin "vdd(4)"
					( attribute "PN" "226"
						( Origin gPackager )
					)
					( objectStatus "J9L1.226" )
				)
				( pin "vdd(5)"
					( attribute "PN" "223"
						( Origin gPackager )
					)
					( objectStatus "J9L1.223" )
				)
				( pin "vdd(6)"
					( attribute "PN" "220"
						( Origin gPackager )
					)
					( objectStatus "J9L1.220" )
				)
				( pin "vdd(7)"
					( attribute "PN" "217"
						( Origin gPackager )
					)
					( objectStatus "J9L1.217" )
				)
				( pin "vdd(8)"
					( attribute "PN" "215"
						( Origin gPackager )
					)
					( objectStatus "J9L1.215" )
				)
				( pin "vdd(9)"
					( attribute "PN" "212"
						( Origin gPackager )
					)
					( objectStatus "J9L1.212" )
				)
				( pin "vdd(10)"
					( attribute "PN" "209"
						( Origin gPackager )
					)
					( objectStatus "J9L1.209" )
				)
				( pin "vdd(11)"
					( attribute "PN" "206"
						( Origin gPackager )
					)
					( objectStatus "J9L1.206" )
				)
				( pin "vdd(12)"
					( attribute "PN" "204"
						( Origin gPackager )
					)
					( objectStatus "J9L1.204" )
				)
				( pin "vdd(13)"
					( attribute "PN" "92"
						( Origin gPackager )
					)
					( objectStatus "J9L1.92" )
				)
				( pin "vdd(14)"
					( attribute "PN" "90"
						( Origin gPackager )
					)
					( objectStatus "J9L1.90" )
				)
				( pin "vdd(15)"
					( attribute "PN" "88"
						( Origin gPackager )
					)
					( objectStatus "J9L1.88" )
				)
				( pin "vdd(16)"
					( attribute "PN" "85"
						( Origin gPackager )
					)
					( objectStatus "J9L1.85" )
				)
				( pin "vdd(17)"
					( attribute "PN" "83"
						( Origin gPackager )
					)
					( objectStatus "J9L1.83" )
				)
				( pin "vdd(18)"
					( attribute "PN" "80"
						( Origin gPackager )
					)
					( objectStatus "J9L1.80" )
				)
				( pin "vdd(19)"
					( attribute "PN" "76"
						( Origin gPackager )
					)
					( objectStatus "J9L1.76" )
				)
				( pin "vdd(20)"
					( attribute "PN" "73"
						( Origin gPackager )
					)
					( objectStatus "J9L1.73" )
				)
				( pin "vdd(21)"
					( attribute "PN" "70"
						( Origin gPackager )
					)
					( objectStatus "J9L1.70" )
				)
				( pin "vdd(22)"
					( attribute "PN" "67"
						( Origin gPackager )
					)
					( objectStatus "J9L1.67" )
				)
				( pin "vdd(23)"
					( attribute "PN" "64"
						( Origin gPackager )
					)
					( objectStatus "J9L1.64" )
				)
				( pin "vdd(24)"
					( attribute "PN" "61"
						( Origin gPackager )
					)
					( objectStatus "J9L1.61" )
				)
				( pin "vdd(25)"
					( attribute "PN" "59"
						( Origin gPackager )
					)
					( objectStatus "J9L1.59" )
				)
				( pin "vpp(0)"
					( attribute "PN" "287"
						( Origin gPackager )
					)
					( objectStatus "J9L1.287" )
				)
				( pin "vpp(1)"
					( attribute "PN" "286"
						( Origin gPackager )
					)
					( objectStatus "J9L1.286" )
				)
				( pin "vpp(2)"
					( attribute "PN" "288"
						( Origin gPackager )
					)
					( objectStatus "J9L1.288" )
				)
				( pin "vpp(3)"
					( attribute "PN" "143"
						( Origin gPackager )
					)
					( objectStatus "J9L1.143" )
				)
				( pin "vpp(4)"
					( attribute "PN" "142"
						( Origin gPackager )
					)
					( objectStatus "J9L1.142" )
				)
				( pin "vtt(0)"
					( attribute "PN" "221"
						( Origin gPackager )
					)
					( objectStatus "J9L1.221" )
				)
				( pin "vtt(1)"
					( attribute "PN" "77"
						( Origin gPackager )
					)
					( objectStatus "J9L1.77" )
				)
			)
			( gate "@baseboard_fab2_lib.baseboard_fab2(sch_1):page88_i177"
				( attribute "BOM_COST" "MEM"
					( Origin gFrontEnd )
				)
				( attribute "CDS_LIB" "dev_discrete"
					( Origin gPackager )
				)
				( attribute "CDS_LOCATION" "C9L1"
					( Origin gPackager )
				)
				( attribute "CDS_SEC" "1"
					( Origin gPackager )
				)
				( attribute "LOCATION" "C9L1"
					( Origin gFrontEnd )
				)
				( attribute "MATERIAL" "X7R"
					( Origin gFrontEnd )
				)
				( attribute "PACK_TYPE" "0402V"
					( Origin gFrontEnd )
				)
				( attribute "PART_NUMBER" "A36096-045"
					( Origin gFrontEnd )
				)
				( attribute "PHYS_PAGE" "88"
					( Origin gFrontEnd )
				)
				( attribute "ROOM" "DDR4_CH_M1"
					( Origin gFrontEnd )
				)
				( attribute "ROT" "2"
					( Origin gFrontEnd )
				)
				( attribute "SEC" "1"
					( Origin gFrontEnd )
				)
				( attribute "SEC_TYPE" "0402V"
					( Origin gFrontEnd )
				)
				( attribute "TOLERANCE" "10%"
					( Origin gFrontEnd )
				)
				( attribute "VALUE" "0.01UF"
					( Origin gFrontEnd )
				)
				( attribute "VER" "1"
					( Origin gFrontEnd )
				)
				( attribute "VOLTAGE" "25V"
					( Units "uVoltage" "V" 1.000000)
					( Origin gFrontEnd )
				)
				( attribute "XY" "(-4650,1400)"
					( Origin gFrontEnd )
				)
				( attribute "CHIPS_PART_NAME" "CAP_A"
					( Origin gPackager )
				)
				( attribute "CDS_PART_NAME" "CAP_A_0402V-0.01UF,25V,10%,X7RA"
					( Origin gPackager )
				)
				( objectStatus "C9L1" )
				( pin "a"
					( attribute "PN" "1"
						( Origin gPackager )
					)
					( objectStatus "C9L1.1" )
				)
				( pin "b"
					( attribute "PN" "2"
						( Origin gPackager )
					)
					( objectStatus "C9L1.2" )
				)
			)
			( gate "@baseboard_fab2_lib.baseboard_fab2(sch_1):page89_i1"
				( attribute "BOM_COST" "MEM_NV"
					( Origin gFrontEnd )
				)
				( attribute "CDS_LIB" "mstr_discrete"
					( Origin gPackager )
				)
				( attribute "CDS_LOCATION" "R4T2"
					( Origin gPackager )
				)
				( attribute "CDS_SEC" "1"
					( Origin gPackager )
				)
				( attribute "LOCATION" "R4T2"
					( Origin gFrontEnd )
				)
				( attribute "MATERIAL" "EMPTY"
					( Origin gFrontEnd )
				)
				( attribute "PACK_TYPE" "0402"
					( Origin gFrontEnd )
				)
				( attribute "PART_NUMBER" "G21497-005"
					( Origin gFrontEnd )
				)
				( attribute "PHYS_PAGE" "89"
					( Origin gFrontEnd )
				)
				( attribute "ROOM" "NV_DIMM"
					( Origin gFrontEnd )
				)
				( attribute "ROT" "0"
					( Origin gFrontEnd )
				)
				( attribute "SEC" "1"
					( Origin gFrontEnd )
				)
				( attribute "SEC_TYPE" "0402"
					( Origin gFrontEnd )
				)
				( attribute "TOLERANCE" "5%"
					( Origin gFrontEnd )
				)
				( attribute "VALUE" "0.0"
					( Origin gFrontEnd )
				)
				( attribute "VER" "1"
					( Origin gFrontEnd )
				)
				( attribute "WATTAGE" "1/16W"
					( Origin gFrontEnd )
				)
				( attribute "XY" "(-1650,2400)"
					( Origin gFrontEnd )
				)
				( attribute "CHIPS_PART_NAME" "RES"
					( Origin gPackager )
				)
				( attribute "CDS_PART_NAME" "RES_0402-0.0,5%,1/16W,EMPTY,G2A"
					( Origin gPackager )
				)
				( objectStatus "R4T2" )
				( pin "a"
					( attribute "PN" "1"
						( Origin gPackager )
					)
					( objectStatus "R4T2.1" )
				)
				( pin "b"
					( attribute "PN" "2"
						( Origin gPackager )
					)
					( objectStatus "R4T2.2" )
				)
			)
			( gate "@baseboard_fab2_lib.baseboard_fab2(sch_1):page89_i2"
				( attribute "BOM_COST" "MEM_NV"
					( Origin gFrontEnd )
				)
				( attribute "CDS_LIB" "mstr_discrete"
					( Origin gPackager )
				)
				( attribute "CDS_LOCATION" "R4T1"
					( Origin gPackager )
				)
				( attribute "CDS_SEC" "1"
					( Origin gPackager )
				)
				( attribute "LOCATION" "R4T1"
					( Origin gFrontEnd )
				)
				( attribute "MATERIAL" "CHIP"
					( Origin gFrontEnd )
				)
				( attribute "PACK_TYPE" "0402"
					( Origin gFrontEnd )
				)
				( attribute "PART_NUMBER" "G21497-005"
					( Origin gFrontEnd )
				)
				( attribute "PHYS_PAGE" "89"
					( Origin gFrontEnd )
				)
				( attribute "ROOM" "NV_DIMM"
					( Origin gFrontEnd )
				)
				( attribute "ROT" "0"
					( Origin gFrontEnd )
				)
				( attribute "SEC" "1"
					( Origin gFrontEnd )
				)
				( attribute "SEC_TYPE" "0402"
					( Origin gFrontEnd )
				)
				( attribute "TOLERANCE" "5%"
					( Origin gFrontEnd )
				)
				( attribute "VALUE" "0.0"
					( Origin gFrontEnd )
				)
				( attribute "VER" "1"
					( Origin gFrontEnd )
				)
				( attribute "WATTAGE" "1/16W"
					( Origin gFrontEnd )
				)
				( attribute "XY" "(-1650,2100)"
					( Origin gFrontEnd )
				)
				( attribute "CHIPS_PART_NAME" "RES"
					( Origin gPackager )
				)
				( attribute "CDS_PART_NAME" "RES_0402-0.0,5%,1/16W,CHIP,G21A"
					( Origin gPackager )
				)
				( objectStatus "R4T1" )
				( pin "a"
					( attribute "PN" "1"
						( Origin gPackager )
					)
					( objectStatus "R4T1.1" )
				)
				( pin "b"
					( attribute "PN" "2"
						( Origin gPackager )
					)
					( objectStatus "R4T1.2" )
				)
			)
			( gate "@baseboard_fab2_lib.baseboard_fab2(sch_1):page89_i3"
				( attribute "BOM_COST" "MEM_NV"
					( Origin gFrontEnd )
				)
				( attribute "CDS_LIB" "mstr_discrete"
					( Origin gPackager )
				)
				( attribute "CDS_LOCATION" "R6F4"
					( Origin gPackager )
				)
				( attribute "CDS_SEC" "1"
					( Origin gPackager )
				)
				( attribute "LOCATION" "R6F4"
					( Origin gFrontEnd )
				)
				( attribute "MATERIAL" "CHIP"
					( Origin gFrontEnd )
				)
				( attribute "PACK_TYPE" "0402"
					( Origin gFrontEnd )
				)
				( attribute "PART_NUMBER" "G21796-047"
					( Origin gFrontEnd )
				)
				( attribute "PHYS_PAGE" "89"
					( Origin gFrontEnd )
				)
				( attribute "ROOM" "NV_DIMM"
					( Origin gFrontEnd )
				)
				( attribute "ROT" "0"
					( Origin gFrontEnd )
				)
				( attribute "SEC" "1"
					( Origin gFrontEnd )
				)
				( attribute "SEC_TYPE" "0402"
					( Origin gFrontEnd )
				)
				( attribute "TOLERANCE" "1%"
					( Origin gFrontEnd )
				)
				( attribute "VALUE" "49.9"
					( Origin gFrontEnd )
				)
				( attribute "VER" "1"
					( Origin gFrontEnd )
				)
				( attribute "WATTAGE" "1/16W"
					( Origin gFrontEnd )
				)
				( attribute "XY" "(450,2500)"
					( Origin gFrontEnd )
				)
				( attribute "CHIPS_PART_NAME" "RES"
					( Origin gPackager )
				)
				( attribute "CDS_PART_NAME" "RES_0402-49.9,1%,1/16W,CHIP,G2A"
					( Origin gPackager )
				)
				( objectStatus "R6F4" )
				( pin "a"
					( attribute "PN" "1"
						( Origin gPackager )
					)
					( objectStatus "R6F4.1" )
				)
				( pin "b"
					( attribute "PN" "2"
						( Origin gPackager )
					)
					( objectStatus "R6F4.2" )
				)
			)
			( gate "@baseboard_fab2_lib.baseboard_fab2(sch_1):page89_i4"
				( attribute "BOM_COST" "MEM_NV"
					( Origin gFrontEnd )
				)
				( attribute "CDS_LIB" "mstr_discrete"
					( Origin gPackager )
				)
				( attribute "CDS_LOCATION" "R6F1"
					( Origin gPackager )
				)
				( attribute "CDS_SEC" "1"
					( Origin gPackager )
				)
				( attribute "LOCATION" "R6F1"
					( Origin gFrontEnd )
				)
				( attribute "MATERIAL" "CHIP"
					( Origin gFrontEnd )
				)
				( attribute "PACK_TYPE" "0402"
					( Origin gFrontEnd )
				)
				( attribute "PART_NUMBER" "G21796-047"
					( Origin gFrontEnd )
				)
				( attribute "PHYS_PAGE" "89"
					( Origin gFrontEnd )
				)
				( attribute "ROOM" "NV_DIMM"
					( Origin gFrontEnd )
				)
				( attribute "ROT" "0"
					( Origin gFrontEnd )
				)
				( attribute "SEC" "1"
					( Origin gFrontEnd )
				)
				( attribute "SEC_TYPE" "0402"
					( Origin gFrontEnd )
				)
				( attribute "TOLERANCE" "1%"
					( Origin gFrontEnd )
				)
				( attribute "VALUE" "49.9"
					( Origin gFrontEnd )
				)
				( attribute "VER" "1"
					( Origin gFrontEnd )
				)
				( attribute "WATTAGE" "1/16W"
					( Origin gFrontEnd )
				)
				( attribute "XY" "(450,2200)"
					( Origin gFrontEnd )
				)
				( attribute "CHIPS_PART_NAME" "RES"
					( Origin gPackager )
				)
				( attribute "CDS_PART_NAME" "RES_0402-49.9,1%,1/16W,CHIP,G2A"
					( Origin gPackager )
				)
				( objectStatus "R6F1" )
				( pin "a"
					( attribute "PN" "1"
						( Origin gPackager )
					)
					( objectStatus "R6F1.1" )
				)
				( pin "b"
					( attribute "PN" "2"
						( Origin gPackager )
					)
					( objectStatus "R6F1.2" )
				)
			)
			( gate "@baseboard_fab2_lib.baseboard_fab2(sch_1):page89_i5"
				( attribute "BOM_COST" "MEM_NV"
					( Origin gFrontEnd )
				)
				( attribute "CDS_LIB" "mstr_discrete"
					( Origin gPackager )
				)
				( attribute "CDS_LOCATION" "R6F5"
					( Origin gPackager )
				)
				( attribute "CDS_SEC" "1"
					( Origin gPackager )
				)
				( attribute "LOCATION" "R6F5"
					( Origin gFrontEnd )
				)
				( attribute "MATERIAL" "CHIP"
					( Origin gFrontEnd )
				)
				( attribute "PACK_TYPE" "0402"
					( Origin gFrontEnd )
				)
				( attribute "PART_NUMBER" "G21796-047"
					( Origin gFrontEnd )
				)
				( attribute "PHYS_PAGE" "89"
					( Origin gFrontEnd )
				)
				( attribute "ROOM" "NV_DIMM"
					( Origin gFrontEnd )
				)
				( attribute "ROT" "0"
					( Origin gFrontEnd )
				)
				( attribute "SEC" "1"
					( Origin gFrontEnd )
				)
				( attribute "SEC_TYPE" "0402"
					( Origin gFrontEnd )
				)
				( attribute "TOLERANCE" "1%"
					( Origin gFrontEnd )
				)
				( attribute "VALUE" "49.9"
					( Origin gFrontEnd )
				)
				( attribute "VER" "1"
					( Origin gFrontEnd )
				)
				( attribute "WATTAGE" "1/16W"
					( Origin gFrontEnd )
				)
				( attribute "XY" "(450,1900)"
					( Origin gFrontEnd )
				)
				( attribute "CHIPS_PART_NAME" "RES"
					( Origin gPackager )
				)
				( attribute "CDS_PART_NAME" "RES_0402-49.9,1%,1/16W,CHIP,G2A"
					( Origin gPackager )
				)
				( objectStatus "R6F5" )
				( pin "a"
					( attribute "PN" "1"
						( Origin gPackager )
					)
					( objectStatus "R6F5.1" )
				)
				( pin "b"
					( attribute "PN" "2"
						( Origin gPackager )
					)
					( objectStatus "R6F5.2" )
				)
			)
			( gate "@baseboard_fab2_lib.baseboard_fab2(sch_1):page89_i6"
				( attribute "BOM_COST" "MEM_NV"
					( Origin gFrontEnd )
				)
				( attribute "CDS_LIB" "mstr_discrete"
					( Origin gPackager )
				)
				( attribute "CDS_LOCATION" "R6F2"
					( Origin gPackager )
				)
				( attribute "CDS_SEC" "1"
					( Origin gPackager )
				)
				( attribute "LOCATION" "R6F2"
					( Origin gFrontEnd )
				)
				( attribute "MATERIAL" "CHIP"
					( Origin gFrontEnd )
				)
				( attribute "PACK_TYPE" "0402"
					( Origin gFrontEnd )
				)
				( attribute "PART_NUMBER" "G21796-047"
					( Origin gFrontEnd )
				)
				( attribute "PHYS_PAGE" "89"
					( Origin gFrontEnd )
				)
				( attribute "ROOM" "NV_DIMM"
					( Origin gFrontEnd )
				)
				( attribute "ROT" "0"
					( Origin gFrontEnd )
				)
				( attribute "SEC" "1"
					( Origin gFrontEnd )
				)
				( attribute "SEC_TYPE" "0402"
					( Origin gFrontEnd )
				)
				( attribute "TOLERANCE" "1%"
					( Origin gFrontEnd )
				)
				( attribute "VALUE" "49.9"
					( Origin gFrontEnd )
				)
				( attribute "VER" "1"
					( Origin gFrontEnd )
				)
				( attribute "WATTAGE" "1/16W"
					( Origin gFrontEnd )
				)
				( attribute "XY" "(450,1600)"
					( Origin gFrontEnd )
				)
				( attribute "CHIPS_PART_NAME" "RES"
					( Origin gPackager )
				)
				( attribute "CDS_PART_NAME" "RES_0402-49.9,1%,1/16W,CHIP,G2A"
					( Origin gPackager )
				)
				( objectStatus "R6F2" )
				( pin "a"
					( attribute "PN" "1"
						( Origin gPackager )
					)
					( objectStatus "R6F2.1" )
				)
				( pin "b"
					( attribute "PN" "2"
						( Origin gPackager )
					)
					( objectStatus "R6F2.2" )
				)
			)
			( gate "@baseboard_fab2_lib.baseboard_fab2(sch_1):page89_i7"
				( attribute "BOM_COST" "MEM_NV"
					( Origin gFrontEnd )
				)
				( attribute "CDS_LIB" "mstr_discrete"
					( Origin gPackager )
				)
				( attribute "CDS_LOCATION" "R6F3"
					( Origin gPackager )
				)
				( attribute "CDS_SEC" "1"
					( Origin gPackager )
				)
				( attribute "LOCATION" "R6F3"
					( Origin gFrontEnd )
				)
				( attribute "MATERIAL" "CHIP"
					( Origin gFrontEnd )
				)
				( attribute "PACK_TYPE" "0402"
					( Origin gFrontEnd )
				)
				( attribute "PART_NUMBER" "G21796-016"
					( Origin gFrontEnd )
				)
				( attribute "PHYS_PAGE" "89"
					( Origin gFrontEnd )
				)
				( attribute "ROOM" "NV_DIMM"
					( Origin gFrontEnd )
				)
				( attribute "ROT" "0"
					( Origin gFrontEnd )
				)
				( attribute "SEC" "1"
					( Origin gFrontEnd )
				)
				( attribute "SEC_TYPE" "0402"
					( Origin gFrontEnd )
				)
				( attribute "TOLERANCE" "1%"
					( Origin gFrontEnd )
				)
				( attribute "VALUE" "10.0K"
					( Origin gFrontEnd )
				)
				( attribute "VER" "2"
					( Origin gFrontEnd )
				)
				( attribute "WATTAGE" "1/16W"
					( Origin gFrontEnd )
				)
				( attribute "XY" "(-550,2700)"
					( Origin gFrontEnd )
				)
				( attribute "CHIPS_PART_NAME" "RES"
					( Origin gPackager )
				)
				( attribute "CDS_PART_NAME" "RES_0402-10.0K,1%,1/16W,CHIP,GA"
					( Origin gPackager )
				)
				( objectStatus "R6F3" )
				( pin "a"
					( attribute "PN" "1"
						( Origin gPackager )
					)
					( objectStatus "R6F3.1" )
				)
				( pin "b"
					( attribute "PN" "2"
						( Origin gPackager )
					)
					( objectStatus "R6F3.2" )
				)
			)
			( gate "@baseboard_fab2_lib.baseboard_fab2(sch_1):page89_i18"
				( attribute "BOM_COST" "MEM_NV"
					( Origin gFrontEnd )
				)
				( attribute "CDS_LIB" "mstr_discrete"
					( Origin gPackager )
				)
				( attribute "CDS_LOCATION" "Q6F1"
					( Origin gPackager )
				)
				( attribute "CDS_SEC" "1"
					( Origin gPackager )
				)
				( attribute "LOCATION" "Q6F1"
					( Origin gFrontEnd )
				)
				( attribute "MATERIAL" "FET"
					( Origin gFrontEnd )
				)
				( attribute "PACK_TYPE" "SOT23"
					( Origin gFrontEnd )
				)
				( attribute "PART_NUMBER" "C79254-001"
					( Origin gFrontEnd )
				)
				( attribute "PHYS_PAGE" "89"
					( Origin gFrontEnd )
				)
				( attribute "ROOM" "NVDIMM"
					( Origin gFrontEnd )
				)
				( attribute "ROT" "0"
					( Origin gFrontEnd )
				)
				( attribute "SEC" "1"
					( Origin gFrontEnd )
				)
				( attribute "SEC_TYPE" "SOT23"
					( Origin gFrontEnd )
				)
				( attribute "VALUE" "2N7002"
					( Origin gFrontEnd )
				)
				( attribute "VER" "8"
					( Origin gFrontEnd )
				)
				( attribute "XY" "(-550,2200)"
					( Origin gFrontEnd )
				)
				( attribute "CHIPS_PART_NAME" "FET_N"
					( Origin gPackager )
				)
				( attribute "CDS_PART_NAME" "FET_N_SOT23-2N7002,FET,C79254-A"
					( Origin gPackager )
				)
				( objectStatus "Q6F1" )
				( pin "drn"
					( attribute "PN" "3"
						( Origin gPackager )
					)
					( objectStatus "Q6F1.3" )
				)
				( pin "gate"
					( attribute "PN" "1"
						( Origin gPackager )
					)
					( objectStatus "Q6F1.1" )
				)
				( pin "src"
					( attribute "PN" "2"
						( Origin gPackager )
					)
					( objectStatus "Q6F1.2" )
				)
			)
			( gate "@baseboard_fab2_lib.baseboard_fab2(sch_1):page89_i23"
				( attribute "BOM_COST" "MEM_NV"
					( Origin gFrontEnd )
				)
				( attribute "CDS_LIB" "mstr_discrete"
					( Origin gPackager )
				)
				( attribute "CDS_LOCATION" "R2P12"
					( Origin gPackager )
				)
				( attribute "CDS_SEC" "1"
					( Origin gPackager )
				)
				( attribute "LOCATION" "R2P12"
					( Origin gFrontEnd )
				)
				( attribute "MATERIAL" "EMPTY"
					( Origin gFrontEnd )
				)
				( attribute "PACK_TYPE" "0402"
					( Origin gFrontEnd )
				)
				( attribute "PART_NUMBER" "G21497-005"
					( Origin gFrontEnd )
				)
				( attribute "PHYS_PAGE" "89"
					( Origin gFrontEnd )
				)
				( attribute "ROOM" "NV_DIMM"
					( Origin gFrontEnd )
				)
				( attribute "ROT" "0"
					( Origin gFrontEnd )
				)
				( attribute "SEC" "1"
					( Origin gPackager )
				)
				( attribute "TOLERANCE" "5%"
					( Origin gFrontEnd )
				)
				( attribute "VALUE" "0.0"
					( Origin gFrontEnd )
				)
				( attribute "VER" "1"
					( Origin gFrontEnd )
				)
				( attribute "WATTAGE" "1/16W"
					( Origin gFrontEnd )
				)
				( attribute "XY" "(3325,2900)"
					( Origin gFrontEnd )
				)
				( attribute "CHIPS_PART_NAME" "RES"
					( Origin gPackager )
				)
				( attribute "CDS_PART_NAME" "RES_0402-0.0,5%,1/16W,EMPTY,G2A"
					( Origin gPackager )
				)
				( objectStatus "R2P12" )
				( pin "a"
					( attribute "PN" "1"
						( Origin gPackager )
					)
					( objectStatus "R2P12.1" )
				)
				( pin "b"
					( attribute "PN" "2"
						( Origin gPackager )
					)
					( objectStatus "R2P12.2" )
				)
			)
			( gate "@baseboard_fab2_lib.baseboard_fab2(sch_1):page89_i26"
				( attribute "CDS_LIB" "mstr_discrete"
					( Origin gPackager )
				)
				( attribute "CDS_LOCATION" "R8D29"
					( Origin gPackager )
				)
				( attribute "CDS_SEC" "1"
					( Origin gPackager )
				)
				( attribute "LOCATION" "R8D29"
					( Origin gFrontEnd )
				)
				( attribute "MATERIAL" "CHIP"
					( Origin gFrontEnd )
				)
				( attribute "PACK_TYPE" "0402"
					( Origin gFrontEnd )
				)
				( attribute "PART_NUMBER" "G21796-072"
					( Origin gFrontEnd )
				)
				( attribute "PHYS_PAGE" "89"
					( Origin gFrontEnd )
				)
				( attribute "ROOM" "NVDIMM"
					( Origin gFrontEnd )
				)
				( attribute "ROT" "0"
					( Origin gFrontEnd )
				)
				( attribute "SEC" "1"
					( Origin gPackager )
				)
				( attribute "TOLERANCE" "1%"
					( Origin gFrontEnd )
				)
				( attribute "VALUE" "4.75K"
					( Origin gFrontEnd )
				)
				( attribute "VER" "2"
					( Origin gFrontEnd )
				)
				( attribute "WATTAGE" "1/16W"
					( Origin gFrontEnd )
				)
				( attribute "XY" "(1850,3875)"
					( Origin gFrontEnd )
				)
				( attribute "CHIPS_PART_NAME" "RES"
					( Origin gPackager )
				)
				( attribute "CDS_PART_NAME" "RES_0402-4.75K,1%,1/16W,CHIP,GA"
					( Origin gPackager )
				)
				( objectStatus "R8D29" )
				( pin "a"
					( attribute "PN" "1"
						( Origin gPackager )
					)
					( objectStatus "R8D29.1" )
				)
				( pin "b"
					( attribute "PN" "2"
						( Origin gPackager )
					)
					( objectStatus "R8D29.2" )
				)
			)
			( gate "@baseboard_fab2_lib.baseboard_fab2(sch_1):page89_i27"
				( attribute "CDS_LIB" "mstr_discrete"
					( Origin gPackager )
				)
				( attribute "CDS_LOCATION" "R8D31"
					( Origin gPackager )
				)
				( attribute "CDS_SEC" "1"
					( Origin gPackager )
				)
				( attribute "LOCATION" "R8D31"
					( Origin gFrontEnd )
				)
				( attribute "MATERIAL" "CHIP"
					( Origin gFrontEnd )
				)
				( attribute "PACK_TYPE" "0402"
					( Origin gFrontEnd )
				)
				( attribute "PART_NUMBER" "G21796-072"
					( Origin gFrontEnd )
				)
				( attribute "PHYS_PAGE" "89"
					( Origin gFrontEnd )
				)
				( attribute "ROOM" "NVDIMM"
					( Origin gFrontEnd )
				)
				( attribute "ROT" "0"
					( Origin gFrontEnd )
				)
				( attribute "SEC" "1"
					( Origin gPackager )
				)
				( attribute "TOLERANCE" "1%"
					( Origin gFrontEnd )
				)
				( attribute "VALUE" "4.75K"
					( Origin gFrontEnd )
				)
				( attribute "VER" "2"
					( Origin gFrontEnd )
				)
				( attribute "WATTAGE" "1/16W"
					( Origin gFrontEnd )
				)
				( attribute "XY" "(2550,4100)"
					( Origin gFrontEnd )
				)
				( attribute "CHIPS_PART_NAME" "RES"
					( Origin gPackager )
				)
				( attribute "CDS_PART_NAME" "RES_0402-4.75K,1%,1/16W,CHIP,GA"
					( Origin gPackager )
				)
				( objectStatus "R8D31" )
				( pin "a"
					( attribute "PN" "1"
						( Origin gPackager )
					)
					( objectStatus "R8D31.1" )
				)
				( pin "b"
					( attribute "PN" "2"
						( Origin gPackager )
					)
					( objectStatus "R8D31.2" )
				)
			)
			( gate "@baseboard_fab2_lib.baseboard_fab2(sch_1):page89_i34"
				( attribute "BOM_COST" "MEM_NV"
					( Origin gFrontEnd )
				)
				( attribute "CDS_LIB" "mstr_discrete"
					( Origin gPackager )
				)
				( attribute "CDS_LOCATION" "R8D30"
					( Origin gPackager )
				)
				( attribute "CDS_SEC" "1"
					( Origin gPackager )
				)
				( attribute "LOCATION" "R8D30"
					( Origin gFrontEnd )
				)
				( attribute "MATERIAL" "CHIP"
					( Origin gFrontEnd )
				)
				( attribute "PACK_TYPE" "0402"
					( Origin gFrontEnd )
				)
				( attribute "PART_NUMBER" "G21796-016"
					( Origin gFrontEnd )
				)
				( attribute "PHYS_PAGE" "89"
					( Origin gFrontEnd )
				)
				( attribute "ROOM" "NV_DIMM"
					( Origin gFrontEnd )
				)
				( attribute "ROT" "0"
					( Origin gFrontEnd )
				)
				( attribute "SEC" "1"
					( Origin gFrontEnd )
				)
				( attribute "SEC_TYPE" "0402"
					( Origin gFrontEnd )
				)
				( attribute "TOLERANCE" "1%"
					( Origin gFrontEnd )
				)
				( attribute "VALUE" "10.0K"
					( Origin gFrontEnd )
				)
				( attribute "VER" "1"
					( Origin gFrontEnd )
				)
				( attribute "WATTAGE" "1/16W"
					( Origin gFrontEnd )
				)
				( attribute "XY" "(875,3075)"
					( Origin gFrontEnd )
				)
				( attribute "CHIPS_PART_NAME" "RES"
					( Origin gPackager )
				)
				( attribute "CDS_PART_NAME" "RES_0402-10.0K,1%,1/16W,CHIP,GA"
					( Origin gPackager )
				)
				( objectStatus "R8D30" )
				( pin "a"
					( attribute "PN" "1"
						( Origin gPackager )
					)
					( objectStatus "R8D30.1" )
				)
				( pin "b"
					( attribute "PN" "2"
						( Origin gPackager )
					)
					( objectStatus "R8D30.2" )
				)
			)
			( gate "@baseboard_fab2_lib.baseboard_fab2(sch_1):page89_i35"
				( attribute "BOM_COST" "MEM_NV"
					( Origin gFrontEnd )
				)
				( attribute "CDS_LIB" "mstr_discrete"
					( Origin gPackager )
				)
				( attribute "CDS_LOCATION" "Q8D1"
					( Origin gPackager )
				)
				( attribute "CDS_SEC" "1"
					( Origin gPackager )
				)
				( attribute "LOCATION" "Q8D1"
					( Origin gFrontEnd )
				)
				( attribute "MATERIAL" "XSTR"
					( Origin gFrontEnd )
				)
				( attribute "PACK_TYPE" "SSOPLF"
					( Origin gFrontEnd )
				)
				( attribute "PART_NUMBER" "C52264-001"
					( Origin gFrontEnd )
				)
				( attribute "PHYS_PAGE" "89"
					( Origin gFrontEnd )
				)
				( attribute "ROOM" "NV_DIMM"
					( Origin gFrontEnd )
				)
				( attribute "ROT" "0"
					( Origin gFrontEnd )
				)
				( attribute "SEC" "1"
					( Origin gFrontEnd )
				)
				( attribute "SEC_TYPE" "SSOPLF"
					( Origin gFrontEnd )
				)
				( attribute "VALUE" "MBT3904"
					( Origin gFrontEnd )
				)
				( attribute "VER" "1"
					( Origin gFrontEnd )
				)
				( attribute "XY" "(1800,3075)"
					( Origin gFrontEnd )
				)
				( attribute "CHIPS_PART_NAME" "NPN_DUAL"
					( Origin gPackager )
				)
				( attribute "CDS_PART_NAME" "NPN_DUAL_SSOPLF-MBT3904,XSTR,CA"
					( Origin gPackager )
				)
				( objectStatus "Q8D1" )
				( pin "b(0)"
					( attribute "PN" "5"
						( Origin gPackager )
					)
					( objectStatus "Q8D1.5" )
				)
				( pin "c(0)"
					( attribute "PN" "3"
						( Origin gPackager )
					)
					( objectStatus "Q8D1.3" )
				)
				( pin "e(0)"
					( attribute "PN" "4"
						( Origin gPackager )
					)
					( objectStatus "Q8D1.4" )
				)
			)
			( gate "@baseboard_fab2_lib.baseboard_fab2(sch_1):page89_i36"
				( attribute "BOM_COST" "MEM_NV"
					( Origin gFrontEnd )
				)
				( attribute "CDS_LIB" "mstr_discrete"
					( Origin gPackager )
				)
				( attribute "CDS_LOCATION" "Q8D1"
					( Origin gPackager )
				)
				( attribute "CDS_SEC" "2"
					( Origin gPackager )
				)
				( attribute "LOCATION" "Q8D1"
					( Origin gFrontEnd )
				)
				( attribute "MATERIAL" "XSTR"
					( Origin gFrontEnd )
				)
				( attribute "PACK_TYPE" "SSOPLF"
					( Origin gFrontEnd )
				)
				( attribute "PART_NUMBER" "C52264-001"
					( Origin gFrontEnd )
				)
				( attribute "PHYS_PAGE" "89"
					( Origin gFrontEnd )
				)
				( attribute "ROOM" "NV_DIMM"
					( Origin gFrontEnd )
				)
				( attribute "ROT" "0"
					( Origin gFrontEnd )
				)
				( attribute "SEC" "2"
					( Origin gFrontEnd )
				)
				( attribute "SEC_TYPE" "SSOPLF"
					( Origin gFrontEnd )
				)
				( attribute "VALUE" "MBT3904"
					( Origin gFrontEnd )
				)
				( attribute "VER" "1"
					( Origin gFrontEnd )
				)
				( attribute "XY" "(2500,3550)"
					( Origin gFrontEnd )
				)
				( attribute "CHIPS_PART_NAME" "NPN_DUAL"
					( Origin gPackager )
				)
				( attribute "CDS_PART_NAME" "NPN_DUAL_SSOPLF-MBT3904,XSTR,CA"
					( Origin gPackager )
				)
				( objectStatus "Q8D1" )
				( pin "b(0)"
					( attribute "PN" "2"
						( Origin gPackager )
					)
					( objectStatus "Q8D1.2" )
				)
				( pin "c(0)"
					( attribute "PN" "6"
						( Origin gPackager )
					)
					( objectStatus "Q8D1.6" )
				)
				( pin "e(0)"
					( attribute "PN" "1"
						( Origin gPackager )
					)
					( objectStatus "Q8D1.1" )
				)
			)
			( gate "@baseboard_fab2_lib.baseboard_fab2(sch_1):page90_i3"
				( attribute "BOM_COST" "PROC"
					( Origin gFrontEnd )
				)
				( attribute "CDS_LIB" "mstr_discrete"
					( Origin gPackager )
				)
				( attribute "CDS_LOCATION" "R6D6"
					( Origin gPackager )
				)
				( attribute "CDS_SEC" "1"
					( Origin gPackager )
				)
				( attribute "LOCATION" "R6D6"
					( Origin gFrontEnd )
				)
				( attribute "MATERIAL" "CHIP"
					( Origin gFrontEnd )
				)
				( attribute "PACK_TYPE" "0402"
					( Origin gFrontEnd )
				)
				( attribute "PART_NUMBER" "G21796-294"
					( Origin gFrontEnd )
				)
				( attribute "PHYS_PAGE" "90"
					( Origin gFrontEnd )
				)
				( attribute "ROOM" "PROC_SIDEBAND"
					( Origin gFrontEnd )
				)
				( attribute "ROT" "0"
					( Origin gFrontEnd )
				)
				( attribute "SEC" "1"
					( Origin gFrontEnd )
				)
				( attribute "SEC_TYPE" "0402"
					( Origin gFrontEnd )
				)
				( attribute "TOLERANCE" "1.0%"
					( Origin gFrontEnd )
				)
				( attribute "VALUE" "240"
					( Origin gFrontEnd )
				)
				( attribute "VER" "1"
					( Origin gFrontEnd )
				)
				( attribute "WATTAGE" "1/16W"
					( Origin gFrontEnd )
				)
				( attribute "XY" "(-500,3400)"
					( Origin gFrontEnd )
				)
				( attribute "CHIPS_PART_NAME" "RES"
					( Origin gPackager )
				)
				( attribute "CDS_PART_NAME" "RES_0402-240,1.0%,1/16W,CHIP,GA"
					( Origin gPackager )
				)
				( objectStatus "R6D6" )
				( pin "a"
					( attribute "PN" "1"
						( Origin gPackager )
					)
					( objectStatus "R6D6.1" )
				)
				( pin "b"
					( attribute "PN" "2"
						( Origin gPackager )
					)
					( objectStatus "R6D6.2" )
				)
			)
			( gate "@baseboard_fab2_lib.baseboard_fab2(sch_1):page90_i4"
				( attribute "BOM_COST" "PROC"
					( Origin gFrontEnd )
				)
				( attribute "CDS_LIB" "mstr_discrete"
					( Origin gPackager )
				)
				( attribute "CDS_LOCATION" "R4P1"
					( Origin gPackager )
				)
				( attribute "CDS_SEC" "1"
					( Origin gPackager )
				)
				( attribute "LOCATION" "R4P1"
					( Origin gFrontEnd )
				)
				( attribute "MATERIAL" "EMPTY"
					( Origin gFrontEnd )
				)
				( attribute "PACK_TYPE" "0402"
					( Origin gFrontEnd )
				)
				( attribute "PART_NUMBER" "G21796-294"
					( Origin gFrontEnd )
				)
				( attribute "PHYS_PAGE" "90"
					( Origin gFrontEnd )
				)
				( attribute "ROOM" "PROC_SIDEBAND"
					( Origin gFrontEnd )
				)
				( attribute "ROT" "0"
					( Origin gFrontEnd )
				)
				( attribute "SEC" "1"
					( Origin gFrontEnd )
				)
				( attribute "SEC_TYPE" "0402"
					( Origin gFrontEnd )
				)
				( attribute "TOLERANCE" "1.0%"
					( Origin gFrontEnd )
				)
				( attribute "VALUE" "240"
					( Origin gFrontEnd )
				)
				( attribute "VER" "1"
					( Origin gFrontEnd )
				)
				( attribute "WATTAGE" "1/16W"
					( Origin gFrontEnd )
				)
				( attribute "XY" "(-500,3200)"
					( Origin gFrontEnd )
				)
				( attribute "CHIPS_PART_NAME" "RES"
					( Origin gPackager )
				)
				( attribute "CDS_PART_NAME" "RES_0402-240,1.0%,1/16W,EMPTY,A"
					( Origin gPackager )
				)
				( objectStatus "R4P1" )
				( pin "a"
					( attribute "PN" "1"
						( Origin gPackager )
					)
					( objectStatus "R4P1.1" )
				)
				( pin "b"
					( attribute "PN" "2"
						( Origin gPackager )
					)
					( objectStatus "R4P1.2" )
				)
			)
			( gate "@baseboard_fab2_lib.baseboard_fab2(sch_1):page90_i11"
				( attribute "BOM_COST" "PROC"
					( Origin gFrontEnd )
				)
				( attribute "CDS_LIB" "mstr_discrete"
					( Origin gPackager )
				)
				( attribute "CDS_LOCATION" "R3D12"
					( Origin gPackager )
				)
				( attribute "CDS_SEC" "1"
					( Origin gPackager )
				)
				( attribute "LOCATION" "R3D12"
					( Origin gFrontEnd )
				)
				( attribute "MATERIAL" "CHIP"
					( Origin gFrontEnd )
				)
				( attribute "PACK_TYPE" "0402"
					( Origin gFrontEnd )
				)
				( attribute "PART_NUMBER" "G21796-294"
					( Origin gFrontEnd )
				)
				( attribute "PHYS_PAGE" "90"
					( Origin gFrontEnd )
				)
				( attribute "ROOM" "PROC_SIDEBAND"
					( Origin gFrontEnd )
				)
				( attribute "ROT" "0"
					( Origin gFrontEnd )
				)
				( attribute "SEC" "1"
					( Origin gFrontEnd )
				)
				( attribute "SEC_TYPE" "0402"
					( Origin gFrontEnd )
				)
				( attribute "TOLERANCE" "1.0%"
					( Origin gFrontEnd )
				)
				( attribute "VALUE" "240"
					( Origin gFrontEnd )
				)
				( attribute "VER" "1"
					( Origin gFrontEnd )
				)
				( attribute "WATTAGE" "1/16W"
					( Origin gFrontEnd )
				)
				( attribute "XY" "(-325,1275)"
					( Origin gFrontEnd )
				)
				( attribute "CHIPS_PART_NAME" "RES"
					( Origin gPackager )
				)
				( attribute "CDS_PART_NAME" "RES_0402-240,1.0%,1/16W,CHIP,GA"
					( Origin gPackager )
				)
				( objectStatus "R3D12" )
				( pin "a"
					( attribute "PN" "1"
						( Origin gPackager )
					)
					( objectStatus "R3D12.1" )
				)
				( pin "b"
					( attribute "PN" "2"
						( Origin gPackager )
					)
					( objectStatus "R3D12.2" )
				)
			)
			( gate "@baseboard_fab2_lib.baseboard_fab2(sch_1):page90_i12"
				( attribute "BOM_COST" "PROC"
					( Origin gFrontEnd )
				)
				( attribute "CDS_LIB" "mstr_discrete"
					( Origin gPackager )
				)
				( attribute "CDS_LOCATION" "R3D13"
					( Origin gPackager )
				)
				( attribute "CDS_SEC" "1"
					( Origin gPackager )
				)
				( attribute "LOCATION" "R3D13"
					( Origin gFrontEnd )
				)
				( attribute "MATERIAL" "EMPTY"
					( Origin gFrontEnd )
				)
				( attribute "PACK_TYPE" "0402"
					( Origin gFrontEnd )
				)
				( attribute "PART_NUMBER" "G21796-294"
					( Origin gFrontEnd )
				)
				( attribute "PHYS_PAGE" "90"
					( Origin gFrontEnd )
				)
				( attribute "ROOM" "PROC_SIDEBAND"
					( Origin gFrontEnd )
				)
				( attribute "ROT" "0"
					( Origin gFrontEnd )
				)
				( attribute "SEC" "1"
					( Origin gFrontEnd )
				)
				( attribute "SEC_TYPE" "0402"
					( Origin gFrontEnd )
				)
				( attribute "TOLERANCE" "1.0%"
					( Origin gFrontEnd )
				)
				( attribute "VALUE" "240"
					( Origin gFrontEnd )
				)
				( attribute "VER" "1"
					( Origin gFrontEnd )
				)
				( attribute "WATTAGE" "1/16W"
					( Origin gFrontEnd )
				)
				( attribute "XY" "(-325,1050)"
					( Origin gFrontEnd )
				)
				( attribute "CHIPS_PART_NAME" "RES"
					( Origin gPackager )
				)
				( attribute "CDS_PART_NAME" "RES_0402-240,1.0%,1/16W,EMPTY,A"
					( Origin gPackager )
				)
				( objectStatus "R3D13" )
				( pin "a"
					( attribute "PN" "1"
						( Origin gPackager )
					)
					( objectStatus "R3D13.1" )
				)
				( pin "b"
					( attribute "PN" "2"
						( Origin gPackager )
					)
					( objectStatus "R3D13.2" )
				)
			)
			( gate "@baseboard_fab2_lib.baseboard_fab2(sch_1):page90_i17"
				( attribute "BOM_COST" "PROC"
					( Origin gFrontEnd )
				)
				( attribute "CDS_LIB" "mstr_discrete"
					( Origin gPackager )
				)
				( attribute "CDS_LOCATION" "R3D22"
					( Origin gPackager )
				)
				( attribute "CDS_SEC" "1"
					( Origin gPackager )
				)
				( attribute "LOCATION" "R3D22"
					( Origin gFrontEnd )
				)
				( attribute "MATERIAL" "EMPTY"
					( Origin gFrontEnd )
				)
				( attribute "PACK_TYPE" "0402"
					( Origin gFrontEnd )
				)
				( attribute "PART_NUMBER" "G21796-294"
					( Origin gFrontEnd )
				)
				( attribute "PHYS_PAGE" "90"
					( Origin gFrontEnd )
				)
				( attribute "ROOM" "PROC_SIDEBAND"
					( Origin gFrontEnd )
				)
				( attribute "ROT" "0"
					( Origin gFrontEnd )
				)
				( attribute "SEC" "1"
					( Origin gFrontEnd )
				)
				( attribute "SEC_TYPE" "0402"
					( Origin gFrontEnd )
				)
				( attribute "TOLERANCE" "1.0%"
					( Origin gFrontEnd )
				)
				( attribute "VALUE" "240"
					( Origin gFrontEnd )
				)
				( attribute "VER" "1"
					( Origin gFrontEnd )
				)
				( attribute "WATTAGE" "1/16W"
					( Origin gFrontEnd )
				)
				( attribute "XY" "(-2450,1875)"
					( Origin gFrontEnd )
				)
				( attribute "CHIPS_PART_NAME" "RES"
					( Origin gPackager )
				)
				( attribute "CDS_PART_NAME" "RES_0402-240,1.0%,1/16W,EMPTY,A"
					( Origin gPackager )
				)
				( objectStatus "R3D22" )
				( pin "a"
					( attribute "PN" "1"
						( Origin gPackager )
					)
					( objectStatus "R3D22.1" )
				)
				( pin "b"
					( attribute "PN" "2"
						( Origin gPackager )
					)
					( objectStatus "R3D22.2" )
				)
			)
			( gate "@baseboard_fab2_lib.baseboard_fab2(sch_1):page90_i24"
				( attribute "BOM_COST" "PROC"
					( Origin gFrontEnd )
				)
				( attribute "CDS_LIB" "mstr_discrete"
					( Origin gPackager )
				)
				( attribute "CDS_LOCATION" "R3D16"
					( Origin gPackager )
				)
				( attribute "CDS_SEC" "1"
					( Origin gPackager )
				)
				( attribute "LOCATION" "R3D16"
					( Origin gFrontEnd )
				)
				( attribute "MATERIAL" "EMPTY"
					( Origin gFrontEnd )
				)
				( attribute "PACK_TYPE" "0402"
					( Origin gFrontEnd )
				)
				( attribute "PART_NUMBER" "G21796-294"
					( Origin gFrontEnd )
				)
				( attribute "PHYS_PAGE" "90"
					( Origin gFrontEnd )
				)
				( attribute "ROOM" "PROC_SIDEBAND"
					( Origin gFrontEnd )
				)
				( attribute "ROT" "0"
					( Origin gFrontEnd )
				)
				( attribute "SEC" "1"
					( Origin gFrontEnd )
				)
				( attribute "SEC_TYPE" "0402"
					( Origin gFrontEnd )
				)
				( attribute "TOLERANCE" "1.0%"
					( Origin gFrontEnd )
				)
				( attribute "VALUE" "240"
					( Origin gFrontEnd )
				)
				( attribute "VER" "1"
					( Origin gFrontEnd )
				)
				( attribute "WATTAGE" "1/16W"
					( Origin gFrontEnd )
				)
				( attribute "XY" "(-2450,1675)"
					( Origin gFrontEnd )
				)
				( attribute "CHIPS_PART_NAME" "RES"
					( Origin gPackager )
				)
				( attribute "CDS_PART_NAME" "RES_0402-240,1.0%,1/16W,EMPTY,A"
					( Origin gPackager )
				)
				( objectStatus "R3D16" )
				( pin "a"
					( attribute "PN" "1"
						( Origin gPackager )
					)
					( objectStatus "R3D16.1" )
				)
				( pin "b"
					( attribute "PN" "2"
						( Origin gPackager )
					)
					( objectStatus "R3D16.2" )
				)
			)
			( gate "@baseboard_fab2_lib.baseboard_fab2(sch_1):page90_i25"
				( attribute "BOM_COST" "PROC"
					( Origin gFrontEnd )
				)
				( attribute "CDS_LIB" "mstr_discrete"
					( Origin gPackager )
				)
				( attribute "CDS_LOCATION" "R3D23"
					( Origin gPackager )
				)
				( attribute "CDS_SEC" "1"
					( Origin gPackager )
				)
				( attribute "LOCATION" "R3D23"
					( Origin gFrontEnd )
				)
				( attribute "MATERIAL" "EMPTY"
					( Origin gFrontEnd )
				)
				( attribute "PACK_TYPE" "0402"
					( Origin gFrontEnd )
				)
				( attribute "PART_NUMBER" "G21796-294"
					( Origin gFrontEnd )
				)
				( attribute "PHYS_PAGE" "90"
					( Origin gFrontEnd )
				)
				( attribute "ROOM" "PROC_SIDEBAND"
					( Origin gFrontEnd )
				)
				( attribute "ROT" "0"
					( Origin gFrontEnd )
				)
				( attribute "SEC" "1"
					( Origin gPackager )
				)
				( attribute "TOLERANCE" "1.0%"
					( Origin gFrontEnd )
				)
				( attribute "VALUE" "240"
					( Origin gFrontEnd )
				)
				( attribute "VER" "1"
					( Origin gFrontEnd )
				)
				( attribute "WATTAGE" "1/16W"
					( Origin gFrontEnd )
				)
				( attribute "XY" "(-2450,1475)"
					( Origin gFrontEnd )
				)
				( attribute "CHIPS_PART_NAME" "RES"
					( Origin gPackager )
				)
				( attribute "CDS_PART_NAME" "RES_0402-240,1.0%,1/16W,EMPTY,A"
					( Origin gPackager )
				)
				( objectStatus "R3D23" )
				( pin "a"
					( attribute "PN" "1"
						( Origin gPackager )
					)
					( objectStatus "R3D23.1" )
				)
				( pin "b"
					( attribute "PN" "2"
						( Origin gPackager )
					)
					( objectStatus "R3D23.2" )
				)
			)
			( gate "@baseboard_fab2_lib.baseboard_fab2(sch_1):page90_i28"
				( attribute "BOM_COST" "PROC"
					( Origin gFrontEnd )
				)
				( attribute "CDS_LIB" "mstr_discrete"
					( Origin gPackager )
				)
				( attribute "CDS_LOCATION" "R3D26"
					( Origin gPackager )
				)
				( attribute "CDS_SEC" "1"
					( Origin gPackager )
				)
				( attribute "LOCATION" "R3D26"
					( Origin gFrontEnd )
				)
				( attribute "MATERIAL" "EMPTY"
					( Origin gFrontEnd )
				)
				( attribute "PACK_TYPE" "0402"
					( Origin gFrontEnd )
				)
				( attribute "PART_NUMBER" "G21796-294"
					( Origin gFrontEnd )
				)
				( attribute "PHYS_PAGE" "90"
					( Origin gFrontEnd )
				)
				( attribute "ROOM" "PROC_SIDEBAND"
					( Origin gFrontEnd )
				)
				( attribute "ROT" "0"
					( Origin gFrontEnd )
				)
				( attribute "SEC" "1"
					( Origin gFrontEnd )
				)
				( attribute "SEC_TYPE" "0402"
					( Origin gFrontEnd )
				)
				( attribute "TOLERANCE" "1.0%"
					( Origin gFrontEnd )
				)
				( attribute "VALUE" "240"
					( Origin gFrontEnd )
				)
				( attribute "VER" "1"
					( Origin gFrontEnd )
				)
				( attribute "WATTAGE" "1/16W"
					( Origin gFrontEnd )
				)
				( attribute "XY" "(-2425,1275)"
					( Origin gFrontEnd )
				)
				( attribute "CHIPS_PART_NAME" "RES"
					( Origin gPackager )
				)
				( attribute "CDS_PART_NAME" "RES_0402-240,1.0%,1/16W,EMPTY,A"
					( Origin gPackager )
				)
				( objectStatus "R3D26" )
				( pin "a"
					( attribute "PN" "1"
						( Origin gPackager )
					)
					( objectStatus "R3D26.1" )
				)
				( pin "b"
					( attribute "PN" "2"
						( Origin gPackager )
					)
					( objectStatus "R3D26.2" )
				)
			)
			( gate "@baseboard_fab2_lib.baseboard_fab2(sch_1):page90_i29"
				( attribute "BOM_COST" "PROC"
					( Origin gFrontEnd )
				)
				( attribute "CDS_LIB" "mstr_discrete"
					( Origin gPackager )
				)
				( attribute "CDS_LOCATION" "R5D3"
					( Origin gPackager )
				)
				( attribute "CDS_SEC" "1"
					( Origin gPackager )
				)
				( attribute "LOCATION" "R5D3"
					( Origin gFrontEnd )
				)
				( attribute "MATERIAL" "CHIP"
					( Origin gFrontEnd )
				)
				( attribute "PACK_TYPE" "0402"
					( Origin gFrontEnd )
				)
				( attribute "PART_NUMBER" "G21796-294"
					( Origin gFrontEnd )
				)
				( attribute "PHYS_PAGE" "90"
					( Origin gFrontEnd )
				)
				( attribute "ROOM" "PROC_SIDEBAND"
					( Origin gFrontEnd )
				)
				( attribute "ROT" "0"
					( Origin gFrontEnd )
				)
				( attribute "SEC" "1"
					( Origin gFrontEnd )
				)
				( attribute "SEC_TYPE" "0402"
					( Origin gFrontEnd )
				)
				( attribute "TOLERANCE" "1.0%"
					( Origin gFrontEnd )
				)
				( attribute "VALUE" "240"
					( Origin gFrontEnd )
				)
				( attribute "VER" "1"
					( Origin gFrontEnd )
				)
				( attribute "WATTAGE" "1/16W"
					( Origin gFrontEnd )
				)
				( attribute "XY" "(-2475,4400)"
					( Origin gFrontEnd )
				)
				( attribute "CHIPS_PART_NAME" "RES"
					( Origin gPackager )
				)
				( attribute "CDS_PART_NAME" "RES_0402-240,1.0%,1/16W,CHIP,GA"
					( Origin gPackager )
				)
				( objectStatus "R5D3" )
				( pin "a"
					( attribute "PN" "1"
						( Origin gPackager )
					)
					( objectStatus "R5D3.1" )
				)
				( pin "b"
					( attribute "PN" "2"
						( Origin gPackager )
					)
					( objectStatus "R5D3.2" )
				)
			)
			( gate "@baseboard_fab2_lib.baseboard_fab2(sch_1):page90_i31"
				( attribute "BOM_COST" "PROC"
					( Origin gFrontEnd )
				)
				( attribute "CDS_LIB" "mstr_discrete"
					( Origin gPackager )
				)
				( attribute "CDS_LOCATION" "R6D7"
					( Origin gPackager )
				)
				( attribute "CDS_SEC" "1"
					( Origin gPackager )
				)
				( attribute "LOCATION" "R6D7"
					( Origin gFrontEnd )
				)
				( attribute "MATERIAL" "EMPTY"
					( Origin gFrontEnd )
				)
				( attribute "PACK_TYPE" "0402"
					( Origin gFrontEnd )
				)
				( attribute "PART_NUMBER" "G21796-294"
					( Origin gFrontEnd )
				)
				( attribute "PHYS_PAGE" "90"
					( Origin gFrontEnd )
				)
				( attribute "ROOM" "PROC_SIDEBAND"
					( Origin gFrontEnd )
				)
				( attribute "ROT" "0"
					( Origin gFrontEnd )
				)
				( attribute "SEC" "1"
					( Origin gFrontEnd )
				)
				( attribute "SEC_TYPE" "0402"
					( Origin gFrontEnd )
				)
				( attribute "TOLERANCE" "1.0%"
					( Origin gFrontEnd )
				)
				( attribute "VALUE" "240"
					( Origin gFrontEnd )
				)
				( attribute "VER" "1"
					( Origin gFrontEnd )
				)
				( attribute "WATTAGE" "1/16W"
					( Origin gFrontEnd )
				)
				( attribute "XY" "(-2475,4200)"
					( Origin gFrontEnd )
				)
				( attribute "CHIPS_PART_NAME" "RES"
					( Origin gPackager )
				)
				( attribute "CDS_PART_NAME" "RES_0402-240,1.0%,1/16W,EMPTY,A"
					( Origin gPackager )
				)
				( objectStatus "R6D7" )
				( pin "a"
					( attribute "PN" "1"
						( Origin gPackager )
					)
					( objectStatus "R6D7.1" )
				)
				( pin "b"
					( attribute "PN" "2"
						( Origin gPackager )
					)
					( objectStatus "R6D7.2" )
				)
			)
			( gate "@baseboard_fab2_lib.baseboard_fab2(sch_1):page90_i32"
				( attribute "BOM_COST" "PROC"
					( Origin gFrontEnd )
				)
				( attribute "CDS_LIB" "mstr_discrete"
					( Origin gPackager )
				)
				( attribute "CDS_LOCATION" "R5D4"
					( Origin gPackager )
				)
				( attribute "CDS_SEC" "1"
					( Origin gPackager )
				)
				( attribute "LOCATION" "R5D4"
					( Origin gFrontEnd )
				)
				( attribute "MATERIAL" "EMPTY"
					( Origin gFrontEnd )
				)
				( attribute "PACK_TYPE" "0402"
					( Origin gFrontEnd )
				)
				( attribute "PART_NUMBER" "G21796-294"
					( Origin gFrontEnd )
				)
				( attribute "PHYS_PAGE" "90"
					( Origin gFrontEnd )
				)
				( attribute "ROOM" "PROC_SIDEBAND"
					( Origin gFrontEnd )
				)
				( attribute "ROT" "0"
					( Origin gFrontEnd )
				)
				( attribute "SEC" "1"
					( Origin gFrontEnd )
				)
				( attribute "SEC_TYPE" "0402"
					( Origin gFrontEnd )
				)
				( attribute "TOLERANCE" "1.0%"
					( Origin gFrontEnd )
				)
				( attribute "VALUE" "240"
					( Origin gFrontEnd )
				)
				( attribute "VER" "1"
					( Origin gFrontEnd )
				)
				( attribute "WATTAGE" "1/16W"
					( Origin gFrontEnd )
				)
				( attribute "XY" "(-2475,4000)"
					( Origin gFrontEnd )
				)
				( attribute "CHIPS_PART_NAME" "RES"
					( Origin gPackager )
				)
				( attribute "CDS_PART_NAME" "RES_0402-240,1.0%,1/16W,EMPTY,A"
					( Origin gPackager )
				)
				( objectStatus "R5D4" )
				( pin "a"
					( attribute "PN" "1"
						( Origin gPackager )
					)
					( objectStatus "R5D4.1" )
				)
				( pin "b"
					( attribute "PN" "2"
						( Origin gPackager )
					)
					( objectStatus "R5D4.2" )
				)
			)
			( gate "@baseboard_fab2_lib.baseboard_fab2(sch_1):page90_i33"
				( attribute "BOM_COST" "PROC"
					( Origin gFrontEnd )
				)
				( attribute "CDS_LIB" "mstr_discrete"
					( Origin gPackager )
				)
				( attribute "CDS_LOCATION" "R6D13"
					( Origin gPackager )
				)
				( attribute "CDS_SEC" "1"
					( Origin gPackager )
				)
				( attribute "LOCATION" "R6D13"
					( Origin gFrontEnd )
				)
				( attribute "MATERIAL" "EMPTY"
					( Origin gFrontEnd )
				)
				( attribute "PACK_TYPE" "0402"
					( Origin gFrontEnd )
				)
				( attribute "PART_NUMBER" "G21796-294"
					( Origin gFrontEnd )
				)
				( attribute "PHYS_PAGE" "90"
					( Origin gFrontEnd )
				)
				( attribute "ROOM" "PROC_SIDEBAND"
					( Origin gFrontEnd )
				)
				( attribute "ROT" "0"
					( Origin gFrontEnd )
				)
				( attribute "SEC" "1"
					( Origin gFrontEnd )
				)
				( attribute "SEC_TYPE" "0402"
					( Origin gFrontEnd )
				)
				( attribute "TOLERANCE" "1.0%"
					( Origin gFrontEnd )
				)
				( attribute "VALUE" "240"
					( Origin gFrontEnd )
				)
				( attribute "VER" "1"
					( Origin gFrontEnd )
				)
				( attribute "WATTAGE" "1/16W"
					( Origin gFrontEnd )
				)
				( attribute "XY" "(-2500,3800)"
					( Origin gFrontEnd )
				)
				( attribute "CHIPS_PART_NAME" "RES"
					( Origin gPackager )
				)
				( attribute "CDS_PART_NAME" "RES_0402-240,1.0%,1/16W,EMPTY,A"
					( Origin gPackager )
				)
				( objectStatus "R6D13" )
				( pin "a"
					( attribute "PN" "1"
						( Origin gPackager )
					)
					( objectStatus "R6D13.1" )
				)
				( pin "b"
					( attribute "PN" "2"
						( Origin gPackager )
					)
					( objectStatus "R6D13.2" )
				)
			)
			( gate "@baseboard_fab2_lib.baseboard_fab2(sch_1):page90_i48"
				( attribute "BOM_COST" "PROC"
					( Origin gFrontEnd )
				)
				( attribute "CDS_LIB" "mstr_discrete"
					( Origin gPackager )
				)
				( attribute "CDS_LOCATION" "R6D15"
					( Origin gPackager )
				)
				( attribute "CDS_SEC" "1"
					( Origin gPackager )
				)
				( attribute "LOCATION" "R6D15"
					( Origin gFrontEnd )
				)
				( attribute "MATERIAL" "EMPTY"
					( Origin gFrontEnd )
				)
				( attribute "PACK_TYPE" "0402"
					( Origin gFrontEnd )
				)
				( attribute "PART_NUMBER" "G21796-294"
					( Origin gFrontEnd )
				)
				( attribute "PHYS_PAGE" "90"
					( Origin gFrontEnd )
				)
				( attribute "ROOM" "PROC_SIDEBAND"
					( Origin gFrontEnd )
				)
				( attribute "ROT" "0"
					( Origin gFrontEnd )
				)
				( attribute "SEC" "1"
					( Origin gFrontEnd )
				)
				( attribute "SEC_TYPE" "0402"
					( Origin gFrontEnd )
				)
				( attribute "TOLERANCE" "1.0%"
					( Origin gFrontEnd )
				)
				( attribute "VALUE" "240"
					( Origin gFrontEnd )
				)
				( attribute "VER" "1"
					( Origin gFrontEnd )
				)
				( attribute "WATTAGE" "1/16W"
					( Origin gFrontEnd )
				)
				( attribute "XY" "(-300,4400)"
					( Origin gFrontEnd )
				)
				( attribute "CHIPS_PART_NAME" "RES"
					( Origin gPackager )
				)
				( attribute "CDS_PART_NAME" "RES_0402-240,1.0%,1/16W,EMPTY,A"
					( Origin gPackager )
				)
				( objectStatus "R6D15" )
				( pin "a"
					( attribute "PN" "1"
						( Origin gPackager )
					)
					( objectStatus "R6D15.1" )
				)
				( pin "b"
					( attribute "PN" "2"
						( Origin gPackager )
					)
					( objectStatus "R6D15.2" )
				)
			)
			( gate "@baseboard_fab2_lib.baseboard_fab2(sch_1):page90_i49"
				( attribute "BOM_COST" "PROC"
					( Origin gFrontEnd )
				)
				( attribute "CDS_LIB" "mstr_discrete"
					( Origin gPackager )
				)
				( attribute "CDS_LOCATION" "R6D10"
					( Origin gPackager )
				)
				( attribute "CDS_SEC" "1"
					( Origin gPackager )
				)
				( attribute "LOCATION" "R6D10"
					( Origin gFrontEnd )
				)
				( attribute "MATERIAL" "EMPTY"
					( Origin gFrontEnd )
				)
				( attribute "PACK_TYPE" "0402"
					( Origin gFrontEnd )
				)
				( attribute "PART_NUMBER" "G21796-294"
					( Origin gFrontEnd )
				)
				( attribute "PHYS_PAGE" "90"
					( Origin gFrontEnd )
				)
				( attribute "ROOM" "PROC_SIDEBAND"
					( Origin gFrontEnd )
				)
				( attribute "ROT" "0"
					( Origin gFrontEnd )
				)
				( attribute "SEC" "1"
					( Origin gFrontEnd )
				)
				( attribute "SEC_TYPE" "0402"
					( Origin gFrontEnd )
				)
				( attribute "TOLERANCE" "1.0%"
					( Origin gFrontEnd )
				)
				( attribute "VALUE" "240"
					( Origin gFrontEnd )
				)
				( attribute "VER" "1"
					( Origin gFrontEnd )
				)
				( attribute "WATTAGE" "1/16W"
					( Origin gFrontEnd )
				)
				( attribute "XY" "(-300,4200)"
					( Origin gFrontEnd )
				)
				( attribute "CHIPS_PART_NAME" "RES"
					( Origin gPackager )
				)
				( attribute "CDS_PART_NAME" "RES_0402-240,1.0%,1/16W,EMPTY,A"
					( Origin gPackager )
				)
				( objectStatus "R6D10" )
				( pin "a"
					( attribute "PN" "1"
						( Origin gPackager )
					)
					( objectStatus "R6D10.1" )
				)
				( pin "b"
					( attribute "PN" "2"
						( Origin gPackager )
					)
					( objectStatus "R6D10.2" )
				)
			)
			( gate "@baseboard_fab2_lib.baseboard_fab2(sch_1):page90_i52"
				( attribute "BOM_COST" "PROC"
					( Origin gFrontEnd )
				)
				( attribute "CDS_LIB" "mstr_discrete"
					( Origin gPackager )
				)
				( attribute "CDS_LOCATION" "R6D14"
					( Origin gPackager )
				)
				( attribute "CDS_SEC" "1"
					( Origin gPackager )
				)
				( attribute "LOCATION" "R6D14"
					( Origin gFrontEnd )
				)
				( attribute "MATERIAL" "EMPTY"
					( Origin gFrontEnd )
				)
				( attribute "PACK_TYPE" "0402"
					( Origin gFrontEnd )
				)
				( attribute "PART_NUMBER" "G21796-294"
					( Origin gFrontEnd )
				)
				( attribute "PHYS_PAGE" "90"
					( Origin gFrontEnd )
				)
				( attribute "ROOM" "PROC_SIDEBAND"
					( Origin gFrontEnd )
				)
				( attribute "ROT" "0"
					( Origin gFrontEnd )
				)
				( attribute "SEC" "1"
					( Origin gFrontEnd )
				)
				( attribute "SEC_TYPE" "0402"
					( Origin gFrontEnd )
				)
				( attribute "TOLERANCE" "1.0%"
					( Origin gFrontEnd )
				)
				( attribute "VALUE" "240"
					( Origin gFrontEnd )
				)
				( attribute "VER" "1"
					( Origin gFrontEnd )
				)
				( attribute "WATTAGE" "1/16W"
					( Origin gFrontEnd )
				)
				( attribute "XY" "(-2475,3600)"
					( Origin gFrontEnd )
				)
				( attribute "CHIPS_PART_NAME" "RES"
					( Origin gPackager )
				)
				( attribute "CDS_PART_NAME" "RES_0402-240,1.0%,1/16W,EMPTY,A"
					( Origin gPackager )
				)
				( objectStatus "R6D14" )
				( pin "a"
					( attribute "PN" "1"
						( Origin gPackager )
					)
					( objectStatus "R6D14.1" )
				)
				( pin "b"
					( attribute "PN" "2"
						( Origin gPackager )
					)
					( objectStatus "R6D14.2" )
				)
			)
			( gate "@baseboard_fab2_lib.baseboard_fab2(sch_1):page90_i53"
				( attribute "BOM_COST" "PROC"
					( Origin gFrontEnd )
				)
				( attribute "CDS_LIB" "mstr_discrete"
					( Origin gPackager )
				)
				( attribute "CDS_LOCATION" "R4P14"
					( Origin gPackager )
				)
				( attribute "CDS_SEC" "1"
					( Origin gPackager )
				)
				( attribute "LOCATION" "R4P14"
					( Origin gFrontEnd )
				)
				( attribute "MATERIAL" "CHIP"
					( Origin gFrontEnd )
				)
				( attribute "PACK_TYPE" "0402"
					( Origin gFrontEnd )
				)
				( attribute "PART_NUMBER" "G21796-294"
					( Origin gFrontEnd )
				)
				( attribute "PHYS_PAGE" "90"
					( Origin gFrontEnd )
				)
				( attribute "ROOM" "PROC_SIDEBAND"
					( Origin gFrontEnd )
				)
				( attribute "ROT" "0"
					( Origin gFrontEnd )
				)
				( attribute "SEC" "1"
					( Origin gFrontEnd )
				)
				( attribute "SEC_TYPE" "0402"
					( Origin gFrontEnd )
				)
				( attribute "TOLERANCE" "1.0%"
					( Origin gFrontEnd )
				)
				( attribute "VALUE" "240"
					( Origin gFrontEnd )
				)
				( attribute "VER" "1"
					( Origin gFrontEnd )
				)
				( attribute "WATTAGE" "1/16W"
					( Origin gFrontEnd )
				)
				( attribute "XY" "(-2500,3400)"
					( Origin gFrontEnd )
				)
				( attribute "CHIPS_PART_NAME" "RES"
					( Origin gPackager )
				)
				( attribute "CDS_PART_NAME" "RES_0402-240,1.0%,1/16W,CHIP,GA"
					( Origin gPackager )
				)
				( objectStatus "R4P14" )
				( pin "a"
					( attribute "PN" "1"
						( Origin gPackager )
					)
					( objectStatus "R4P14.1" )
				)
				( pin "b"
					( attribute "PN" "2"
						( Origin gPackager )
					)
					( objectStatus "R4P14.2" )
				)
			)
			( gate "@baseboard_fab2_lib.baseboard_fab2(sch_1):page90_i59"
				( attribute "BOM_COST" "PROC"
					( Origin gFrontEnd )
				)
				( attribute "CDS_LIB" "mstr_discrete"
					( Origin gPackager )
				)
				( attribute "CDS_LOCATION" "R3D24"
					( Origin gPackager )
				)
				( attribute "CDS_SEC" "1"
					( Origin gPackager )
				)
				( attribute "LOCATION" "R3D24"
					( Origin gFrontEnd )
				)
				( attribute "MATERIAL" "CHIP"
					( Origin gFrontEnd )
				)
				( attribute "PACK_TYPE" "0402"
					( Origin gFrontEnd )
				)
				( attribute "PART_NUMBER" "G21796-294"
					( Origin gFrontEnd )
				)
				( attribute "PHYS_PAGE" "90"
					( Origin gFrontEnd )
				)
				( attribute "ROOM" "PROC_SIDEBAND"
					( Origin gFrontEnd )
				)
				( attribute "ROT" "0"
					( Origin gFrontEnd )
				)
				( attribute "SEC" "1"
					( Origin gPackager )
				)
				( attribute "TOLERANCE" "1.0%"
					( Origin gFrontEnd )
				)
				( attribute "VALUE" "240"
					( Origin gFrontEnd )
				)
				( attribute "VER" "1"
					( Origin gFrontEnd )
				)
				( attribute "WATTAGE" "1/16W"
					( Origin gFrontEnd )
				)
				( attribute "XY" "(-375,1675)"
					( Origin gFrontEnd )
				)
				( attribute "CHIPS_PART_NAME" "RES"
					( Origin gPackager )
				)
				( attribute "CDS_PART_NAME" "RES_0402-240,1.0%,1/16W,CHIP,GA"
					( Origin gPackager )
				)
				( objectStatus "R3D24" )
				( pin "a"
					( attribute "PN" "1"
						( Origin gPackager )
					)
					( objectStatus "R3D24.1" )
				)
				( pin "b"
					( attribute "PN" "2"
						( Origin gPackager )
					)
					( objectStatus "R3D24.2" )
				)
			)
			( gate "@baseboard_fab2_lib.baseboard_fab2(sch_1):page90_i60"
				( attribute "BOM_COST" "PROC"
					( Origin gFrontEnd )
				)
				( attribute "CDS_LIB" "mstr_discrete"
					( Origin gPackager )
				)
				( attribute "CDS_LOCATION" "R3D17"
					( Origin gPackager )
				)
				( attribute "CDS_SEC" "1"
					( Origin gPackager )
				)
				( attribute "LOCATION" "R3D17"
					( Origin gFrontEnd )
				)
				( attribute "MATERIAL" "EMPTY"
					( Origin gFrontEnd )
				)
				( attribute "PACK_TYPE" "0402"
					( Origin gFrontEnd )
				)
				( attribute "PART_NUMBER" "G21796-294"
					( Origin gFrontEnd )
				)
				( attribute "PHYS_PAGE" "90"
					( Origin gFrontEnd )
				)
				( attribute "ROOM" "PROC_SIDEBAND"
					( Origin gFrontEnd )
				)
				( attribute "ROT" "0"
					( Origin gFrontEnd )
				)
				( attribute "SEC" "1"
					( Origin gPackager )
				)
				( attribute "TOLERANCE" "1.0%"
					( Origin gFrontEnd )
				)
				( attribute "VALUE" "240"
					( Origin gFrontEnd )
				)
				( attribute "VER" "1"
					( Origin gFrontEnd )
				)
				( attribute "WATTAGE" "1/16W"
					( Origin gFrontEnd )
				)
				( attribute "XY" "(-350,1475)"
					( Origin gFrontEnd )
				)
				( attribute "CHIPS_PART_NAME" "RES"
					( Origin gPackager )
				)
				( attribute "CDS_PART_NAME" "RES_0402-240,1.0%,1/16W,EMPTY,A"
					( Origin gPackager )
				)
				( objectStatus "R3D17" )
				( pin "a"
					( attribute "PN" "1"
						( Origin gPackager )
					)
					( objectStatus "R3D17.1" )
				)
				( pin "b"
					( attribute "PN" "2"
						( Origin gPackager )
					)
					( objectStatus "R3D17.2" )
				)
			)
			( gate "@baseboard_fab2_lib.baseboard_fab2(sch_1):page90_i66"
				( attribute "BOM_COST" "PROC"
					( Origin gFrontEnd )
				)
				( attribute "CDS_LIB" "mstr_discrete"
					( Origin gPackager )
				)
				( attribute "CDS_LOCATION" "R3D25"
					( Origin gPackager )
				)
				( attribute "CDS_SEC" "1"
					( Origin gPackager )
				)
				( attribute "LOCATION" "R3D25"
					( Origin gFrontEnd )
				)
				( attribute "MATERIAL" "EMPTY"
					( Origin gFrontEnd )
				)
				( attribute "PACK_TYPE" "0402"
					( Origin gFrontEnd )
				)
				( attribute "PART_NUMBER" "G21796-294"
					( Origin gFrontEnd )
				)
				( attribute "PHYS_PAGE" "90"
					( Origin gFrontEnd )
				)
				( attribute "ROOM" "PROC_SIDEBAND"
					( Origin gFrontEnd )
				)
				( attribute "ROT" "0"
					( Origin gFrontEnd )
				)
				( attribute "SEC" "1"
					( Origin gFrontEnd )
				)
				( attribute "SEC_TYPE" "0402"
					( Origin gFrontEnd )
				)
				( attribute "TOLERANCE" "1.0%"
					( Origin gFrontEnd )
				)
				( attribute "VALUE" "240"
					( Origin gFrontEnd )
				)
				( attribute "VER" "1"
					( Origin gFrontEnd )
				)
				( attribute "WATTAGE" "1/16W"
					( Origin gFrontEnd )
				)
				( attribute "XY" "(-2500,1025)"
					( Origin gFrontEnd )
				)
				( attribute "CHIPS_PART_NAME" "RES"
					( Origin gPackager )
				)
				( attribute "CDS_PART_NAME" "RES_0402-240,1.0%,1/16W,EMPTY,A"
					( Origin gPackager )
				)
				( objectStatus "R3D25" )
				( pin "a"
					( attribute "PN" "1"
						( Origin gPackager )
					)
					( objectStatus "R3D25.1" )
				)
				( pin "b"
					( attribute "PN" "2"
						( Origin gPackager )
					)
					( objectStatus "R3D25.2" )
				)
			)
			( gate "@baseboard_fab2_lib.baseboard_fab2(sch_1):page90_i68"
				( attribute "BOM_COST" "PROC"
					( Origin gFrontEnd )
				)
				( attribute "CDS_LIB" "mstr_discrete"
					( Origin gPackager )
				)
				( attribute "CDS_LOCATION" "R4P6"
					( Origin gPackager )
				)
				( attribute "CDS_SEC" "1"
					( Origin gPackager )
				)
				( attribute "LOCATION" "R4P6"
					( Origin gFrontEnd )
				)
				( attribute "MATERIAL" "EMPTY"
					( Origin gFrontEnd )
				)
				( attribute "PACK_TYPE" "0402"
					( Origin gFrontEnd )
				)
				( attribute "PART_NUMBER" "G21796-294"
					( Origin gFrontEnd )
				)
				( attribute "PHYS_PAGE" "90"
					( Origin gFrontEnd )
				)
				( attribute "ROOM" "PROC_SIDEBAND"
					( Origin gFrontEnd )
				)
				( attribute "ROT" "0"
					( Origin gFrontEnd )
				)
				( attribute "SEC" "1"
					( Origin gFrontEnd )
				)
				( attribute "SEC_TYPE" "0402"
					( Origin gFrontEnd )
				)
				( attribute "TOLERANCE" "1.0%"
					( Origin gFrontEnd )
				)
				( attribute "VALUE" "240"
					( Origin gFrontEnd )
				)
				( attribute "VER" "1"
					( Origin gFrontEnd )
				)
				( attribute "WATTAGE" "1/16W"
					( Origin gFrontEnd )
				)
				( attribute "XY" "(-425,3000)"
					( Origin gFrontEnd )
				)
				( attribute "CHIPS_PART_NAME" "RES"
					( Origin gPackager )
				)
				( attribute "CDS_PART_NAME" "RES_0402-240,1.0%,1/16W,EMPTY,A"
					( Origin gPackager )
				)
				( objectStatus "R4P6" )
				( pin "a"
					( attribute "PN" "1"
						( Origin gPackager )
					)
					( objectStatus "R4P6.1" )
				)
				( pin "b"
					( attribute "PN" "2"
						( Origin gPackager )
					)
					( objectStatus "R4P6.2" )
				)
			)
			( gate "@baseboard_fab2_lib.baseboard_fab2(sch_1):page90_i70"
				( attribute "BOM_COST" "PROC"
					( Origin gFrontEnd )
				)
				( attribute "CDS_LIB" "mstr_discrete"
					( Origin gPackager )
				)
				( attribute "CDS_LOCATION" "R7P14"
					( Origin gPackager )
				)
				( attribute "CDS_SEC" "1"
					( Origin gPackager )
				)
				( attribute "LOCATION" "R7P14"
					( Origin gFrontEnd )
				)
				( attribute "MATERIAL" "CHIP"
					( Origin gFrontEnd )
				)
				( attribute "PACK_TYPE" "0402"
					( Origin gFrontEnd )
				)
				( attribute "PART_NUMBER" "G21796-294"
					( Origin gFrontEnd )
				)
				( attribute "PHYS_PAGE" "90"
					( Origin gFrontEnd )
				)
				( attribute "ROOM" "PROC_SIDEBAND"
					( Origin gFrontEnd )
				)
				( attribute "ROT" "0"
					( Origin gFrontEnd )
				)
				( attribute "SEC" "1"
					( Origin gFrontEnd )
				)
				( attribute "SEC_TYPE" "0402"
					( Origin gFrontEnd )
				)
				( attribute "TOLERANCE" "1.0%"
					( Origin gFrontEnd )
				)
				( attribute "VALUE" "240"
					( Origin gFrontEnd )
				)
				( attribute "VER" "1"
					( Origin gFrontEnd )
				)
				( attribute "WATTAGE" "1/16W"
					( Origin gFrontEnd )
				)
				( attribute "XY" "(-275,850)"
					( Origin gFrontEnd )
				)
				( attribute "CHIPS_PART_NAME" "RES"
					( Origin gPackager )
				)
				( attribute "CDS_PART_NAME" "RES_0402-240,1.0%,1/16W,CHIP,GA"
					( Origin gPackager )
				)
				( objectStatus "R7P14" )
				( pin "a"
					( attribute "PN" "1"
						( Origin gPackager )
					)
					( objectStatus "R7P14.1" )
				)
				( pin "b"
					( attribute "PN" "2"
						( Origin gPackager )
					)
					( objectStatus "R7P14.2" )
				)
			)
			( gate "@baseboard_fab2_lib.baseboard_fab2(sch_1):page90_i72"
				( attribute "BOM_COST" "PROC"
					( Origin gFrontEnd )
				)
				( attribute "CDS_LIB" "mstr_discrete"
					( Origin gPackager )
				)
				( attribute "CDS_LOCATION" "R4P7"
					( Origin gPackager )
				)
				( attribute "CDS_SEC" "1"
					( Origin gPackager )
				)
				( attribute "LOCATION" "R4P7"
					( Origin gFrontEnd )
				)
				( attribute "MATERIAL" "EMPTY"
					( Origin gFrontEnd )
				)
				( attribute "PACK_TYPE" "0402"
					( Origin gFrontEnd )
				)
				( attribute "PART_NUMBER" "G21796-294"
					( Origin gFrontEnd )
				)
				( attribute "PHYS_PAGE" "90"
					( Origin gFrontEnd )
				)
				( attribute "ROOM" "PROC_SIDEBAND"
					( Origin gFrontEnd )
				)
				( attribute "ROT" "0"
					( Origin gFrontEnd )
				)
				( attribute "SEC" "1"
					( Origin gFrontEnd )
				)
				( attribute "SEC_TYPE" "0402"
					( Origin gFrontEnd )
				)
				( attribute "TOLERANCE" "1.0%"
					( Origin gFrontEnd )
				)
				( attribute "VALUE" "240"
					( Origin gFrontEnd )
				)
				( attribute "VER" "1"
					( Origin gFrontEnd )
				)
				( attribute "WATTAGE" "1/16W"
					( Origin gFrontEnd )
				)
				( attribute "XY" "(-425,2800)"
					( Origin gFrontEnd )
				)
				( attribute "CHIPS_PART_NAME" "RES"
					( Origin gPackager )
				)
				( attribute "CDS_PART_NAME" "RES_0402-240,1.0%,1/16W,EMPTY,A"
					( Origin gPackager )
				)
				( objectStatus "R4P7" )
				( pin "a"
					( attribute "PN" "1"
						( Origin gPackager )
					)
					( objectStatus "R4P7.1" )
				)
				( pin "b"
					( attribute "PN" "2"
						( Origin gPackager )
					)
					( objectStatus "R4P7.2" )
				)
			)
			( gate "@baseboard_fab2_lib.baseboard_fab2(sch_1):page90_i74"
				( attribute "BOM_COST" "PROC"
					( Origin gFrontEnd )
				)
				( attribute "CDS_LIB" "mstr_discrete"
					( Origin gPackager )
				)
				( attribute "CDS_LOCATION" "R7P15"
					( Origin gPackager )
				)
				( attribute "CDS_SEC" "1"
					( Origin gPackager )
				)
				( attribute "LOCATION" "R7P15"
					( Origin gFrontEnd )
				)
				( attribute "MATERIAL" "EMPTY"
					( Origin gFrontEnd )
				)
				( attribute "PACK_TYPE" "0402"
					( Origin gFrontEnd )
				)
				( attribute "PART_NUMBER" "G21796-294"
					( Origin gFrontEnd )
				)
				( attribute "PHYS_PAGE" "90"
					( Origin gFrontEnd )
				)
				( attribute "ROOM" "PROC_SIDEBAND"
					( Origin gFrontEnd )
				)
				( attribute "ROT" "0"
					( Origin gFrontEnd )
				)
				( attribute "SEC" "1"
					( Origin gFrontEnd )
				)
				( attribute "SEC_TYPE" "0402"
					( Origin gFrontEnd )
				)
				( attribute "TOLERANCE" "1.0%"
					( Origin gFrontEnd )
				)
				( attribute "VALUE" "240"
					( Origin gFrontEnd )
				)
				( attribute "VER" "1"
					( Origin gFrontEnd )
				)
				( attribute "WATTAGE" "1/16W"
					( Origin gFrontEnd )
				)
				( attribute "XY" "(-275,650)"
					( Origin gFrontEnd )
				)
				( attribute "CHIPS_PART_NAME" "RES"
					( Origin gPackager )
				)
				( attribute "CDS_PART_NAME" "RES_0402-240,1.0%,1/16W,EMPTY,A"
					( Origin gPackager )
				)
				( objectStatus "R7P15" )
				( pin "a"
					( attribute "PN" "1"
						( Origin gPackager )
					)
					( objectStatus "R7P15.1" )
				)
				( pin "b"
					( attribute "PN" "2"
						( Origin gPackager )
					)
					( objectStatus "R7P15.2" )
				)
			)
			( gate "@baseboard_fab2_lib.baseboard_fab2(sch_1):page90_i76"
				( attribute "BOM_COST" "PROC"
					( Origin gFrontEnd )
				)
				( attribute "CDS_LIB" "mstr_discrete"
					( Origin gPackager )
				)
				( attribute "CDS_LOCATION" "R7P22"
					( Origin gPackager )
				)
				( attribute "CDS_SEC" "1"
					( Origin gPackager )
				)
				( attribute "LOCATION" "R7P22"
					( Origin gFrontEnd )
				)
				( attribute "MATERIAL" "EMPTY"
					( Origin gFrontEnd )
				)
				( attribute "PACK_TYPE" "0402"
					( Origin gFrontEnd )
				)
				( attribute "PART_NUMBER" "G21796-294"
					( Origin gFrontEnd )
				)
				( attribute "PHYS_PAGE" "90"
					( Origin gFrontEnd )
				)
				( attribute "ROOM" "PROC_SIDEBAND"
					( Origin gFrontEnd )
				)
				( attribute "ROT" "0"
					( Origin gFrontEnd )
				)
				( attribute "SEC" "1"
					( Origin gFrontEnd )
				)
				( attribute "SEC_TYPE" "0402"
					( Origin gFrontEnd )
				)
				( attribute "TOLERANCE" "1.0%"
					( Origin gFrontEnd )
				)
				( attribute "VALUE" "240"
					( Origin gFrontEnd )
				)
				( attribute "VER" "1"
					( Origin gFrontEnd )
				)
				( attribute "WATTAGE" "1/16W"
					( Origin gFrontEnd )
				)
				( attribute "XY" "(-2475,800)"
					( Origin gFrontEnd )
				)
				( attribute "CHIPS_PART_NAME" "RES"
					( Origin gPackager )
				)
				( attribute "CDS_PART_NAME" "RES_0402-240,1.0%,1/16W,EMPTY,A"
					( Origin gPackager )
				)
				( objectStatus "R7P22" )
				( pin "a"
					( attribute "PN" "1"
						( Origin gPackager )
					)
					( objectStatus "R7P22.1" )
				)
				( pin "b"
					( attribute "PN" "2"
						( Origin gPackager )
					)
					( objectStatus "R7P22.2" )
				)
			)
			( gate "@baseboard_fab2_lib.baseboard_fab2(sch_1):page90_i79"
				( attribute "CDS_LIB" "mstr_discrete"
					( Origin gPackager )
				)
				( attribute "CDS_LOCATION" "R5P2"
					( Origin gPackager )
				)
				( attribute "CDS_SEC" "1"
					( Origin gPackager )
				)
				( attribute "LOCATION" "R5P2"
					( Origin gFrontEnd )
				)
				( attribute "MATERIAL" "CHIP"
					( Origin gFrontEnd )
				)
				( attribute "PACK_TYPE" "0402"
					( Origin gFrontEnd )
				)
				( attribute "PART_NUMBER" "G21796-047"
					( Origin gFrontEnd )
				)
				( attribute "PHYS_PAGE" "90"
					( Origin gFrontEnd )
				)
				( attribute "ROOM" "CPU0"
					( Origin gFrontEnd )
				)
				( attribute "ROT" "0"
					( Origin gFrontEnd )
				)
				( attribute "SEC" "1"
					( Origin gFrontEnd )
				)
				( attribute "SEC_TYPE" "0402"
					( Origin gFrontEnd )
				)
				( attribute "TOLERANCE" "1%"
					( Origin gFrontEnd )
				)
				( attribute "VALUE" "49.9"
					( Origin gFrontEnd )
				)
				( attribute "VER" "1"
					( Origin gFrontEnd )
				)
				( attribute "WATTAGE" "1/16W"
					( Origin gFrontEnd )
				)
				( attribute "XY" "(-1575,3200)"
					( Origin gFrontEnd )
				)
				( attribute "CHIPS_PART_NAME" "RES"
					( Origin gPackager )
				)
				( attribute "CDS_PART_NAME" "RES_0402-49.9,1%,1/16W,CHIP,G2A"
					( Origin gPackager )
				)
				( objectStatus "R5P2" )
				( pin "a"
					( attribute "PN" "1"
						( Origin gPackager )
					)
					( objectStatus "R5P2.1" )
				)
				( pin "b"
					( attribute "PN" "2"
						( Origin gPackager )
					)
					( objectStatus "R5P2.2" )
				)
			)
			( gate "@baseboard_fab2_lib.baseboard_fab2(sch_1):page90_i80"
				( attribute "CDS_LIB" "mstr_discrete"
					( Origin gPackager )
				)
				( attribute "CDS_LOCATION" "R5P3"
					( Origin gPackager )
				)
				( attribute "CDS_SEC" "1"
					( Origin gPackager )
				)
				( attribute "LOCATION" "R5P3"
					( Origin gFrontEnd )
				)
				( attribute "MATERIAL" "CHIP"
					( Origin gFrontEnd )
				)
				( attribute "PACK_TYPE" "0402"
					( Origin gFrontEnd )
				)
				( attribute "PART_NUMBER" "G21796-047"
					( Origin gFrontEnd )
				)
				( attribute "PHYS_PAGE" "90"
					( Origin gFrontEnd )
				)
				( attribute "ROOM" "CPU0"
					( Origin gFrontEnd )
				)
				( attribute "ROT" "0"
					( Origin gFrontEnd )
				)
				( attribute "SEC" "1"
					( Origin gFrontEnd )
				)
				( attribute "SEC_TYPE" "0402"
					( Origin gFrontEnd )
				)
				( attribute "TOLERANCE" "1%"
					( Origin gFrontEnd )
				)
				( attribute "VALUE" "49.9"
					( Origin gFrontEnd )
				)
				( attribute "VER" "1"
					( Origin gFrontEnd )
				)
				( attribute "WATTAGE" "1/16W"
					( Origin gFrontEnd )
				)
				( attribute "XY" "(-1575,3075)"
					( Origin gFrontEnd )
				)
				( attribute "CHIPS_PART_NAME" "RES"
					( Origin gPackager )
				)
				( attribute "CDS_PART_NAME" "RES_0402-49.9,1%,1/16W,CHIP,G2A"
					( Origin gPackager )
				)
				( objectStatus "R5P3" )
				( pin "a"
					( attribute "PN" "1"
						( Origin gPackager )
					)
					( objectStatus "R5P3.1" )
				)
				( pin "b"
					( attribute "PN" "2"
						( Origin gPackager )
					)
					( objectStatus "R5P3.2" )
				)
			)
			( gate "@baseboard_fab2_lib.baseboard_fab2(sch_1):page90_i81"
				( attribute "CDS_LIB" "mstr_discrete"
					( Origin gPackager )
				)
				( attribute "CDS_LOCATION" "R6D5"
					( Origin gPackager )
				)
				( attribute "CDS_SEC" "1"
					( Origin gPackager )
				)
				( attribute "LOCATION" "R6D5"
					( Origin gFrontEnd )
				)
				( attribute "MATERIAL" "CHIP"
					( Origin gFrontEnd )
				)
				( attribute "PACK_TYPE" "0402"
					( Origin gFrontEnd )
				)
				( attribute "PART_NUMBER" "G21796-047"
					( Origin gFrontEnd )
				)
				( attribute "PHYS_PAGE" "90"
					( Origin gFrontEnd )
				)
				( attribute "ROOM" "CPU0"
					( Origin gFrontEnd )
				)
				( attribute "ROT" "0"
					( Origin gFrontEnd )
				)
				( attribute "SEC" "1"
					( Origin gFrontEnd )
				)
				( attribute "SEC_TYPE" "0402"
					( Origin gFrontEnd )
				)
				( attribute "TOLERANCE" "1%"
					( Origin gFrontEnd )
				)
				( attribute "VALUE" "49.9"
					( Origin gFrontEnd )
				)
				( attribute "VER" "1"
					( Origin gFrontEnd )
				)
				( attribute "WATTAGE" "1/16W"
					( Origin gFrontEnd )
				)
				( attribute "XY" "(-1575,2925)"
					( Origin gFrontEnd )
				)
				( attribute "CHIPS_PART_NAME" "RES"
					( Origin gPackager )
				)
				( attribute "CDS_PART_NAME" "RES_0402-49.9,1%,1/16W,CHIP,G2A"
					( Origin gPackager )
				)
				( objectStatus "R6D5" )
				( pin "a"
					( attribute "PN" "1"
						( Origin gPackager )
					)
					( objectStatus "R6D5.1" )
				)
				( pin "b"
					( attribute "PN" "2"
						( Origin gPackager )
					)
					( objectStatus "R6D5.2" )
				)
			)
			( gate "@baseboard_fab2_lib.baseboard_fab2(sch_1):page90_i85"
				( attribute "CDS_LIB" "mstr_discrete"
					( Origin gPackager )
				)
				( attribute "CDS_LOCATION" "R8P1"
					( Origin gPackager )
				)
				( attribute "CDS_SEC" "1"
					( Origin gPackager )
				)
				( attribute "LOCATION" "R8P1"
					( Origin gFrontEnd )
				)
				( attribute "MATERIAL" "CHIP"
					( Origin gFrontEnd )
				)
				( attribute "PACK_TYPE" "0402"
					( Origin gFrontEnd )
				)
				( attribute "PART_NUMBER" "G21796-047"
					( Origin gFrontEnd )
				)
				( attribute "PHYS_PAGE" "90"
					( Origin gFrontEnd )
				)
				( attribute "ROOM" "CPU1"
					( Origin gFrontEnd )
				)
				( attribute "ROT" "0"
					( Origin gFrontEnd )
				)
				( attribute "SEC" "1"
					( Origin gFrontEnd )
				)
				( attribute "SEC_TYPE" "0402"
					( Origin gFrontEnd )
				)
				( attribute "TOLERANCE" "1%"
					( Origin gFrontEnd )
				)
				( attribute "VALUE" "49.9"
					( Origin gFrontEnd )
				)
				( attribute "VER" "1"
					( Origin gFrontEnd )
				)
				( attribute "WATTAGE" "1/16W"
					( Origin gFrontEnd )
				)
				( attribute "XY" "(325,2475)"
					( Origin gFrontEnd )
				)
				( attribute "CHIPS_PART_NAME" "RES"
					( Origin gPackager )
				)
				( attribute "CDS_PART_NAME" "RES_0402-49.9,1%,1/16W,CHIP,G2A"
					( Origin gPackager )
				)
				( objectStatus "R8P1" )
				( pin "a"
					( attribute "PN" "1"
						( Origin gPackager )
					)
					( objectStatus "R8P1.1" )
				)
				( pin "b"
					( attribute "PN" "2"
						( Origin gPackager )
					)
					( objectStatus "R8P1.2" )
				)
			)
			( gate "@baseboard_fab2_lib.baseboard_fab2(sch_1):page90_i86"
				( attribute "CDS_LIB" "mstr_discrete"
					( Origin gPackager )
				)
				( attribute "CDS_LOCATION" "R8P2"
					( Origin gPackager )
				)
				( attribute "CDS_SEC" "1"
					( Origin gPackager )
				)
				( attribute "LOCATION" "R8P2"
					( Origin gFrontEnd )
				)
				( attribute "MATERIAL" "CHIP"
					( Origin gFrontEnd )
				)
				( attribute "PACK_TYPE" "0402"
					( Origin gFrontEnd )
				)
				( attribute "PART_NUMBER" "G21796-047"
					( Origin gFrontEnd )
				)
				( attribute "PHYS_PAGE" "90"
					( Origin gFrontEnd )
				)
				( attribute "ROOM" "CPU1"
					( Origin gFrontEnd )
				)
				( attribute "ROT" "0"
					( Origin gFrontEnd )
				)
				( attribute "SEC" "1"
					( Origin gFrontEnd )
				)
				( attribute "SEC_TYPE" "0402"
					( Origin gFrontEnd )
				)
				( attribute "TOLERANCE" "1%"
					( Origin gFrontEnd )
				)
				( attribute "VALUE" "49.9"
					( Origin gFrontEnd )
				)
				( attribute "VER" "1"
					( Origin gFrontEnd )
				)
				( attribute "WATTAGE" "1/16W"
					( Origin gFrontEnd )
				)
				( attribute "XY" "(325,2350)"
					( Origin gFrontEnd )
				)
				( attribute "CHIPS_PART_NAME" "RES"
					( Origin gPackager )
				)
				( attribute "CDS_PART_NAME" "RES_0402-49.9,1%,1/16W,CHIP,G2A"
					( Origin gPackager )
				)
				( objectStatus "R8P2" )
				( pin "a"
					( attribute "PN" "1"
						( Origin gPackager )
					)
					( objectStatus "R8P2.1" )
				)
				( pin "b"
					( attribute "PN" "2"
						( Origin gPackager )
					)
					( objectStatus "R8P2.2" )
				)
			)
			( gate "@baseboard_fab2_lib.baseboard_fab2(sch_1):page90_i88"
				( attribute "CDS_LIB" "mstr_discrete"
					( Origin gPackager )
				)
				( attribute "CDS_LOCATION" "R3D9"
					( Origin gPackager )
				)
				( attribute "CDS_SEC" "1"
					( Origin gPackager )
				)
				( attribute "LOCATION" "R3D9"
					( Origin gFrontEnd )
				)
				( attribute "MATERIAL" "CHIP"
					( Origin gFrontEnd )
				)
				( attribute "PACK_TYPE" "0402"
					( Origin gFrontEnd )
				)
				( attribute "PART_NUMBER" "G21796-047"
					( Origin gFrontEnd )
				)
				( attribute "PHYS_PAGE" "90"
					( Origin gFrontEnd )
				)
				( attribute "ROOM" "CPU1"
					( Origin gFrontEnd )
				)
				( attribute "ROT" "0"
					( Origin gFrontEnd )
				)
				( attribute "SEC" "1"
					( Origin gFrontEnd )
				)
				( attribute "SEC_TYPE" "0402"
					( Origin gFrontEnd )
				)
				( attribute "TOLERANCE" "1%"
					( Origin gFrontEnd )
				)
				( attribute "VALUE" "49.9"
					( Origin gFrontEnd )
				)
				( attribute "VER" "1"
					( Origin gFrontEnd )
				)
				( attribute "WATTAGE" "1/16W"
					( Origin gFrontEnd )
				)
				( attribute "XY" "(325,2200)"
					( Origin gFrontEnd )
				)
				( attribute "CHIPS_PART_NAME" "RES"
					( Origin gPackager )
				)
				( attribute "CDS_PART_NAME" "RES_0402-49.9,1%,1/16W,CHIP,G2A"
					( Origin gPackager )
				)
				( objectStatus "R3D9" )
				( pin "a"
					( attribute "PN" "1"
						( Origin gPackager )
					)
					( objectStatus "R3D9.1" )
				)
				( pin "b"
					( attribute "PN" "2"
						( Origin gPackager )
					)
					( objectStatus "R3D9.2" )
				)
			)
			( gate "@baseboard_fab2_lib.baseboard_fab2(sch_1):page91_i1"
				( attribute "CDS_LIB" "mstr_sconn"
					( Origin gPackager )
				)
				( attribute "CDS_LOCATION" "J8B1"
					( Origin gPackager )
				)
				( attribute "CDS_SEC" "1"
					( Origin gPackager )
				)
				( attribute "LOCATION" "J8B1"
					( Origin gFrontEnd )
				)
				( attribute "MATERIAL" "SCONN"
					( Origin gFrontEnd )
				)
				( attribute "PACK_TYPE" "SM"
					( Origin gFrontEnd )
				)
				( attribute "PART_NUMBER" "H46321-001"
					( Origin gFrontEnd )
				)
				( attribute "PHYS_PAGE" "91"
					( Origin gFrontEnd )
				)
				( attribute "ROOM" "HFI"
					( Origin gFrontEnd )
				)
				( attribute "ROT" "0"
					( Origin gFrontEnd )
				)
				( attribute "SEC" "1"
					( Origin gPackager )
				)
				( attribute "VER" "1"
					( Origin gFrontEnd )
				)
				( attribute "XY" "(25,2825)"
					( Origin gFrontEnd )
				)
				( attribute "CHIPS_PART_NAME" "SCONN24_H46321001"
					( Origin gPackager )
				)
				( attribute "CDS_PART_NAME" "SCONN24_H46321001_SM-SCONN,H46A"
					( Origin gPackager )
				)
				( objectStatus "J8B1" )
				( pin "io1"
					( attribute "PN" "1"
						( Origin gPackager )
					)
					( objectStatus "J8B1.1" )
				)
				( pin "io2"
					( attribute "PN" "2"
						( Origin gPackager )
					)
					( objectStatus "J8B1.2" )
				)
				( pin "io3"
					( attribute "PN" "3"
						( Origin gPackager )
					)
					( objectStatus "J8B1.3" )
				)
				( pin "io4"
					( attribute "PN" "4"
						( Origin gPackager )
					)
					( objectStatus "J8B1.4" )
				)
				( pin "io5"
					( attribute "PN" "5"
						( Origin gPackager )
					)
					( objectStatus "J8B1.5" )
				)
				( pin "io6"
					( attribute "PN" "6"
						( Origin gPackager )
					)
					( objectStatus "J8B1.6" )
				)
				( pin "io7"
					( attribute "PN" "7"
						( Origin gPackager )
					)
					( objectStatus "J8B1.7" )
				)
				( pin "io8"
					( attribute "PN" "8"
						( Origin gPackager )
					)
					( objectStatus "J8B1.8" )
				)
				( pin "io9"
					( attribute "PN" "9"
						( Origin gPackager )
					)
					( objectStatus "J8B1.9" )
				)
				( pin "io10"
					( attribute "PN" "10"
						( Origin gPackager )
					)
					( objectStatus "J8B1.10" )
				)
				( pin "io11"
					( attribute "PN" "11"
						( Origin gPackager )
					)
					( objectStatus "J8B1.11" )
				)
				( pin "io12"
					( attribute "PN" "12"
						( Origin gPackager )
					)
					( objectStatus "J8B1.12" )
				)
				( pin "io13"
					( attribute "PN" "13"
						( Origin gPackager )
					)
					( objectStatus "J8B1.13" )
				)
				( pin "io14"
					( attribute "PN" "14"
						( Origin gPackager )
					)
					( objectStatus "J8B1.14" )
				)
				( pin "io15"
					( attribute "PN" "15"
						( Origin gPackager )
					)
					( objectStatus "J8B1.15" )
				)
				( pin "io16"
					( attribute "PN" "16"
						( Origin gPackager )
					)
					( objectStatus "J8B1.16" )
				)
				( pin "io17"
					( attribute "PN" "17"
						( Origin gPackager )
					)
					( objectStatus "J8B1.17" )
				)
				( pin "io18"
					( attribute "PN" "18"
						( Origin gPackager )
					)
					( objectStatus "J8B1.18" )
				)
				( pin "io19"
					( attribute "PN" "19"
						( Origin gPackager )
					)
					( objectStatus "J8B1.19" )
				)
				( pin "io20"
					( attribute "PN" "20"
						( Origin gPackager )
					)
					( objectStatus "J8B1.20" )
				)
				( pin "io21"
					( attribute "PN" "21"
						( Origin gPackager )
					)
					( objectStatus "J8B1.21" )
				)
				( pin "io22"
					( attribute "PN" "22"
						( Origin gPackager )
					)
					( objectStatus "J8B1.22" )
				)
				( pin "io23"
					( attribute "PN" "23"
						( Origin gPackager )
					)
					( objectStatus "J8B1.23" )
				)
				( pin "io24"
					( attribute "PN" "24"
						( Origin gPackager )
					)
					( objectStatus "J8B1.24" )
				)
				( pin "mp1"
					( attribute "PN" "MP1"
						( Origin gPackager )
					)
					( objectStatus "J8B1.MP1" )
				)
				( pin "mp2"
					( attribute "PN" "MP2"
						( Origin gPackager )
					)
					( objectStatus "J8B1.MP2" )
				)
			)
			( gate "@baseboard_fab2_lib.baseboard_fab2(sch_1):page91_i14"
				( attribute "CDS_LIB" "mstr_discrete"
					( Origin gPackager )
				)
				( attribute "CDS_LOCATION" "R8B8"
					( Origin gPackager )
				)
				( attribute "CDS_SEC" "1"
					( Origin gPackager )
				)
				( attribute "LOCATION" "R8B8"
					( Origin gFrontEnd )
				)
				( attribute "MATERIAL" "CHIP"
					( Origin gFrontEnd )
				)
				( attribute "PACK_TYPE" "0402"
					( Origin gFrontEnd )
				)
				( attribute "PART_NUMBER" "G21796-072"
					( Origin gFrontEnd )
				)
				( attribute "PHYS_PAGE" "91"
					( Origin gFrontEnd )
				)
				( attribute "ROOM" "HFI"
					( Origin gFrontEnd )
				)
				( attribute "ROT" "0"
					( Origin gFrontEnd )
				)
				( attribute "SEC" "1"
					( Origin gFrontEnd )
				)
				( attribute "SEC_TYPE" "0402"
					( Origin gFrontEnd )
				)
				( attribute "SIGNAL_MODEL" "DEFAULT_RESISTOR_4750OHM_2_1"
					( Origin gFrontEnd )
				)
				( attribute "TOLERANCE" "1%"
					( Origin gFrontEnd )
				)
				( attribute "VALUE" "4.75K"
					( Origin gFrontEnd )
				)
				( attribute "VER" "2"
					( Origin gFrontEnd )
				)
				( attribute "WATTAGE" "1/16W"
					( Origin gFrontEnd )
				)
				( attribute "XY" "(1400,3350)"
					( Origin gFrontEnd )
				)
				( attribute "CHIPS_PART_NAME" "RES"
					( Origin gPackager )
				)
				( attribute "CDS_PART_NAME" "RES_0402-4.75K,1%,1/16W,CHIP,GA"
					( Origin gPackager )
				)
				( objectStatus "R8B8" )
				( pin "a"
					( attribute "PN" "1"
						( Origin gPackager )
					)
					( objectStatus "R8B8.1" )
				)
				( pin "b"
					( attribute "PN" "2"
						( Origin gPackager )
					)
					( objectStatus "R8B8.2" )
				)
			)
			( gate "@baseboard_fab2_lib.baseboard_fab2(sch_1):page91_i16"
				( attribute "CDS_LIB" "mstr_discrete"
					( Origin gPackager )
				)
				( attribute "CDS_LOCATION" "R8B10"
					( Origin gPackager )
				)
				( attribute "CDS_SEC" "1"
					( Origin gPackager )
				)
				( attribute "LOCATION" "R8B10"
					( Origin gFrontEnd )
				)
				( attribute "MATERIAL" "CHIP"
					( Origin gFrontEnd )
				)
				( attribute "PACK_TYPE" "0402"
					( Origin gFrontEnd )
				)
				( attribute "PART_NUMBER" "G21796-072"
					( Origin gFrontEnd )
				)
				( attribute "PHYS_PAGE" "91"
					( Origin gFrontEnd )
				)
				( attribute "ROOM" "HFI"
					( Origin gFrontEnd )
				)
				( attribute "ROT" "0"
					( Origin gFrontEnd )
				)
				( attribute "SEC" "1"
					( Origin gFrontEnd )
				)
				( attribute "SEC_TYPE" "0402"
					( Origin gFrontEnd )
				)
				( attribute "SIGNAL_MODEL" "DEFAULT_RESISTOR_4750OHM_2_1"
					( Origin gFrontEnd )
				)
				( attribute "TOLERANCE" "1%"
					( Origin gFrontEnd )
				)
				( attribute "VALUE" "4.75K"
					( Origin gFrontEnd )
				)
				( attribute "VER" "2"
					( Origin gFrontEnd )
				)
				( attribute "WATTAGE" "1/16W"
					( Origin gFrontEnd )
				)
				( attribute "XY" "(1150,3350)"
					( Origin gFrontEnd )
				)
				( attribute "CHIPS_PART_NAME" "RES"
					( Origin gPackager )
				)
				( attribute "CDS_PART_NAME" "RES_0402-4.75K,1%,1/16W,CHIP,GA"
					( Origin gPackager )
				)
				( objectStatus "R8B10" )
				( pin "a"
					( attribute "PN" "1"
						( Origin gPackager )
					)
					( objectStatus "R8B10.1" )
				)
				( pin "b"
					( attribute "PN" "2"
						( Origin gPackager )
					)
					( objectStatus "R8B10.2" )
				)
			)
			( gate "@baseboard_fab2_lib.baseboard_fab2(sch_1):page91_i17"
				( attribute "CDS_LIB" "mstr_discrete"
					( Origin gPackager )
				)
				( attribute "CDS_LOCATION" "R8B16"
					( Origin gPackager )
				)
				( attribute "CDS_SEC" "1"
					( Origin gPackager )
				)
				( attribute "LOCATION" "R8B16"
					( Origin gFrontEnd )
				)
				( attribute "MATERIAL" "CHIP"
					( Origin gFrontEnd )
				)
				( attribute "PACK_TYPE" "0402"
					( Origin gFrontEnd )
				)
				( attribute "PART_NUMBER" "G21796-072"
					( Origin gFrontEnd )
				)
				( attribute "PHYS_PAGE" "91"
					( Origin gFrontEnd )
				)
				( attribute "ROOM" "HFI"
					( Origin gFrontEnd )
				)
				( attribute "ROT" "0"
					( Origin gFrontEnd )
				)
				( attribute "SEC" "1"
					( Origin gFrontEnd )
				)
				( attribute "SEC_TYPE" "0402"
					( Origin gFrontEnd )
				)
				( attribute "SIGNAL_MODEL" "DEFAULT_RESISTOR_4750OHM_2_1"
					( Origin gFrontEnd )
				)
				( attribute "TOLERANCE" "1%"
					( Origin gFrontEnd )
				)
				( attribute "VALUE" "4.75K"
					( Origin gFrontEnd )
				)
				( attribute "VER" "2"
					( Origin gFrontEnd )
				)
				( attribute "WATTAGE" "1/16W"
					( Origin gFrontEnd )
				)
				( attribute "XY" "(900,3350)"
					( Origin gFrontEnd )
				)
				( attribute "CHIPS_PART_NAME" "RES"
					( Origin gPackager )
				)
				( attribute "CDS_PART_NAME" "RES_0402-4.75K,1%,1/16W,CHIP,GA"
					( Origin gPackager )
				)
				( objectStatus "R8B16" )
				( pin "a"
					( attribute "PN" "1"
						( Origin gPackager )
					)
					( objectStatus "R8B16.1" )
				)
				( pin "b"
					( attribute "PN" "2"
						( Origin gPackager )
					)
					( objectStatus "R8B16.2" )
				)
			)
			( gate "@baseboard_fab2_lib.baseboard_fab2(sch_1):page91_i18"
				( attribute "CDS_LIB" "mstr_discrete"
					( Origin gPackager )
				)
				( attribute "CDS_LOCATION" "R8B17"
					( Origin gPackager )
				)
				( attribute "CDS_SEC" "1"
					( Origin gPackager )
				)
				( attribute "LOCATION" "R8B17"
					( Origin gFrontEnd )
				)
				( attribute "MATERIAL" "CHIP"
					( Origin gFrontEnd )
				)
				( attribute "PACK_TYPE" "0402"
					( Origin gFrontEnd )
				)
				( attribute "PART_NUMBER" "G21796-072"
					( Origin gFrontEnd )
				)
				( attribute "PHYS_PAGE" "91"
					( Origin gFrontEnd )
				)
				( attribute "ROOM" "HFI"
					( Origin gFrontEnd )
				)
				( attribute "ROT" "0"
					( Origin gFrontEnd )
				)
				( attribute "SEC" "1"
					( Origin gFrontEnd )
				)
				( attribute "SEC_TYPE" "0402"
					( Origin gFrontEnd )
				)
				( attribute "SIGNAL_MODEL" "DEFAULT_RESISTOR_4750OHM_2_1"
					( Origin gFrontEnd )
				)
				( attribute "TOLERANCE" "1%"
					( Origin gFrontEnd )
				)
				( attribute "VALUE" "4.75K"
					( Origin gFrontEnd )
				)
				( attribute "VER" "2"
					( Origin gFrontEnd )
				)
				( attribute "WATTAGE" "1/16W"
					( Origin gFrontEnd )
				)
				( attribute "XY" "(650,3350)"
					( Origin gFrontEnd )
				)
				( attribute "CHIPS_PART_NAME" "RES"
					( Origin gPackager )
				)
				( attribute "CDS_PART_NAME" "RES_0402-4.75K,1%,1/16W,CHIP,GA"
					( Origin gPackager )
				)
				( objectStatus "R8B17" )
				( pin "a"
					( attribute "PN" "1"
						( Origin gPackager )
					)
					( objectStatus "R8B17.1" )
				)
				( pin "b"
					( attribute "PN" "2"
						( Origin gPackager )
					)
					( objectStatus "R8B17.2" )
				)
			)
			( gate "@baseboard_fab2_lib.baseboard_fab2(sch_1):page91_i20"
				( attribute "CDS_LIB" "mstr_discrete"
					( Origin gPackager )
				)
				( attribute "CDS_LOCATION" "R8B18"
					( Origin gPackager )
				)
				( attribute "CDS_SEC" "1"
					( Origin gPackager )
				)
				( attribute "LOCATION" "R8B18"
					( Origin gFrontEnd )
				)
				( attribute "MATERIAL" "CHIP"
					( Origin gFrontEnd )
				)
				( attribute "PACK_TYPE" "0402"
					( Origin gFrontEnd )
				)
				( attribute "PART_NUMBER" "G21796-072"
					( Origin gFrontEnd )
				)
				( attribute "PHYS_PAGE" "91"
					( Origin gFrontEnd )
				)
				( attribute "ROOM" "HFI"
					( Origin gFrontEnd )
				)
				( attribute "ROT" "2"
					( Origin gFrontEnd )
				)
				( attribute "SEC" "1"
					( Origin gFrontEnd )
				)
				( attribute "SEC_TYPE" "0402"
					( Origin gFrontEnd )
				)
				( attribute "SIGNAL_MODEL" "DEFAULT_RESISTOR_4750OHM_2_1"
					( Origin gFrontEnd )
				)
				( attribute "TOLERANCE" "1%"
					( Origin gFrontEnd )
				)
				( attribute "VALUE" "4.75K"
					( Origin gFrontEnd )
				)
				( attribute "VER" "2"
					( Origin gFrontEnd )
				)
				( attribute "WATTAGE" "1/16W"
					( Origin gFrontEnd )
				)
				( attribute "XY" "(-600,3325)"
					( Origin gFrontEnd )
				)
				( attribute "CHIPS_PART_NAME" "RES"
					( Origin gPackager )
				)
				( attribute "CDS_PART_NAME" "RES_0402-4.75K,1%,1/16W,CHIP,GA"
					( Origin gPackager )
				)
				( objectStatus "R8B18" )
				( pin "a"
					( attribute "PN" "1"
						( Origin gPackager )
					)
					( objectStatus "R8B18.1" )
				)
				( pin "b"
					( attribute "PN" "2"
						( Origin gPackager )
					)
					( objectStatus "R8B18.2" )
				)
			)
			( gate "@baseboard_fab2_lib.baseboard_fab2(sch_1):page91_i21"
				( attribute "CDS_LIB" "mstr_discrete"
					( Origin gPackager )
				)
				( attribute "CDS_LOCATION" "R8B19"
					( Origin gPackager )
				)
				( attribute "CDS_SEC" "1"
					( Origin gPackager )
				)
				( attribute "LOCATION" "R8B19"
					( Origin gFrontEnd )
				)
				( attribute "MATERIAL" "CHIP"
					( Origin gFrontEnd )
				)
				( attribute "PACK_TYPE" "0402"
					( Origin gFrontEnd )
				)
				( attribute "PART_NUMBER" "G21796-072"
					( Origin gFrontEnd )
				)
				( attribute "PHYS_PAGE" "91"
					( Origin gFrontEnd )
				)
				( attribute "ROOM" "HFI"
					( Origin gFrontEnd )
				)
				( attribute "ROT" "2"
					( Origin gFrontEnd )
				)
				( attribute "SEC" "1"
					( Origin gFrontEnd )
				)
				( attribute "SEC_TYPE" "0402"
					( Origin gFrontEnd )
				)
				( attribute "SIGNAL_MODEL" "DEFAULT_RESISTOR_4750OHM_2_1"
					( Origin gFrontEnd )
				)
				( attribute "TOLERANCE" "1%"
					( Origin gFrontEnd )
				)
				( attribute "VALUE" "4.75K"
					( Origin gFrontEnd )
				)
				( attribute "VER" "2"
					( Origin gFrontEnd )
				)
				( attribute "WATTAGE" "1/16W"
					( Origin gFrontEnd )
				)
				( attribute "XY" "(-975,3325)"
					( Origin gFrontEnd )
				)
				( attribute "CHIPS_PART_NAME" "RES"
					( Origin gPackager )
				)
				( attribute "CDS_PART_NAME" "RES_0402-4.75K,1%,1/16W,CHIP,GA"
					( Origin gPackager )
				)
				( objectStatus "R8B19" )
				( pin "a"
					( attribute "PN" "1"
						( Origin gPackager )
					)
					( objectStatus "R8B19.1" )
				)
				( pin "b"
					( attribute "PN" "2"
						( Origin gPackager )
					)
					( objectStatus "R8B19.2" )
				)
			)
			( gate "@baseboard_fab2_lib.baseboard_fab2(sch_1):page91_i22"
				( attribute "CDS_LIB" "mstr_discrete"
					( Origin gPackager )
				)
				( attribute "CDS_LOCATION" "R8B5"
					( Origin gPackager )
				)
				( attribute "CDS_SEC" "1"
					( Origin gPackager )
				)
				( attribute "LOCATION" "R8B5"
					( Origin gFrontEnd )
				)
				( attribute "MATERIAL" "CHIP"
					( Origin gFrontEnd )
				)
				( attribute "PACK_TYPE" "0402"
					( Origin gFrontEnd )
				)
				( attribute "PART_NUMBER" "G21796-072"
					( Origin gFrontEnd )
				)
				( attribute "PHYS_PAGE" "91"
					( Origin gFrontEnd )
				)
				( attribute "ROOM" "HFI"
					( Origin gFrontEnd )
				)
				( attribute "ROT" "2"
					( Origin gFrontEnd )
				)
				( attribute "SEC" "1"
					( Origin gFrontEnd )
				)
				( attribute "SEC_TYPE" "0402"
					( Origin gFrontEnd )
				)
				( attribute "SIGNAL_MODEL" "DEFAULT_RESISTOR_4750OHM_2_1"
					( Origin gFrontEnd )
				)
				( attribute "TOLERANCE" "1%"
					( Origin gFrontEnd )
				)
				( attribute "VALUE" "4.75K"
					( Origin gFrontEnd )
				)
				( attribute "VER" "2"
					( Origin gFrontEnd )
				)
				( attribute "WATTAGE" "1/16W"
					( Origin gFrontEnd )
				)
				( attribute "XY" "(-1350,3325)"
					( Origin gFrontEnd )
				)
				( attribute "CHIPS_PART_NAME" "RES"
					( Origin gPackager )
				)
				( attribute "CDS_PART_NAME" "RES_0402-4.75K,1%,1/16W,CHIP,GA"
					( Origin gPackager )
				)
				( objectStatus "R8B5" )
				( pin "a"
					( attribute "PN" "1"
						( Origin gPackager )
					)
					( objectStatus "R8B5.1" )
				)
				( pin "b"
					( attribute "PN" "2"
						( Origin gPackager )
					)
					( objectStatus "R8B5.2" )
				)
			)
			( gate "@baseboard_fab2_lib.baseboard_fab2(sch_1):page91_i24"
				( attribute "CDS_LIB" "mstr_discrete"
					( Origin gPackager )
				)
				( attribute "CDS_LOCATION" "R8B3"
					( Origin gPackager )
				)
				( attribute "CDS_SEC" "1"
					( Origin gPackager )
				)
				( attribute "LOCATION" "R8B3"
					( Origin gFrontEnd )
				)
				( attribute "MATERIAL" "CHIP"
					( Origin gFrontEnd )
				)
				( attribute "PACK_TYPE" "0402"
					( Origin gFrontEnd )
				)
				( attribute "PART_NUMBER" "G21796-072"
					( Origin gFrontEnd )
				)
				( attribute "PHYS_PAGE" "91"
					( Origin gFrontEnd )
				)
				( attribute "ROOM" "HFI"
					( Origin gFrontEnd )
				)
				( attribute "ROT" "2"
					( Origin gFrontEnd )
				)
				( attribute "SEC" "1"
					( Origin gFrontEnd )
				)
				( attribute "SEC_TYPE" "0402"
					( Origin gFrontEnd )
				)
				( attribute "SIGNAL_MODEL" "DEFAULT_RESISTOR_4750OHM_2_1"
					( Origin gFrontEnd )
				)
				( attribute "TOLERANCE" "1%"
					( Origin gFrontEnd )
				)
				( attribute "VALUE" "4.75K"
					( Origin gFrontEnd )
				)
				( attribute "VER" "2"
					( Origin gFrontEnd )
				)
				( attribute "WATTAGE" "1/16W"
					( Origin gFrontEnd )
				)
				( attribute "XY" "(-1725,3325)"
					( Origin gFrontEnd )
				)
				( attribute "CHIPS_PART_NAME" "RES"
					( Origin gPackager )
				)
				( attribute "CDS_PART_NAME" "RES_0402-4.75K,1%,1/16W,CHIP,GA"
					( Origin gPackager )
				)
				( objectStatus "R8B3" )
				( pin "a"
					( attribute "PN" "1"
						( Origin gPackager )
					)
					( objectStatus "R8B3.1" )
				)
				( pin "b"
					( attribute "PN" "2"
						( Origin gPackager )
					)
					( objectStatus "R8B3.2" )
				)
			)
			( gate "@baseboard_fab2_lib.baseboard_fab2(sch_1):page91_i34"
				( attribute "CDS_LIB" "mstr_discrete"
					( Origin gPackager )
				)
				( attribute "CDS_LOCATION" "R8B13"
					( Origin gPackager )
				)
				( attribute "CDS_SEC" "1"
					( Origin gPackager )
				)
				( attribute "LOCATION" "R8B13"
					( Origin gFrontEnd )
				)
				( attribute "MATERIAL" "CHIP"
					( Origin gFrontEnd )
				)
				( attribute "PACK_TYPE" "0402"
					( Origin gFrontEnd )
				)
				( attribute "PART_NUMBER" "G21796-336"
					( Origin gFrontEnd )
				)
				( attribute "PHYS_PAGE" "91"
					( Origin gFrontEnd )
				)
				( attribute "ROOM" "SMBUS_CPU0_STL"
					( Origin gFrontEnd )
				)
				( attribute "ROT" "0"
					( Origin gFrontEnd )
				)
				( attribute "SEC" "1"
					( Origin gFrontEnd )
				)
				( attribute "SEC_TYPE" "0402"
					( Origin gFrontEnd )
				)
				( attribute "TOLERANCE" "1%"
					( Origin gFrontEnd )
				)
				( attribute "VALUE" "1.8K"
					( Origin gFrontEnd )
				)
				( attribute "VER" "2"
					( Origin gFrontEnd )
				)
				( attribute "WATTAGE" "1/16W"
					( Origin gFrontEnd )
				)
				( attribute "XY" "(1650,3350)"
					( Origin gFrontEnd )
				)
				( attribute "CHIPS_PART_NAME" "RES"
					( Origin gPackager )
				)
				( attribute "CDS_PART_NAME" "RES_0402-1.8K,1%,1/16W,CHIP,G2A"
					( Origin gPackager )
				)
				( objectStatus "R8B13" )
				( pin "a"
					( attribute "PN" "1"
						( Origin gPackager )
					)
					( objectStatus "R8B13.1" )
				)
				( pin "b"
					( attribute "PN" "2"
						( Origin gPackager )
					)
					( objectStatus "R8B13.2" )
				)
			)
			( gate "@baseboard_fab2_lib.baseboard_fab2(sch_1):page91_i35"
				( attribute "CDS_LIB" "mstr_discrete"
					( Origin gPackager )
				)
				( attribute "CDS_LOCATION" "R8B11"
					( Origin gPackager )
				)
				( attribute "CDS_SEC" "1"
					( Origin gPackager )
				)
				( attribute "LOCATION" "R8B11"
					( Origin gFrontEnd )
				)
				( attribute "MATERIAL" "CHIP"
					( Origin gFrontEnd )
				)
				( attribute "PACK_TYPE" "0402"
					( Origin gFrontEnd )
				)
				( attribute "PART_NUMBER" "G21796-336"
					( Origin gFrontEnd )
				)
				( attribute "PHYS_PAGE" "91"
					( Origin gFrontEnd )
				)
				( attribute "ROOM" "SMBUS_CPU0_STL"
					( Origin gFrontEnd )
				)
				( attribute "ROT" "0"
					( Origin gFrontEnd )
				)
				( attribute "SEC" "1"
					( Origin gFrontEnd )
				)
				( attribute "SEC_TYPE" "0402"
					( Origin gFrontEnd )
				)
				( attribute "TOLERANCE" "1%"
					( Origin gFrontEnd )
				)
				( attribute "VALUE" "1.8K"
					( Origin gFrontEnd )
				)
				( attribute "VER" "2"
					( Origin gFrontEnd )
				)
				( attribute "WATTAGE" "1/16W"
					( Origin gFrontEnd )
				)
				( attribute "XY" "(1875,3350)"
					( Origin gFrontEnd )
				)
				( attribute "CHIPS_PART_NAME" "RES"
					( Origin gPackager )
				)
				( attribute "CDS_PART_NAME" "RES_0402-1.8K,1%,1/16W,CHIP,G2A"
					( Origin gPackager )
				)
				( objectStatus "R8B11" )
				( pin "a"
					( attribute "PN" "1"
						( Origin gPackager )
					)
					( objectStatus "R8B11.1" )
				)
				( pin "b"
					( attribute "PN" "2"
						( Origin gPackager )
					)
					( objectStatus "R8B11.2" )
				)
			)
			( gate "@baseboard_fab2_lib.baseboard_fab2(sch_1):page91_i36"
				( attribute "CDS_LIB" "mstr_discrete"
					( Origin gPackager )
				)
				( attribute "CDS_LOCATION" "R8B7"
					( Origin gPackager )
				)
				( attribute "CDS_SEC" "1"
					( Origin gPackager )
				)
				( attribute "LOCATION" "R8B7"
					( Origin gFrontEnd )
				)
				( attribute "MATERIAL" "CHIP"
					( Origin gFrontEnd )
				)
				( attribute "PACK_TYPE" "0402"
					( Origin gFrontEnd )
				)
				( attribute "PART_NUMBER" "G21796-336"
					( Origin gFrontEnd )
				)
				( attribute "PHYS_PAGE" "91"
					( Origin gFrontEnd )
				)
				( attribute "ROOM" "SMBUS_CPU0_STL"
					( Origin gFrontEnd )
				)
				( attribute "ROT" "0"
					( Origin gFrontEnd )
				)
				( attribute "SEC" "1"
					( Origin gFrontEnd )
				)
				( attribute "SEC_TYPE" "0402"
					( Origin gFrontEnd )
				)
				( attribute "TOLERANCE" "1%"
					( Origin gFrontEnd )
				)
				( attribute "VALUE" "1.8K"
					( Origin gFrontEnd )
				)
				( attribute "VER" "2"
					( Origin gFrontEnd )
				)
				( attribute "WATTAGE" "1/16W"
					( Origin gFrontEnd )
				)
				( attribute "XY" "(2125,3350)"
					( Origin gFrontEnd )
				)
				( attribute "CHIPS_PART_NAME" "RES"
					( Origin gPackager )
				)
				( attribute "CDS_PART_NAME" "RES_0402-1.8K,1%,1/16W,CHIP,G2A"
					( Origin gPackager )
				)
				( objectStatus "R8B7" )
				( pin "a"
					( attribute "PN" "1"
						( Origin gPackager )
					)
					( objectStatus "R8B7.1" )
				)
				( pin "b"
					( attribute "PN" "2"
						( Origin gPackager )
					)
					( objectStatus "R8B7.2" )
				)
			)
			( gate "@baseboard_fab2_lib.baseboard_fab2(sch_1):page91_i37"
				( attribute "CDS_LIB" "mstr_discrete"
					( Origin gPackager )
				)
				( attribute "CDS_LOCATION" "R8B6"
					( Origin gPackager )
				)
				( attribute "CDS_SEC" "1"
					( Origin gPackager )
				)
				( attribute "LOCATION" "R8B6"
					( Origin gFrontEnd )
				)
				( attribute "MATERIAL" "CHIP"
					( Origin gFrontEnd )
				)
				( attribute "PACK_TYPE" "0402"
					( Origin gFrontEnd )
				)
				( attribute "PART_NUMBER" "G21796-336"
					( Origin gFrontEnd )
				)
				( attribute "PHYS_PAGE" "91"
					( Origin gFrontEnd )
				)
				( attribute "ROOM" "SMBUS_CPU0_STL"
					( Origin gFrontEnd )
				)
				( attribute "ROT" "0"
					( Origin gFrontEnd )
				)
				( attribute "SEC" "1"
					( Origin gFrontEnd )
				)
				( attribute "SEC_TYPE" "0402"
					( Origin gFrontEnd )
				)
				( attribute "TOLERANCE" "1%"
					( Origin gFrontEnd )
				)
				( attribute "VALUE" "1.8K"
					( Origin gFrontEnd )
				)
				( attribute "VER" "2"
					( Origin gFrontEnd )
				)
				( attribute "WATTAGE" "1/16W"
					( Origin gFrontEnd )
				)
				( attribute "XY" "(2400,3350)"
					( Origin gFrontEnd )
				)
				( attribute "CHIPS_PART_NAME" "RES"
					( Origin gPackager )
				)
				( attribute "CDS_PART_NAME" "RES_0402-1.8K,1%,1/16W,CHIP,G2A"
					( Origin gPackager )
				)
				( objectStatus "R8B6" )
				( pin "a"
					( attribute "PN" "1"
						( Origin gPackager )
					)
					( objectStatus "R8B6.1" )
				)
				( pin "b"
					( attribute "PN" "2"
						( Origin gPackager )
					)
					( objectStatus "R8B6.2" )
				)
			)
			( gate "@baseboard_fab2_lib.baseboard_fab2(sch_1):page92_i1"
				( attribute "BOM_COST" "PROC_SIDEBAND"
					( Origin gFrontEnd )
				)
				( attribute "CDS_LIB" "mstr_digital"
					( Origin gPackager )
				)
				( attribute "CDS_LOCATION" "U3P2"
					( Origin gPackager )
				)
				( attribute "CDS_SEC" "1"
					( Origin gPackager )
				)
				( attribute "LOCATION" "U3P2"
					( Origin gFrontEnd )
				)
				( attribute "MATERIAL" "IC"
					( Origin gFrontEnd )
				)
				( attribute "PACK_TYPE" "SM"
					( Origin gFrontEnd )
				)
				( attribute "PART_NUMBER" "D66151-001"
					( Origin gFrontEnd )
				)
				( attribute "PHYS_PAGE" "92"
					( Origin gFrontEnd )
				)
				( attribute "ROOM" "PROC_SIDEBAND"
					( Origin gFrontEnd )
				)
				( attribute "ROT" "2"
					( Origin gFrontEnd )
				)
				( attribute "SEC" "1"
					( Origin gFrontEnd )
				)
				( attribute "SEC_TYPE" "SM"
					( Origin gFrontEnd )
				)
				( attribute "VER" "1"
					( Origin gFrontEnd )
				)
				( attribute "XY" "(-1825,4250)"
					( Origin gFrontEnd )
				)
				( attribute "CHIPS_PART_NAME" "GTL2014"
					( Origin gPackager )
				)
				( attribute "CDS_PART_NAME" "GTL2014_SM-IC,D66151-001"
					( Origin gPackager )
				)
				( objectStatus "U3P2" )
				( pin "a0"
					( attribute "PN" "13"
						( Origin gPackager )
					)
					( objectStatus "U3P2.13" )
				)
				( pin "a1"
					( attribute "PN" "12"
						( Origin gPackager )
					)
					( objectStatus "U3P2.12" )
				)
				( pin "a2"
					( attribute "PN" "10"
						( Origin gPackager )
					)
					( objectStatus "U3P2.10" )
				)
				( pin "a3"
					( attribute "PN" "9"
						( Origin gPackager )
					)
					( objectStatus "U3P2.9" )
				)
				( pin "b0"
					( attribute "PN" "2"
						( Origin gPackager )
					)
					( objectStatus "U3P2.2" )
				)
				( pin "b1"
					( attribute "PN" "3"
						( Origin gPackager )
					)
					( objectStatus "U3P2.3" )
				)
				( pin "b2"
					( attribute "PN" "5"
						( Origin gPackager )
					)
					( objectStatus "U3P2.5" )
				)
				( pin "b3"
					( attribute "PN" "6"
						( Origin gPackager )
					)
					( objectStatus "U3P2.6" )
				)
				( pin "dir"
					( attribute "PN" "1"
						( Origin gPackager )
					)
					( objectStatus "U3P2.1" )
				)
				( pin "gnd(0)"
					( attribute "PN" "7"
						( Origin gPackager )
					)
					( objectStatus "U3P2.7" )
				)
				( pin "gnd(1)"
					( attribute "PN" "8"
						( Origin gPackager )
					)
					( objectStatus "U3P2.8" )
				)
				( pin "gnd(2)"
					( attribute "PN" "11"
						( Origin gPackager )
					)
					( objectStatus "U3P2.11" )
				)
				( pin "vcc"
					( attribute "PN" "14"
						( Origin gPackager )
					)
					( objectStatus "U3P2.14" )
				)
				( pin "vref"
					( attribute "PN" "4"
						( Origin gPackager )
					)
					( objectStatus "U3P2.4" )
				)
			)
			( gate "@baseboard_fab2_lib.baseboard_fab2(sch_1):page92_i9"
				( attribute "BOM_COST" "PROC_SIDEBAND"
					( Origin gFrontEnd )
				)
				( attribute "CDS_LIB" "mstr_discrete"
					( Origin gPackager )
				)
				( attribute "CDS_LOCATION" "R3P41"
					( Origin gPackager )
				)
				( attribute "CDS_SEC" "1"
					( Origin gPackager )
				)
				( attribute "LOCATION" "R3P41"
					( Origin gFrontEnd )
				)
				( attribute "MATERIAL" "CHIP"
					( Origin gFrontEnd )
				)
				( attribute "PACK_TYPE" "0402"
					( Origin gFrontEnd )
				)
				( attribute "PART_NUMBER" "G21796-267"
					( Origin gFrontEnd )
				)
				( attribute "PHYS_PAGE" "92"
					( Origin gFrontEnd )
				)
				( attribute "ROOM" "PROC_SIDEBAND"
					( Origin gFrontEnd )
				)
				( attribute "ROT" "0"
					( Origin gFrontEnd )
				)
				( attribute "SEC" "1"
					( Origin gFrontEnd )
				)
				( attribute "SEC_TYPE" "0402"
					( Origin gFrontEnd )
				)
				( attribute "TOLERANCE" "1.0%"
					( Origin gFrontEnd )
				)
				( attribute "VALUE" "75"
					( Origin gFrontEnd )
				)
				( attribute "VER" "2"
					( Origin gFrontEnd )
				)
				( attribute "WATTAGE" "1/16W"
					( Origin gFrontEnd )
				)
				( attribute "XY" "(-2900,4525)"
					( Origin gFrontEnd )
				)
				( attribute "CHIPS_PART_NAME" "RES"
					( Origin gPackager )
				)
				( attribute "CDS_PART_NAME" "RES_0402-75,1.0%,1/16W,CHIP,G2A"
					( Origin gPackager )
				)
				( objectStatus "R3P41" )
				( pin "a"
					( attribute "PN" "1"
						( Origin gPackager )
					)
					( objectStatus "R3P41.1" )
				)
				( pin "b"
					( attribute "PN" "2"
						( Origin gPackager )
					)
					( objectStatus "R3P41.2" )
				)
			)
			( gate "@baseboard_fab2_lib.baseboard_fab2(sch_1):page92_i12"
				( attribute "BOM_COST" "PROC_SIDEBAND"
					( Origin gFrontEnd )
				)
				( attribute "CDS_LIB" "mstr_discrete"
					( Origin gPackager )
				)
				( attribute "CDS_LOCATION" "R3P46"
					( Origin gPackager )
				)
				( attribute "CDS_SEC" "1"
					( Origin gPackager )
				)
				( attribute "LOCATION" "R3P46"
					( Origin gFrontEnd )
				)
				( attribute "MATERIAL" "CHIP"
					( Origin gFrontEnd )
				)
				( attribute "PACK_TYPE" "0402"
					( Origin gFrontEnd )
				)
				( attribute "PART_NUMBER" "G21796-074"
					( Origin gFrontEnd )
				)
				( attribute "PHYS_PAGE" "92"
					( Origin gFrontEnd )
				)
				( attribute "ROOM" "PROC_SIDEBAND"
					( Origin gFrontEnd )
				)
				( attribute "ROT" "0"
					( Origin gFrontEnd )
				)
				( attribute "SEC" "1"
					( Origin gFrontEnd )
				)
				( attribute "SEC_TYPE" "0402"
					( Origin gFrontEnd )
				)
				( attribute "TOLERANCE" "1%"
					( Origin gFrontEnd )
				)
				( attribute "VALUE" "33.2"
					( Origin gFrontEnd )
				)
				( attribute "VER" "1"
					( Origin gFrontEnd )
				)
				( attribute "WATTAGE" "1/16W"
					( Origin gFrontEnd )
				)
				( attribute "XY" "(-125,3750)"
					( Origin gFrontEnd )
				)
				( attribute "CHIPS_PART_NAME" "RES"
					( Origin gPackager )
				)
				( attribute "CDS_PART_NAME" "RES_0402-33.2,1%,1/16W,CHIP,G2A"
					( Origin gPackager )
				)
				( objectStatus "R3P46" )
				( pin "a"
					( attribute "PN" "1"
						( Origin gPackager )
					)
					( objectStatus "R3P46.1" )
				)
				( pin "b"
					( attribute "PN" "2"
						( Origin gPackager )
					)
					( objectStatus "R3P46.2" )
				)
			)
			( gate "@baseboard_fab2_lib.baseboard_fab2(sch_1):page92_i13"
				( attribute "BOM_COST" "PROC_SIDEBAND"
					( Origin gFrontEnd )
				)
				( attribute "CDS_LIB" "mstr_discrete"
					( Origin gPackager )
				)
				( attribute "CDS_LOCATION" "R3P43"
					( Origin gPackager )
				)
				( attribute "CDS_SEC" "1"
					( Origin gPackager )
				)
				( attribute "LOCATION" "R3P43"
					( Origin gFrontEnd )
				)
				( attribute "MATERIAL" "CHIP"
					( Origin gFrontEnd )
				)
				( attribute "PACK_TYPE" "0402"
					( Origin gFrontEnd )
				)
				( attribute "PART_NUMBER" "G21796-074"
					( Origin gFrontEnd )
				)
				( attribute "PHYS_PAGE" "92"
					( Origin gFrontEnd )
				)
				( attribute "ROOM" "PROC_SIDEBAND"
					( Origin gFrontEnd )
				)
				( attribute "ROT" "0"
					( Origin gFrontEnd )
				)
				( attribute "SEC" "1"
					( Origin gFrontEnd )
				)
				( attribute "SEC_TYPE" "0402"
					( Origin gFrontEnd )
				)
				( attribute "TOLERANCE" "1%"
					( Origin gFrontEnd )
				)
				( attribute "VALUE" "33.2"
					( Origin gFrontEnd )
				)
				( attribute "VER" "1"
					( Origin gFrontEnd )
				)
				( attribute "WATTAGE" "1/16W"
					( Origin gFrontEnd )
				)
				( attribute "XY" "(-125,4000)"
					( Origin gFrontEnd )
				)
				( attribute "CHIPS_PART_NAME" "RES"
					( Origin gPackager )
				)
				( attribute "CDS_PART_NAME" "RES_0402-33.2,1%,1/16W,CHIP,G2A"
					( Origin gPackager )
				)
				( objectStatus "R3P43" )
				( pin "a"
					( attribute "PN" "1"
						( Origin gPackager )
					)
					( objectStatus "R3P43.1" )
				)
				( pin "b"
					( attribute "PN" "2"
						( Origin gPackager )
					)
					( objectStatus "R3P43.2" )
				)
			)
			( gate "@baseboard_fab2_lib.baseboard_fab2(sch_1):page92_i14"
				( attribute "BOM_COST" "PROC_SIDEBAND"
					( Origin gFrontEnd )
				)
				( attribute "CDS_LIB" "mstr_discrete"
					( Origin gPackager )
				)
				( attribute "CDS_LOCATION" "R3P42"
					( Origin gPackager )
				)
				( attribute "CDS_SEC" "1"
					( Origin gPackager )
				)
				( attribute "LOCATION" "R3P42"
					( Origin gFrontEnd )
				)
				( attribute "MATERIAL" "CHIP"
					( Origin gFrontEnd )
				)
				( attribute "PACK_TYPE" "0402"
					( Origin gFrontEnd )
				)
				( attribute "PART_NUMBER" "G21796-074"
					( Origin gFrontEnd )
				)
				( attribute "PHYS_PAGE" "92"
					( Origin gFrontEnd )
				)
				( attribute "ROOM" "PROC_SIDEBAND"
					( Origin gFrontEnd )
				)
				( attribute "ROT" "0"
					( Origin gFrontEnd )
				)
				( attribute "SEC" "1"
					( Origin gFrontEnd )
				)
				( attribute "SEC_TYPE" "0402"
					( Origin gFrontEnd )
				)
				( attribute "TOLERANCE" "1%"
					( Origin gFrontEnd )
				)
				( attribute "VALUE" "33.2"
					( Origin gFrontEnd )
				)
				( attribute "VER" "1"
					( Origin gFrontEnd )
				)
				( attribute "WATTAGE" "1/16W"
					( Origin gFrontEnd )
				)
				( attribute "XY" "(-125,4250)"
					( Origin gFrontEnd )
				)
				( attribute "CHIPS_PART_NAME" "RES"
					( Origin gPackager )
				)
				( attribute "CDS_PART_NAME" "RES_0402-33.2,1%,1/16W,CHIP,G2A"
					( Origin gPackager )
				)
				( objectStatus "R3P42" )
				( pin "a"
					( attribute "PN" "1"
						( Origin gPackager )
					)
					( objectStatus "R3P42.1" )
				)
				( pin "b"
					( attribute "PN" "2"
						( Origin gPackager )
					)
					( objectStatus "R3P42.2" )
				)
			)
			( gate "@baseboard_fab2_lib.baseboard_fab2(sch_1):page92_i19"
				( attribute "BOM_COST" "PROC_SIDEBAND"
					( Origin gFrontEnd )
				)
				( attribute "CDS_LIB" "mstr_discrete"
					( Origin gPackager )
				)
				( attribute "CDS_LOCATION" "R7E2"
					( Origin gPackager )
				)
				( attribute "CDS_SEC" "1"
					( Origin gPackager )
				)
				( attribute "LOCATION" "R7E2"
					( Origin gFrontEnd )
				)
				( attribute "MATERIAL" "CHIP"
					( Origin gFrontEnd )
				)
				( attribute "PACK_TYPE" "0402"
					( Origin gFrontEnd )
				)
				( attribute "PART_NUMBER" "G21796-267"
					( Origin gFrontEnd )
				)
				( attribute "PHYS_PAGE" "92"
					( Origin gFrontEnd )
				)
				( attribute "ROOM" "PROC_SIDEBAND"
					( Origin gFrontEnd )
				)
				( attribute "ROT" "0"
					( Origin gFrontEnd )
				)
				( attribute "SEC" "1"
					( Origin gFrontEnd )
				)
				( attribute "SEC_TYPE" "0402"
					( Origin gFrontEnd )
				)
				( attribute "TOLERANCE" "1.0%"
					( Origin gFrontEnd )
				)
				( attribute "VALUE" "75"
					( Origin gFrontEnd )
				)
				( attribute "VER" "2"
					( Origin gFrontEnd )
				)
				( attribute "WATTAGE" "1/16W"
					( Origin gFrontEnd )
				)
				( attribute "XY" "(-2850,2325)"
					( Origin gFrontEnd )
				)
				( attribute "CHIPS_PART_NAME" "RES"
					( Origin gPackager )
				)
				( attribute "CDS_PART_NAME" "RES_0402-75,1.0%,1/16W,CHIP,G2A"
					( Origin gPackager )
				)
				( objectStatus "R7E2" )
				( pin "a"
					( attribute "PN" "1"
						( Origin gPackager )
					)
					( objectStatus "R7E2.1" )
				)
				( pin "b"
					( attribute "PN" "2"
						( Origin gPackager )
					)
					( objectStatus "R7E2.2" )
				)
			)
			( gate "@baseboard_fab2_lib.baseboard_fab2(sch_1):page92_i24"
				( attribute "BOM_COST" "PROC_SIDEBAND"
					( Origin gFrontEnd )
				)
				( attribute "CDS_LIB" "mstr_discrete"
					( Origin gPackager )
				)
				( attribute "CDS_LOCATION" "R7D34"
					( Origin gPackager )
				)
				( attribute "CDS_SEC" "1"
					( Origin gPackager )
				)
				( attribute "LOCATION" "R7D34"
					( Origin gFrontEnd )
				)
				( attribute "MATERIAL" "CHIP"
					( Origin gFrontEnd )
				)
				( attribute "PACK_TYPE" "0402"
					( Origin gFrontEnd )
				)
				( attribute "PART_NUMBER" "G21796-074"
					( Origin gFrontEnd )
				)
				( attribute "PHYS_PAGE" "92"
					( Origin gFrontEnd )
				)
				( attribute "ROOM" "PROC_SIDEBAND"
					( Origin gFrontEnd )
				)
				( attribute "ROT" "0"
					( Origin gFrontEnd )
				)
				( attribute "SEC" "1"
					( Origin gFrontEnd )
				)
				( attribute "SEC_TYPE" "0402"
					( Origin gFrontEnd )
				)
				( attribute "TOLERANCE" "1%"
					( Origin gFrontEnd )
				)
				( attribute "VALUE" "33.2"
					( Origin gFrontEnd )
				)
				( attribute "VER" "1"
					( Origin gFrontEnd )
				)
				( attribute "WATTAGE" "1/16W"
					( Origin gFrontEnd )
				)
				( attribute "XY" "(-125,2050)"
					( Origin gFrontEnd )
				)
				( attribute "CHIPS_PART_NAME" "RES"
					( Origin gPackager )
				)
				( attribute "CDS_PART_NAME" "RES_0402-33.2,1%,1/16W,CHIP,G2A"
					( Origin gPackager )
				)
				( objectStatus "R7D34" )
				( pin "a"
					( attribute "PN" "1"
						( Origin gPackager )
					)
					( objectStatus "R7D34.1" )
				)
				( pin "b"
					( attribute "PN" "2"
						( Origin gPackager )
					)
					( objectStatus "R7D34.2" )
				)
			)
			( gate "@baseboard_fab2_lib.baseboard_fab2(sch_1):page92_i29"
				( attribute "BOM_COST" "PROC_SIDEBAND"
					( Origin gFrontEnd )
				)
				( attribute "CDS_LIB" "mstr_discrete"
					( Origin gPackager )
				)
				( attribute "CDS_LOCATION" "R7D31"
					( Origin gPackager )
				)
				( attribute "CDS_SEC" "1"
					( Origin gPackager )
				)
				( attribute "LOCATION" "R7D31"
					( Origin gFrontEnd )
				)
				( attribute "MATERIAL" "CHIP"
					( Origin gFrontEnd )
				)
				( attribute "PACK_TYPE" "0402"
					( Origin gFrontEnd )
				)
				( attribute "PART_NUMBER" "G21796-074"
					( Origin gFrontEnd )
				)
				( attribute "PHYS_PAGE" "92"
					( Origin gFrontEnd )
				)
				( attribute "ROOM" "PROC_SIDEBAND"
					( Origin gFrontEnd )
				)
				( attribute "ROT" "0"
					( Origin gFrontEnd )
				)
				( attribute "SEC" "1"
					( Origin gFrontEnd )
				)
				( attribute "SEC_TYPE" "0402"
					( Origin gFrontEnd )
				)
				( attribute "TOLERANCE" "1%"
					( Origin gFrontEnd )
				)
				( attribute "VALUE" "33.2"
					( Origin gFrontEnd )
				)
				( attribute "VER" "1"
					( Origin gFrontEnd )
				)
				( attribute "WATTAGE" "1/16W"
					( Origin gFrontEnd )
				)
				( attribute "XY" "(-100,1800)"
					( Origin gFrontEnd )
				)
				( attribute "CHIPS_PART_NAME" "RES"
					( Origin gPackager )
				)
				( attribute "CDS_PART_NAME" "RES_0402-33.2,1%,1/16W,CHIP,G2A"
					( Origin gPackager )
				)
				( objectStatus "R7D31" )
				( pin "a"
					( attribute "PN" "1"
						( Origin gPackager )
					)
					( objectStatus "R7D31.1" )
				)
				( pin "b"
					( attribute "PN" "2"
						( Origin gPackager )
					)
					( objectStatus "R7D31.2" )
				)
			)
			( gate "@baseboard_fab2_lib.baseboard_fab2(sch_1):page92_i30"
				( attribute "BOM_COST" "PROC_SIDEBAND"
					( Origin gFrontEnd )
				)
				( attribute "CDS_LIB" "mstr_discrete"
					( Origin gPackager )
				)
				( attribute "CDS_LOCATION" "R7D29"
					( Origin gPackager )
				)
				( attribute "CDS_SEC" "1"
					( Origin gPackager )
				)
				( attribute "LOCATION" "R7D29"
					( Origin gFrontEnd )
				)
				( attribute "MATERIAL" "CHIP"
					( Origin gFrontEnd )
				)
				( attribute "PACK_TYPE" "0402"
					( Origin gFrontEnd )
				)
				( attribute "PART_NUMBER" "G21796-074"
					( Origin gFrontEnd )
				)
				( attribute "PHYS_PAGE" "92"
					( Origin gFrontEnd )
				)
				( attribute "ROOM" "PROC_SIDEBAND"
					( Origin gFrontEnd )
				)
				( attribute "ROT" "0"
					( Origin gFrontEnd )
				)
				( attribute "SEC" "1"
					( Origin gFrontEnd )
				)
				( attribute "SEC_TYPE" "0402"
					( Origin gFrontEnd )
				)
				( attribute "TOLERANCE" "1%"
					( Origin gFrontEnd )
				)
				( attribute "VALUE" "33.2"
					( Origin gFrontEnd )
				)
				( attribute "VER" "1"
					( Origin gFrontEnd )
				)
				( attribute "WATTAGE" "1/16W"
					( Origin gFrontEnd )
				)
				( attribute "XY" "(-100,1550)"
					( Origin gFrontEnd )
				)
				( attribute "CHIPS_PART_NAME" "RES"
					( Origin gPackager )
				)
				( attribute "CDS_PART_NAME" "RES_0402-33.2,1%,1/16W,CHIP,G2A"
					( Origin gPackager )
				)
				( objectStatus "R7D29" )
				( pin "a"
					( attribute "PN" "1"
						( Origin gPackager )
					)
					( objectStatus "R7D29.1" )
				)
				( pin "b"
					( attribute "PN" "2"
						( Origin gPackager )
					)
					( objectStatus "R7D29.2" )
				)
			)
			( gate "@baseboard_fab2_lib.baseboard_fab2(sch_1):page92_i32"
				( attribute "BOM_COST" "PROC_SIDEBAND"
					( Origin gFrontEnd )
				)
				( attribute "CDS_LIB" "mstr_digital"
					( Origin gPackager )
				)
				( attribute "CDS_LOCATION" "U7D2"
					( Origin gPackager )
				)
				( attribute "CDS_SEC" "1"
					( Origin gPackager )
				)
				( attribute "LOCATION" "U7D2"
					( Origin gFrontEnd )
				)
				( attribute "MATERIAL" "IC"
					( Origin gFrontEnd )
				)
				( attribute "PACK_TYPE" "SM"
					( Origin gFrontEnd )
				)
				( attribute "PART_NUMBER" "D66151-001"
					( Origin gFrontEnd )
				)
				( attribute "PHYS_PAGE" "92"
					( Origin gFrontEnd )
				)
				( attribute "ROOM" "PROC_SIDEBAND"
					( Origin gFrontEnd )
				)
				( attribute "ROT" "2"
					( Origin gFrontEnd )
				)
				( attribute "SEC" "1"
					( Origin gFrontEnd )
				)
				( attribute "SEC_TYPE" "SM"
					( Origin gFrontEnd )
				)
				( attribute "VER" "1"
					( Origin gFrontEnd )
				)
				( attribute "XY" "(-1750,2050)"
					( Origin gFrontEnd )
				)
				( attribute "CHIPS_PART_NAME" "GTL2014"
					( Origin gPackager )
				)
				( attribute "CDS_PART_NAME" "GTL2014_SM-IC,D66151-001"
					( Origin gPackager )
				)
				( objectStatus "U7D2" )
				( pin "a0"
					( attribute "PN" "13"
						( Origin gPackager )
					)
					( objectStatus "U7D2.13" )
				)
				( pin "a1"
					( attribute "PN" "12"
						( Origin gPackager )
					)
					( objectStatus "U7D2.12" )
				)
				( pin "a2"
					( attribute "PN" "10"
						( Origin gPackager )
					)
					( objectStatus "U7D2.10" )
				)
				( pin "a3"
					( attribute "PN" "9"
						( Origin gPackager )
					)
					( objectStatus "U7D2.9" )
				)
				( pin "b0"
					( attribute "PN" "2"
						( Origin gPackager )
					)
					( objectStatus "U7D2.2" )
				)
				( pin "b1"
					( attribute "PN" "3"
						( Origin gPackager )
					)
					( objectStatus "U7D2.3" )
				)
				( pin "b2"
					( attribute "PN" "5"
						( Origin gPackager )
					)
					( objectStatus "U7D2.5" )
				)
				( pin "b3"
					( attribute "PN" "6"
						( Origin gPackager )
					)
					( objectStatus "U7D2.6" )
				)
				( pin "dir"
					( attribute "PN" "1"
						( Origin gPackager )
					)
					( objectStatus "U7D2.1" )
				)
				( pin "gnd(0)"
					( attribute "PN" "7"
						( Origin gPackager )
					)
					( objectStatus "U7D2.7" )
				)
				( pin "gnd(1)"
					( attribute "PN" "8"
						( Origin gPackager )
					)
					( objectStatus "U7D2.8" )
				)
				( pin "gnd(2)"
					( attribute "PN" "11"
						( Origin gPackager )
					)
					( objectStatus "U7D2.11" )
				)
				( pin "vcc"
					( attribute "PN" "14"
						( Origin gPackager )
					)
					( objectStatus "U7D2.14" )
				)
				( pin "vref"
					( attribute "PN" "4"
						( Origin gPackager )
					)
					( objectStatus "U7D2.4" )
				)
			)
			( gate "@baseboard_fab2_lib.baseboard_fab2(sch_1):page92_i37"
				( attribute "BOM_COST" "PROC_SIDEBAND"
					( Origin gFrontEnd )
				)
				( attribute "CDS_LIB" "dev_discrete"
					( Origin gPackager )
				)
				( attribute "CDS_LOCATION" "C3P49"
					( Origin gPackager )
				)
				( attribute "CDS_SEC" "1"
					( Origin gPackager )
				)
				( attribute "LOCATION" "C3P49"
					( Origin gFrontEnd )
				)
				( attribute "MATERIAL" "X7R"
					( Origin gFrontEnd )
				)
				( attribute "PACK_TYPE" "0402V"
					( Origin gFrontEnd )
				)
				( attribute "PART_NUMBER" "A36096-030"
					( Origin gFrontEnd )
				)
				( attribute "PHYS_PAGE" "92"
					( Origin gFrontEnd )
				)
				( attribute "ROOM" "PROC_SIDEBAND"
					( Origin gFrontEnd )
				)
				( attribute "ROT" "0"
					( Origin gFrontEnd )
				)
				( attribute "SEC" "1"
					( Origin gFrontEnd )
				)
				( attribute "SEC_TYPE" "0402V"
					( Origin gFrontEnd )
				)
				( attribute "TOLERANCE" "10%"
					( Origin gFrontEnd )
				)
				( attribute "VALUE" "0.1UF"
					( Origin gFrontEnd )
				)
				( attribute "VER" "1"
					( Origin gFrontEnd )
				)
				( attribute "VOLTAGE" "16V"
					( Units "uVoltage" "V" 1.000000)
					( Origin gFrontEnd )
				)
				( attribute "XY" "(-300,4825)"
					( Origin gFrontEnd )
				)
				( attribute "CHIPS_PART_NAME" "CAP_A"
					( Origin gPackager )
				)
				( attribute "CDS_PART_NAME" "CAP_A_0402V-0.1UF,16V,10%,X7R,A"
					( Origin gPackager )
				)
				( objectStatus "C3P49" )
				( pin "a"
					( attribute "PN" "1"
						( Origin gPackager )
					)
					( objectStatus "C3P49.1" )
				)
				( pin "b"
					( attribute "PN" "2"
						( Origin gPackager )
					)
					( objectStatus "C3P49.2" )
				)
			)
			( gate "@baseboard_fab2_lib.baseboard_fab2(sch_1):page92_i38"
				( attribute "BOM_COST" "PROC_SIDEBAND"
					( Origin gFrontEnd )
				)
				( attribute "CDS_LIB" "mstr_discrete"
					( Origin gPackager )
				)
				( attribute "CDS_LOCATION" "R3P49"
					( Origin gPackager )
				)
				( attribute "CDS_SEC" "1"
					( Origin gPackager )
				)
				( attribute "LOCATION" "R3P49"
					( Origin gFrontEnd )
				)
				( attribute "MATERIAL" "CHIP"
					( Origin gFrontEnd )
				)
				( attribute "PACK_TYPE" "0402"
					( Origin gFrontEnd )
				)
				( attribute "PART_NUMBER" "G21796-017"
					( Origin gFrontEnd )
				)
				( attribute "PHYS_PAGE" "92"
					( Origin gFrontEnd )
				)
				( attribute "ROOM" "PROC_SIDEBAND"
					( Origin gFrontEnd )
				)
				( attribute "ROT" "0"
					( Origin gFrontEnd )
				)
				( attribute "SEC" "1"
					( Origin gFrontEnd )
				)
				( attribute "SEC_TYPE" "0402"
					( Origin gFrontEnd )
				)
				( attribute "TOLERANCE" "1%"
					( Origin gFrontEnd )
				)
				( attribute "VALUE" "100.0"
					( Origin gFrontEnd )
				)
				( attribute "VER" "2"
					( Origin gFrontEnd )
				)
				( attribute "WATTAGE" "1/16W"
					( Origin gFrontEnd )
				)
				( attribute "XY" "(125,4800)"
					( Origin gFrontEnd )
				)
				( attribute "CHIPS_PART_NAME" "RES"
					( Origin gPackager )
				)
				( attribute "CDS_PART_NAME" "RES_0402-100.0,1%,1/16W,CHIP,GA"
					( Origin gPackager )
				)
				( objectStatus "R3P49" )
				( pin "a"
					( attribute "PN" "1"
						( Origin gPackager )
					)
					( objectStatus "R3P49.1" )
				)
				( pin "b"
					( attribute "PN" "2"
						( Origin gPackager )
					)
					( objectStatus "R3P49.2" )
				)
			)
			( gate "@baseboard_fab2_lib.baseboard_fab2(sch_1):page92_i39"
				( attribute "BOM_COST" "PROC_SIDEBAND"
					( Origin gFrontEnd )
				)
				( attribute "CDS_LIB" "mstr_discrete"
					( Origin gPackager )
				)
				( attribute "CDS_LOCATION" "R3P45"
					( Origin gPackager )
				)
				( attribute "CDS_SEC" "1"
					( Origin gPackager )
				)
				( attribute "LOCATION" "R3P45"
					( Origin gFrontEnd )
				)
				( attribute "MATERIAL" "CHIP"
					( Origin gFrontEnd )
				)
				( attribute "PACK_TYPE" "0402"
					( Origin gFrontEnd )
				)
				( attribute "PART_NUMBER" "G21796-047"
					( Origin gFrontEnd )
				)
				( attribute "PHYS_PAGE" "92"
					( Origin gFrontEnd )
				)
				( attribute "ROOM" "PROC_SIDEBAND"
					( Origin gFrontEnd )
				)
				( attribute "ROT" "0"
					( Origin gFrontEnd )
				)
				( attribute "SEC" "1"
					( Origin gFrontEnd )
				)
				( attribute "SEC_TYPE" "0402"
					( Origin gFrontEnd )
				)
				( attribute "TOLERANCE" "1%"
					( Origin gFrontEnd )
				)
				( attribute "VALUE" "49.9"
					( Origin gFrontEnd )
				)
				( attribute "VER" "2"
					( Origin gFrontEnd )
				)
				( attribute "WATTAGE" "1/16W"
					( Origin gFrontEnd )
				)
				( attribute "XY" "(125,5200)"
					( Origin gFrontEnd )
				)
				( attribute "CHIPS_PART_NAME" "RES"
					( Origin gPackager )
				)
				( attribute "CDS_PART_NAME" "RES_0402-49.9,1%,1/16W,CHIP,G2A"
					( Origin gPackager )
				)
				( objectStatus "R3P45" )
				( pin "a"
					( attribute "PN" "1"
						( Origin gPackager )
					)
					( objectStatus "R3P45.1" )
				)
				( pin "b"
					( attribute "PN" "2"
						( Origin gPackager )
					)
					( objectStatus "R3P45.2" )
				)
			)
			( gate "@baseboard_fab2_lib.baseboard_fab2(sch_1):page92_i46"
				( attribute "BOM_COST" "PROC_SIDEBAND"
					( Origin gFrontEnd )
				)
				( attribute "CDS_LIB" "mstr_discrete"
					( Origin gPackager )
				)
				( attribute "CDS_LOCATION" "R3R1"
					( Origin gPackager )
				)
				( attribute "CDS_SEC" "1"
					( Origin gPackager )
				)
				( attribute "LOCATION" "R3R1"
					( Origin gFrontEnd )
				)
				( attribute "MATERIAL" "CHIP"
					( Origin gFrontEnd )
				)
				( attribute "PACK_TYPE" "0402"
					( Origin gFrontEnd )
				)
				( attribute "PART_NUMBER" "G21796-026"
					( Origin gFrontEnd )
				)
				( attribute "PHYS_PAGE" "92"
					( Origin gFrontEnd )
				)
				( attribute "ROOM" "PROC_SIDEBAND"
					( Origin gFrontEnd )
				)
				( attribute "ROT" "0"
					( Origin gFrontEnd )
				)
				( attribute "SEC" "1"
					( Origin gFrontEnd )
				)
				( attribute "SEC_TYPE" "0402"
					( Origin gFrontEnd )
				)
				( attribute "TOLERANCE" "1%"
					( Origin gFrontEnd )
				)
				( attribute "VALUE" "1.00K"
					( Origin gFrontEnd )
				)
				( attribute "VER" "1"
					( Origin gFrontEnd )
				)
				( attribute "WATTAGE" "1/16W"
					( Origin gFrontEnd )
				)
				( attribute "XY" "(-675,4400)"
					( Origin gFrontEnd )
				)
				( attribute "CHIPS_PART_NAME" "RES"
					( Origin gPackager )
				)
				( attribute "CDS_PART_NAME" "RES_0402-1.00K,1%,1/16W,CHIP,GA"
					( Origin gPackager )
				)
				( objectStatus "R3R1" )
				( pin "a"
					( attribute "PN" "1"
						( Origin gPackager )
					)
					( objectStatus "R3R1.1" )
				)
				( pin "b"
					( attribute "PN" "2"
						( Origin gPackager )
					)
					( objectStatus "R3R1.2" )
				)
			)
			( gate "@baseboard_fab2_lib.baseboard_fab2(sch_1):page92_i48"
				( attribute "BOM_COST" "PROC_SIDEBAND"
					( Origin gFrontEnd )
				)
				( attribute "CDS_LIB" "mstr_discrete"
					( Origin gPackager )
				)
				( attribute "CDS_LOCATION" "R7D32"
					( Origin gPackager )
				)
				( attribute "CDS_SEC" "1"
					( Origin gPackager )
				)
				( attribute "LOCATION" "R7D32"
					( Origin gFrontEnd )
				)
				( attribute "MATERIAL" "CHIP"
					( Origin gFrontEnd )
				)
				( attribute "PACK_TYPE" "0402"
					( Origin gFrontEnd )
				)
				( attribute "PART_NUMBER" "G21796-017"
					( Origin gFrontEnd )
				)
				( attribute "PHYS_PAGE" "92"
					( Origin gFrontEnd )
				)
				( attribute "ROOM" "PROC_SIDEBAND"
					( Origin gFrontEnd )
				)
				( attribute "ROT" "0"
					( Origin gFrontEnd )
				)
				( attribute "SEC" "1"
					( Origin gFrontEnd )
				)
				( attribute "SEC_TYPE" "0402"
					( Origin gFrontEnd )
				)
				( attribute "TOLERANCE" "1%"
					( Origin gFrontEnd )
				)
				( attribute "VALUE" "100.0"
					( Origin gFrontEnd )
				)
				( attribute "VER" "2"
					( Origin gFrontEnd )
				)
				( attribute "WATTAGE" "1/16W"
					( Origin gFrontEnd )
				)
				( attribute "XY" "(350,2525)"
					( Origin gFrontEnd )
				)
				( attribute "CHIPS_PART_NAME" "RES"
					( Origin gPackager )
				)
				( attribute "CDS_PART_NAME" "RES_0402-100.0,1%,1/16W,CHIP,GA"
					( Origin gPackager )
				)
				( objectStatus "R7D32" )
				( pin "a"
					( attribute "PN" "1"
						( Origin gPackager )
					)
					( objectStatus "R7D32.1" )
				)
				( pin "b"
					( attribute "PN" "2"
						( Origin gPackager )
					)
					( objectStatus "R7D32.2" )
				)
			)
			( gate "@baseboard_fab2_lib.baseboard_fab2(sch_1):page92_i51"
				( attribute "BOM_COST" "PROC_SIDEBAND"
					( Origin gFrontEnd )
				)
				( attribute "CDS_LIB" "mstr_discrete"
					( Origin gPackager )
				)
				( attribute "CDS_LOCATION" "R7D33"
					( Origin gPackager )
				)
				( attribute "CDS_SEC" "1"
					( Origin gPackager )
				)
				( attribute "LOCATION" "R7D33"
					( Origin gFrontEnd )
				)
				( attribute "MATERIAL" "CHIP"
					( Origin gFrontEnd )
				)
				( attribute "PACK_TYPE" "0402"
					( Origin gFrontEnd )
				)
				( attribute "PART_NUMBER" "G21796-047"
					( Origin gFrontEnd )
				)
				( attribute "PHYS_PAGE" "92"
					( Origin gFrontEnd )
				)
				( attribute "ROOM" "PROC_SIDEBAND"
					( Origin gFrontEnd )
				)
				( attribute "ROT" "0"
					( Origin gFrontEnd )
				)
				( attribute "SEC" "1"
					( Origin gFrontEnd )
				)
				( attribute "SEC_TYPE" "0402"
					( Origin gFrontEnd )
				)
				( attribute "TOLERANCE" "1%"
					( Origin gFrontEnd )
				)
				( attribute "VALUE" "49.9"
					( Origin gFrontEnd )
				)
				( attribute "VER" "2"
					( Origin gFrontEnd )
				)
				( attribute "WATTAGE" "1/16W"
					( Origin gFrontEnd )
				)
				( attribute "XY" "(350,3050)"
					( Origin gFrontEnd )
				)
				( attribute "CHIPS_PART_NAME" "RES"
					( Origin gPackager )
				)
				( attribute "CDS_PART_NAME" "RES_0402-49.9,1%,1/16W,CHIP,G2A"
					( Origin gPackager )
				)
				( objectStatus "R7D33" )
				( pin "a"
					( attribute "PN" "1"
						( Origin gPackager )
					)
					( objectStatus "R7D33.1" )
				)
				( pin "b"
					( attribute "PN" "2"
						( Origin gPackager )
					)
					( objectStatus "R7D33.2" )
				)
			)
			( gate "@baseboard_fab2_lib.baseboard_fab2(sch_1):page92_i52"
				( attribute "BOM_COST" "PROC_SIDEBAND"
					( Origin gFrontEnd )
				)
				( attribute "CDS_LIB" "dev_discrete"
					( Origin gPackager )
				)
				( attribute "CDS_LOCATION" "C7D5"
					( Origin gPackager )
				)
				( attribute "CDS_SEC" "1"
					( Origin gPackager )
				)
				( attribute "LOCATION" "C7D5"
					( Origin gFrontEnd )
				)
				( attribute "MATERIAL" "X7R"
					( Origin gFrontEnd )
				)
				( attribute "PACK_TYPE" "0402V"
					( Origin gFrontEnd )
				)
				( attribute "PART_NUMBER" "A36096-030"
					( Origin gFrontEnd )
				)
				( attribute "PHYS_PAGE" "92"
					( Origin gFrontEnd )
				)
				( attribute "ROOM" "PROC_SIDEBAND"
					( Origin gFrontEnd )
				)
				( attribute "ROT" "0"
					( Origin gFrontEnd )
				)
				( attribute "SEC" "1"
					( Origin gFrontEnd )
				)
				( attribute "SEC_TYPE" "0402V"
					( Origin gFrontEnd )
				)
				( attribute "TOLERANCE" "10%"
					( Origin gFrontEnd )
				)
				( attribute "VALUE" "0.1UF"
					( Origin gFrontEnd )
				)
				( attribute "VER" "1"
					( Origin gFrontEnd )
				)
				( attribute "VOLTAGE" "16V"
					( Units "uVoltage" "V" 1.000000)
					( Origin gFrontEnd )
				)
				( attribute "XY" "(-75,2550)"
					( Origin gFrontEnd )
				)
				( attribute "CHIPS_PART_NAME" "CAP_A"
					( Origin gPackager )
				)
				( attribute "CDS_PART_NAME" "CAP_A_0402V-0.1UF,16V,10%,X7R,A"
					( Origin gPackager )
				)
				( objectStatus "C7D5" )
				( pin "a"
					( attribute "PN" "1"
						( Origin gPackager )
					)
					( objectStatus "C7D5.1" )
				)
				( pin "b"
					( attribute "PN" "2"
						( Origin gPackager )
					)
					( objectStatus "C7D5.2" )
				)
			)
			( gate "@baseboard_fab2_lib.baseboard_fab2(sch_1):page92_i54"
				( attribute "BOM_COST" "PROC_SIDEBAND"
					( Origin gFrontEnd )
				)
				( attribute "CDS_LIB" "mstr_discrete"
					( Origin gPackager )
				)
				( attribute "CDS_LOCATION" "R7D26"
					( Origin gPackager )
				)
				( attribute "CDS_SEC" "1"
					( Origin gPackager )
				)
				( attribute "LOCATION" "R7D26"
					( Origin gFrontEnd )
				)
				( attribute "MATERIAL" "CHIP"
					( Origin gFrontEnd )
				)
				( attribute "PACK_TYPE" "0402"
					( Origin gFrontEnd )
				)
				( attribute "PART_NUMBER" "G21796-026"
					( Origin gFrontEnd )
				)
				( attribute "PHYS_PAGE" "92"
					( Origin gFrontEnd )
				)
				( attribute "ROOM" "PROC_SIDEBAND"
					( Origin gFrontEnd )
				)
				( attribute "ROT" "0"
					( Origin gFrontEnd )
				)
				( attribute "SEC" "1"
					( Origin gFrontEnd )
				)
				( attribute "SEC_TYPE" "0402"
					( Origin gFrontEnd )
				)
				( attribute "TOLERANCE" "1%"
					( Origin gFrontEnd )
				)
				( attribute "VALUE" "1.00K"
					( Origin gFrontEnd )
				)
				( attribute "VER" "1"
					( Origin gFrontEnd )
				)
				( attribute "WATTAGE" "1/16W"
					( Origin gFrontEnd )
				)
				( attribute "XY" "(-600,2200)"
					( Origin gFrontEnd )
				)
				( attribute "CHIPS_PART_NAME" "RES"
					( Origin gPackager )
				)
				( attribute "CDS_PART_NAME" "RES_0402-1.00K,1%,1/16W,CHIP,GA"
					( Origin gPackager )
				)
				( objectStatus "R7D26" )
				( pin "a"
					( attribute "PN" "1"
						( Origin gPackager )
					)
					( objectStatus "R7D26.1" )
				)
				( pin "b"
					( attribute "PN" "2"
						( Origin gPackager )
					)
					( objectStatus "R7D26.2" )
				)
			)
			( gate "@baseboard_fab2_lib.baseboard_fab2(sch_1):page92_i61"
				( attribute "BOM_COST" "PROC_SIDEBAND"
					( Origin gFrontEnd )
				)
				( attribute "CDS_LIB" "mstr_discrete"
					( Origin gPackager )
				)
				( attribute "CDS_LOCATION" "R3R3"
					( Origin gPackager )
				)
				( attribute "CDS_SEC" "1"
					( Origin gPackager )
				)
				( attribute "LOCATION" "R3R3"
					( Origin gFrontEnd )
				)
				( attribute "MATERIAL" "CHIP"
					( Origin gFrontEnd )
				)
				( attribute "PACK_TYPE" "0402"
					( Origin gFrontEnd )
				)
				( attribute "PART_NUMBER" "G21796-074"
					( Origin gFrontEnd )
				)
				( attribute "PHYS_PAGE" "92"
					( Origin gFrontEnd )
				)
				( attribute "ROOM" "PROC_SIDEBAND"
					( Origin gFrontEnd )
				)
				( attribute "ROT" "0"
					( Origin gFrontEnd )
				)
				( attribute "SEC" "1"
					( Origin gFrontEnd )
				)
				( attribute "SEC_TYPE" "0402"
					( Origin gFrontEnd )
				)
				( attribute "TOLERANCE" "1%"
					( Origin gFrontEnd )
				)
				( attribute "VALUE" "33.2"
					( Origin gFrontEnd )
				)
				( attribute "VER" "1"
					( Origin gFrontEnd )
				)
				( attribute "WATTAGE" "1/16W"
					( Origin gFrontEnd )
				)
				( attribute "XY" "(-125,3550)"
					( Origin gFrontEnd )
				)
				( attribute "CHIPS_PART_NAME" "RES"
					( Origin gPackager )
				)
				( attribute "CDS_PART_NAME" "RES_0402-33.2,1%,1/16W,CHIP,G2A"
					( Origin gPackager )
				)
				( objectStatus "R3R3" )
				( pin "a"
					( attribute "PN" "1"
						( Origin gPackager )
					)
					( objectStatus "R3R3.1" )
				)
				( pin "b"
					( attribute "PN" "2"
						( Origin gPackager )
					)
					( objectStatus "R3R3.2" )
				)
			)
			( gate "@baseboard_fab2_lib.baseboard_fab2(sch_1):page92_i64"
				( attribute "BOM_COST" "PROC_SIDEBAND"
					( Origin gFrontEnd )
				)
				( attribute "CDS_LIB" "mstr_discrete"
					( Origin gPackager )
				)
				( attribute "CDS_LOCATION" "R6D9"
					( Origin gPackager )
				)
				( attribute "CDS_SEC" "1"
					( Origin gPackager )
				)
				( attribute "LOCATION" "R6D9"
					( Origin gFrontEnd )
				)
				( attribute "MATERIAL" "CHIP"
					( Origin gFrontEnd )
				)
				( attribute "PACK_TYPE" "0402"
					( Origin gFrontEnd )
				)
				( attribute "PART_NUMBER" "G21796-009"
					( Origin gFrontEnd )
				)
				( attribute "PHYS_PAGE" "92"
					( Origin gFrontEnd )
				)
				( attribute "ROOM" "PROC_SIDEBAND"
					( Origin gFrontEnd )
				)
				( attribute "ROT" "2"
					( Origin gFrontEnd )
				)
				( attribute "SEC" "1"
					( Origin gFrontEnd )
				)
				( attribute "SEC_TYPE" "0402"
					( Origin gFrontEnd )
				)
				( attribute "TOLERANCE" "1%"
					( Origin gFrontEnd )
				)
				( attribute "VALUE" "150.0"
					( Origin gFrontEnd )
				)
				( attribute "VER" "2"
					( Origin gFrontEnd )
				)
				( attribute "WATTAGE" "1/16W"
					( Origin gFrontEnd )
				)
				( attribute "XY" "(-4600,1825)"
					( Origin gFrontEnd )
				)
				( attribute "CHIPS_PART_NAME" "RES"
					( Origin gPackager )
				)
				( attribute "CDS_PART_NAME" "RES_0402-150.0,1%,1/16W,CHIP,GA"
					( Origin gPackager )
				)
				( objectStatus "R6D9" )
				( pin "a"
					( attribute "PN" "1"
						( Origin gPackager )
					)
					( objectStatus "R6D9.1" )
				)
				( pin "b"
					( attribute "PN" "2"
						( Origin gPackager )
					)
					( objectStatus "R6D9.2" )
				)
			)
			( gate "@baseboard_fab2_lib.baseboard_fab2(sch_1):page92_i65"
				( attribute "BOM_COST" "PROC_SIDEBAND"
					( Origin gFrontEnd )
				)
				( attribute "CDS_LIB" "mstr_discrete"
					( Origin gPackager )
				)
				( attribute "CDS_LOCATION" "R7P27"
					( Origin gPackager )
				)
				( attribute "CDS_SEC" "1"
					( Origin gPackager )
				)
				( attribute "LOCATION" "R7P27"
					( Origin gFrontEnd )
				)
				( attribute "MATERIAL" "CHIP"
					( Origin gFrontEnd )
				)
				( attribute "PACK_TYPE" "0402"
					( Origin gFrontEnd )
				)
				( attribute "PART_NUMBER" "G21796-009"
					( Origin gFrontEnd )
				)
				( attribute "PHYS_PAGE" "92"
					( Origin gFrontEnd )
				)
				( attribute "ROOM" "PROC_SIDEBAND"
					( Origin gFrontEnd )
				)
				( attribute "ROT" "0"
					( Origin gFrontEnd )
				)
				( attribute "SEC" "1"
					( Origin gFrontEnd )
				)
				( attribute "SEC_TYPE" "0402"
					( Origin gFrontEnd )
				)
				( attribute "TOLERANCE" "1%"
					( Origin gFrontEnd )
				)
				( attribute "VALUE" "150.0"
					( Origin gFrontEnd )
				)
				( attribute "VER" "2"
					( Origin gFrontEnd )
				)
				( attribute "WATTAGE" "1/16W"
					( Origin gFrontEnd )
				)
				( attribute "XY" "(-4275,1800)"
					( Origin gFrontEnd )
				)
				( attribute "CHIPS_PART_NAME" "RES"
					( Origin gPackager )
				)
				( attribute "CDS_PART_NAME" "RES_0402-150.0,1%,1/16W,CHIP,GA"
					( Origin gPackager )
				)
				( objectStatus "R7P27" )
				( pin "a"
					( attribute "PN" "1"
						( Origin gPackager )
					)
					( objectStatus "R7P27.1" )
				)
				( pin "b"
					( attribute "PN" "2"
						( Origin gPackager )
					)
					( objectStatus "R7P27.2" )
				)
			)
			( gate "@baseboard_fab2_lib.baseboard_fab2(sch_1):page92_i67"
				( attribute "BOM_COST" "PROC_SIDEBAND"
					( Origin gFrontEnd )
				)
				( attribute "CDS_LIB" "mstr_discrete"
					( Origin gPackager )
				)
				( attribute "CDS_LOCATION" "R7D28"
					( Origin gPackager )
				)
				( attribute "CDS_SEC" "1"
					( Origin gPackager )
				)
				( attribute "LOCATION" "R7D28"
					( Origin gFrontEnd )
				)
				( attribute "MATERIAL" "CHIP"
					( Origin gFrontEnd )
				)
				( attribute "PACK_TYPE" "0402"
					( Origin gFrontEnd )
				)
				( attribute "PART_NUMBER" "G21497-005"
					( Origin gFrontEnd )
				)
				( attribute "PHYS_PAGE" "92"
					( Origin gFrontEnd )
				)
				( attribute "ROOM" "PROC_SIDEBAND"
					( Origin gFrontEnd )
				)
				( attribute "ROT" "0"
					( Origin gFrontEnd )
				)
				( attribute "SEC" "1"
					( Origin gFrontEnd )
				)
				( attribute "SEC_TYPE" "0402"
					( Origin gFrontEnd )
				)
				( attribute "TOLERANCE" "5%"
					( Origin gFrontEnd )
				)
				( attribute "VALUE" "0.0"
					( Origin gFrontEnd )
				)
				( attribute "VER" "1"
					( Origin gFrontEnd )
				)
				( attribute "WATTAGE" "1/16W"
					( Origin gFrontEnd )
				)
				( attribute "XY" "(-3725,1275)"
					( Origin gFrontEnd )
				)
				( attribute "CHIPS_PART_NAME" "RES"
					( Origin gPackager )
				)
				( attribute "CDS_PART_NAME" "RES_0402-0.0,5%,1/16W,CHIP,G21A"
					( Origin gPackager )
				)
				( objectStatus "R7D28" )
				( pin "a"
					( attribute "PN" "1"
						( Origin gPackager )
					)
					( objectStatus "R7D28.1" )
				)
				( pin "b"
					( attribute "PN" "2"
						( Origin gPackager )
					)
					( objectStatus "R7D28.2" )
				)
			)
			( gate "@baseboard_fab2_lib.baseboard_fab2(sch_1):page92_i68"
				( attribute "BOM_COST" "PROC_SIDEBAND"
					( Origin gFrontEnd )
				)
				( attribute "CDS_LIB" "mstr_discrete"
					( Origin gPackager )
				)
				( attribute "CDS_LOCATION" "R7D27"
					( Origin gPackager )
				)
				( attribute "CDS_SEC" "1"
					( Origin gPackager )
				)
				( attribute "LOCATION" "R7D27"
					( Origin gFrontEnd )
				)
				( attribute "MATERIAL" "CHIP"
					( Origin gFrontEnd )
				)
				( attribute "PACK_TYPE" "0402"
					( Origin gFrontEnd )
				)
				( attribute "PART_NUMBER" "G21497-005"
					( Origin gFrontEnd )
				)
				( attribute "PHYS_PAGE" "92"
					( Origin gFrontEnd )
				)
				( attribute "ROOM" "PROC_SIDEBAND"
					( Origin gFrontEnd )
				)
				( attribute "ROT" "0"
					( Origin gFrontEnd )
				)
				( attribute "SEC" "1"
					( Origin gFrontEnd )
				)
				( attribute "SEC_TYPE" "0402"
					( Origin gFrontEnd )
				)
				( attribute "TOLERANCE" "5%"
					( Origin gFrontEnd )
				)
				( attribute "VALUE" "0.0"
					( Origin gFrontEnd )
				)
				( attribute "VER" "1"
					( Origin gFrontEnd )
				)
				( attribute "WATTAGE" "1/16W"
					( Origin gFrontEnd )
				)
				( attribute "XY" "(-3775,1550)"
					( Origin gFrontEnd )
				)
				( attribute "CHIPS_PART_NAME" "RES"
					( Origin gPackager )
				)
				( attribute "CDS_PART_NAME" "RES_0402-0.0,5%,1/16W,CHIP,G21A"
					( Origin gPackager )
				)
				( objectStatus "R7D27" )
				( pin "a"
					( attribute "PN" "1"
						( Origin gPackager )
					)
					( objectStatus "R7D27.1" )
				)
				( pin "b"
					( attribute "PN" "2"
						( Origin gPackager )
					)
					( objectStatus "R7D27.2" )
				)
			)
			( gate "@baseboard_fab2_lib.baseboard_fab2(sch_1):page92_i70"
				( attribute "BOM_COST" "PROC_SIDEBAND"
					( Origin gFrontEnd )
				)
				( attribute "CDS_LIB" "mstr_discrete"
					( Origin gPackager )
				)
				( attribute "CDS_LOCATION" "R7D25"
					( Origin gPackager )
				)
				( attribute "CDS_SEC" "1"
					( Origin gPackager )
				)
				( attribute "LOCATION" "R7D25"
					( Origin gFrontEnd )
				)
				( attribute "MATERIAL" "CHIP"
					( Origin gFrontEnd )
				)
				( attribute "PACK_TYPE" "0402"
					( Origin gFrontEnd )
				)
				( attribute "PART_NUMBER" "G21796-074"
					( Origin gFrontEnd )
				)
				( attribute "PHYS_PAGE" "92"
					( Origin gFrontEnd )
				)
				( attribute "ROOM" "PROC_SIDEBAND"
					( Origin gFrontEnd )
				)
				( attribute "ROT" "0"
					( Origin gFrontEnd )
				)
				( attribute "SEC" "1"
					( Origin gFrontEnd )
				)
				( attribute "SEC_TYPE" "0402"
					( Origin gFrontEnd )
				)
				( attribute "TOLERANCE" "1%"
					( Origin gFrontEnd )
				)
				( attribute "VALUE" "33.2"
					( Origin gFrontEnd )
				)
				( attribute "VER" "1"
					( Origin gFrontEnd )
				)
				( attribute "WATTAGE" "1/16W"
					( Origin gFrontEnd )
				)
				( attribute "XY" "(-100,1250)"
					( Origin gFrontEnd )
				)
				( attribute "CHIPS_PART_NAME" "RES"
					( Origin gPackager )
				)
				( attribute "CDS_PART_NAME" "RES_0402-33.2,1%,1/16W,CHIP,G2A"
					( Origin gPackager )
				)
				( objectStatus "R7D25" )
				( pin "a"
					( attribute "PN" "1"
						( Origin gPackager )
					)
					( objectStatus "R7D25.1" )
				)
				( pin "b"
					( attribute "PN" "2"
						( Origin gPackager )
					)
					( objectStatus "R7D25.2" )
				)
			)
			( gate "@baseboard_fab2_lib.baseboard_fab2(sch_1):page92_i75"
				( attribute "CDS_LIB" "mstr_discrete"
					( Origin gPackager )
				)
				( attribute "CDS_LOCATION" "R3R2"
					( Origin gPackager )
				)
				( attribute "CDS_SEC" "1"
					( Origin gPackager )
				)
				( attribute "LOCATION" "R3R2"
					( Origin gFrontEnd )
				)
				( attribute "MATERIAL" "CHIP"
					( Origin gFrontEnd )
				)
				( attribute "PACK_TYPE" "0402"
					( Origin gFrontEnd )
				)
				( attribute "PART_NUMBER" "G21796-026"
					( Origin gFrontEnd )
				)
				( attribute "PHYS_PAGE" "92"
					( Origin gFrontEnd )
				)
				( attribute "ROOM" "PROC_SIDEBAND"
					( Origin gFrontEnd )
				)
				( attribute "ROT" "0"
					( Origin gFrontEnd )
				)
				( attribute "SEC" "1"
					( Origin gFrontEnd )
				)
				( attribute "SEC_TYPE" "0402"
					( Origin gFrontEnd )
				)
				( attribute "TOLERANCE" "1%"
					( Origin gFrontEnd )
				)
				( attribute "VALUE" "1.00K"
					( Origin gFrontEnd )
				)
				( attribute "VER" "2"
					( Origin gFrontEnd )
				)
				( attribute "WATTAGE" "1/16W"
					( Origin gFrontEnd )
				)
				( attribute "XY" "(-2925,3900)"
					( Origin gFrontEnd )
				)
				( attribute "CHIPS_PART_NAME" "RES"
					( Origin gPackager )
				)
				( attribute "CDS_PART_NAME" "RES_0402-1.00K,1%,1/16W,CHIP,GA"
					( Origin gPackager )
				)
				( objectStatus "R3R2" )
				( pin "a"
					( attribute "PN" "1"
						( Origin gPackager )
					)
					( objectStatus "R3R2.1" )
				)
				( pin "b"
					( attribute "PN" "2"
						( Origin gPackager )
					)
					( objectStatus "R3R2.2" )
				)
			)
			( gate "@baseboard_fab2_lib.baseboard_fab2(sch_1):page92_i79"
				( attribute "BOM_COST" "PROC"
					( Origin gFrontEnd )
				)
				( attribute "CDS_LIB" "mstr_discrete"
					( Origin gPackager )
				)
				( attribute "CDS_LOCATION" "C7D4"
					( Origin gPackager )
				)
				( attribute "CDS_SEC" "1"
					( Origin gPackager )
				)
				( attribute "LOCATION" "C7D4"
					( Origin gFrontEnd )
				)
				( attribute "MATERIAL" "X6S"
					( Origin gFrontEnd )
				)
				( attribute "PACK_TYPE" "0402"
					( Origin gFrontEnd )
				)
				( attribute "PART_NUMBER" "D97712-011"
					( Origin gFrontEnd )
				)
				( attribute "PHYS_PAGE" "92"
					( Origin gFrontEnd )
				)
				( attribute "ROOM" "PROC_SIDEBAND"
					( Origin gFrontEnd )
				)
				( attribute "ROT" "0"
					( Origin gFrontEnd )
				)
				( attribute "SEC" "1"
					( Origin gFrontEnd )
				)
				( attribute "SEC_TYPE" "0402"
					( Origin gFrontEnd )
				)
				( attribute "TOLERANCE" "10%"
					( Origin gFrontEnd )
				)
				( attribute "VALUE" "1.0UF"
					( Origin gFrontEnd )
				)
				( attribute "VER" "1"
					( Origin gFrontEnd )
				)
				( attribute "VOLTAGE" "16V"
					( Units "uVoltage" "V" 1.000000)
					( Origin gFrontEnd )
				)
				( attribute "XY" "(-900,2525)"
					( Origin gFrontEnd )
				)
				( attribute "CHIPS_PART_NAME" "CAP"
					( Origin gPackager )
				)
				( attribute "CDS_PART_NAME" "CAP_0402-1.0UF,16V,10%,X6S,D97A"
					( Origin gPackager )
				)
				( objectStatus "C7D4" )
				( pin "a"
					( attribute "PN" "1"
						( Origin gPackager )
					)
					( objectStatus "C7D4.1" )
				)
				( pin "b"
					( attribute "PN" "2"
						( Origin gPackager )
					)
					( objectStatus "C7D4.2" )
				)
			)
			( gate "@baseboard_fab2_lib.baseboard_fab2(sch_1):page92_i84"
				( attribute "BOM_COST" "PROC"
					( Origin gFrontEnd )
				)
				( attribute "CDS_LIB" "mstr_discrete"
					( Origin gPackager )
				)
				( attribute "CDS_LOCATION" "C3P50"
					( Origin gPackager )
				)
				( attribute "CDS_SEC" "1"
					( Origin gPackager )
				)
				( attribute "LOCATION" "C3P50"
					( Origin gFrontEnd )
				)
				( attribute "MATERIAL" "X6S"
					( Origin gFrontEnd )
				)
				( attribute "PACK_TYPE" "0402"
					( Origin gFrontEnd )
				)
				( attribute "PART_NUMBER" "D97712-011"
					( Origin gFrontEnd )
				)
				( attribute "PHYS_PAGE" "92"
					( Origin gFrontEnd )
				)
				( attribute "ROOM" "PROC_SIDEBAND"
					( Origin gFrontEnd )
				)
				( attribute "ROT" "0"
					( Origin gFrontEnd )
				)
				( attribute "SEC" "1"
					( Origin gFrontEnd )
				)
				( attribute "SEC_TYPE" "0402"
					( Origin gFrontEnd )
				)
				( attribute "TOLERANCE" "10%"
					( Origin gFrontEnd )
				)
				( attribute "VALUE" "1.0UF"
					( Origin gFrontEnd )
				)
				( attribute "VER" "1"
					( Origin gFrontEnd )
				)
				( attribute "VOLTAGE" "16V"
					( Units "uVoltage" "V" 1.000000)
					( Origin gFrontEnd )
				)
				( attribute "XY" "(-1025,4725)"
					( Origin gFrontEnd )
				)
				( attribute "CHIPS_PART_NAME" "CAP"
					( Origin gPackager )
				)
				( attribute "CDS_PART_NAME" "CAP_0402-1.0UF,16V,10%,X6S,D97A"
					( Origin gPackager )
				)
				( objectStatus "C3P50" )
				( pin "a"
					( attribute "PN" "1"
						( Origin gPackager )
					)
					( objectStatus "C3P50.1" )
				)
				( pin "b"
					( attribute "PN" "2"
						( Origin gPackager )
					)
					( objectStatus "C3P50.2" )
				)
			)
			( gate "@baseboard_fab2_lib.baseboard_fab2(sch_1):page92_i92"
				( attribute "BOM_COST" "PROC"
					( Origin gFrontEnd )
				)
				( attribute "CDS_LIB" "mstr_discrete"
					( Origin gPackager )
				)
				( attribute "CDS_LOCATION" "R2T44"
					( Origin gPackager )
				)
				( attribute "CDS_SEC" "1"
					( Origin gPackager )
				)
				( attribute "LOCATION" "R2T44"
					( Origin gFrontEnd )
				)
				( attribute "MATERIAL" "CHIP"
					( Origin gFrontEnd )
				)
				( attribute "PACK_TYPE" "0402"
					( Origin gFrontEnd )
				)
				( attribute "PART_NUMBER" "G21497-005"
					( Origin gFrontEnd )
				)
				( attribute "PHYS_PAGE" "92"
					( Origin gFrontEnd )
				)
				( attribute "ROOM" "PROC_SIDEBAND"
					( Origin gFrontEnd )
				)
				( attribute "ROT" "0"
					( Origin gFrontEnd )
				)
				( attribute "SEC" "1"
					( Origin gPackager )
				)
				( attribute "TOLERANCE" "5%"
					( Origin gFrontEnd )
				)
				( attribute "VALUE" "0.0"
					( Origin gFrontEnd )
				)
				( attribute "VER" "1"
					( Origin gFrontEnd )
				)
				( attribute "WATTAGE" "1/16W"
					( Origin gFrontEnd )
				)
				( attribute "XY" "(-4575,2550)"
					( Origin gFrontEnd )
				)
				( attribute "CHIPS_PART_NAME" "RES"
					( Origin gPackager )
				)
				( attribute "CDS_PART_NAME" "RES_0402-0.0,5%,1/16W,CHIP,G21A"
					( Origin gPackager )
				)
				( objectStatus "R2T44" )
				( pin "a"
					( attribute "PN" "1"
						( Origin gPackager )
					)
					( objectStatus "R2T44.1" )
				)
				( pin "b"
					( attribute "PN" "2"
						( Origin gPackager )
					)
					( objectStatus "R2T44.2" )
				)
			)
			( gate "@baseboard_fab2_lib.baseboard_fab2(sch_1):page92_i93"
				( attribute "BOM_COST" "PROC"
					( Origin gFrontEnd )
				)
				( attribute "CDS_LIB" "mstr_discrete"
					( Origin gPackager )
				)
				( attribute "CDS_LOCATION" "R2T40"
					( Origin gPackager )
				)
				( attribute "CDS_SEC" "1"
					( Origin gPackager )
				)
				( attribute "LOCATION" "R2T40"
					( Origin gFrontEnd )
				)
				( attribute "MATERIAL" "CHIP"
					( Origin gFrontEnd )
				)
				( attribute "PACK_TYPE" "0402"
					( Origin gFrontEnd )
				)
				( attribute "PART_NUMBER" "G21497-005"
					( Origin gFrontEnd )
				)
				( attribute "PHYS_PAGE" "92"
					( Origin gFrontEnd )
				)
				( attribute "ROOM" "PROC_SIDEBAND"
					( Origin gFrontEnd )
				)
				( attribute "ROT" "0"
					( Origin gFrontEnd )
				)
				( attribute "SEC" "1"
					( Origin gPackager )
				)
				( attribute "TOLERANCE" "5%"
					( Origin gFrontEnd )
				)
				( attribute "VALUE" "0.0"
					( Origin gFrontEnd )
				)
				( attribute "VER" "1"
					( Origin gFrontEnd )
				)
				( attribute "WATTAGE" "1/16W"
					( Origin gFrontEnd )
				)
				( attribute "XY" "(-4600,2800)"
					( Origin gFrontEnd )
				)
				( attribute "CHIPS_PART_NAME" "RES"
					( Origin gPackager )
				)
				( attribute "CDS_PART_NAME" "RES_0402-0.0,5%,1/16W,CHIP,G21A"
					( Origin gPackager )
				)
				( objectStatus "R2T40" )
				( pin "a"
					( attribute "PN" "1"
						( Origin gPackager )
					)
					( objectStatus "R2T40.1" )
				)
				( pin "b"
					( attribute "PN" "2"
						( Origin gPackager )
					)
					( objectStatus "R2T40.2" )
				)
			)
			( gate "@baseboard_fab2_lib.baseboard_fab2(sch_1):page92_i94"
				( attribute "BOM_COST" "PROC"
					( Origin gFrontEnd )
				)
				( attribute "CDS_LIB" "mstr_discrete"
					( Origin gPackager )
				)
				( attribute "CDS_LOCATION" "R2T37"
					( Origin gPackager )
				)
				( attribute "CDS_SEC" "1"
					( Origin gPackager )
				)
				( attribute "LOCATION" "R2T37"
					( Origin gFrontEnd )
				)
				( attribute "MATERIAL" "CHIP"
					( Origin gFrontEnd )
				)
				( attribute "PACK_TYPE" "0402"
					( Origin gFrontEnd )
				)
				( attribute "PART_NUMBER" "G21796-004"
					( Origin gFrontEnd )
				)
				( attribute "PHYS_PAGE" "92"
					( Origin gFrontEnd )
				)
				( attribute "ROOM" "PROC_SIDEBAND"
					( Origin gFrontEnd )
				)
				( attribute "ROT" "0"
					( Origin gFrontEnd )
				)
				( attribute "SEC" "1"
					( Origin gPackager )
				)
				( attribute "TOLERANCE" "1%"
					( Origin gFrontEnd )
				)
				( attribute "VALUE" "200.0"
					( Origin gFrontEnd )
				)
				( attribute "VER" "2"
					( Origin gFrontEnd )
				)
				( attribute "WATTAGE" "1/16W"
					( Origin gFrontEnd )
				)
				( attribute "XY" "(-4000,2950)"
					( Origin gFrontEnd )
				)
				( attribute "CHIPS_PART_NAME" "RES"
					( Origin gPackager )
				)
				( attribute "CDS_PART_NAME" "RES_0402-200.0,1%,1/16W,CHIP,GA"
					( Origin gPackager )
				)
				( objectStatus "R2T37" )
				( pin "a"
					( attribute "PN" "1"
						( Origin gPackager )
					)
					( objectStatus "R2T37.1" )
				)
				( pin "b"
					( attribute "PN" "2"
						( Origin gPackager )
					)
					( objectStatus "R2T37.2" )
				)
			)
			( gate "@baseboard_fab2_lib.baseboard_fab2(sch_1):page92_i96"
				( attribute "BOM_COST" "PROC"
					( Origin gFrontEnd )
				)
				( attribute "CDS_LIB" "mstr_discrete"
					( Origin gPackager )
				)
				( attribute "CDS_LOCATION" "R2T43"
					( Origin gPackager )
				)
				( attribute "CDS_SEC" "1"
					( Origin gPackager )
				)
				( attribute "LOCATION" "R2T43"
					( Origin gFrontEnd )
				)
				( attribute "MATERIAL" "CHIP"
					( Origin gFrontEnd )
				)
				( attribute "PACK_TYPE" "0402"
					( Origin gFrontEnd )
				)
				( attribute "PART_NUMBER" "G21796-267"
					( Origin gFrontEnd )
				)
				( attribute "PHYS_PAGE" "92"
					( Origin gFrontEnd )
				)
				( attribute "ROOM" "PROC_SIDEBAND"
					( Origin gFrontEnd )
				)
				( attribute "ROT" "0"
					( Origin gFrontEnd )
				)
				( attribute "SEC" "1"
					( Origin gPackager )
				)
				( attribute "TOLERANCE" "1.0%"
					( Origin gFrontEnd )
				)
				( attribute "VALUE" "75"
					( Origin gFrontEnd )
				)
				( attribute "VER" "1"
					( Origin gFrontEnd )
				)
				( attribute "WATTAGE" "1/16W"
					( Origin gFrontEnd )
				)
				( attribute "XY" "(-3675,2675)"
					( Origin gFrontEnd )
				)
				( attribute "CHIPS_PART_NAME" "RES"
					( Origin gPackager )
				)
				( attribute "CDS_PART_NAME" "RES_0402-75,1.0%,1/16W,CHIP,G2A"
					( Origin gPackager )
				)
				( objectStatus "R2T43" )
				( pin "a"
					( attribute "PN" "1"
						( Origin gPackager )
					)
					( objectStatus "R2T43.1" )
				)
				( pin "b"
					( attribute "PN" "2"
						( Origin gPackager )
					)
					( objectStatus "R2T43.2" )
				)
			)
			( gate "@baseboard_fab2_lib.baseboard_fab2(sch_1):page92_i97"
				( attribute "BOM_COST" "PROC"
					( Origin gFrontEnd )
				)
				( attribute "CDS_LIB" "mstr_discrete"
					( Origin gPackager )
				)
				( attribute "CDS_LOCATION" "R3P59"
					( Origin gPackager )
				)
				( attribute "CDS_SEC" "1"
					( Origin gPackager )
				)
				( attribute "LOCATION" "R3P59"
					( Origin gFrontEnd )
				)
				( attribute "MATERIAL" "CHIP"
					( Origin gFrontEnd )
				)
				( attribute "PACK_TYPE" "0402"
					( Origin gFrontEnd )
				)
				( attribute "PART_NUMBER" "G21497-005"
					( Origin gFrontEnd )
				)
				( attribute "PHYS_PAGE" "92"
					( Origin gFrontEnd )
				)
				( attribute "ROOM" "PROC_SIDEBAND"
					( Origin gFrontEnd )
				)
				( attribute "ROT" "0"
					( Origin gFrontEnd )
				)
				( attribute "SEC" "1"
					( Origin gFrontEnd )
				)
				( attribute "SEC_TYPE" "0402"
					( Origin gFrontEnd )
				)
				( attribute "TOLERANCE" "5%"
					( Origin gFrontEnd )
				)
				( attribute "VALUE" "0.0"
					( Origin gFrontEnd )
				)
				( attribute "VER" "1"
					( Origin gFrontEnd )
				)
				( attribute "WATTAGE" "1/16W"
					( Origin gFrontEnd )
				)
				( attribute "XY" "(-3775,4350)"
					( Origin gFrontEnd )
				)
				( attribute "CHIPS_PART_NAME" "RES"
					( Origin gPackager )
				)
				( attribute "CDS_PART_NAME" "RES_0402-0.0,5%,1/16W,CHIP,G21A"
					( Origin gPackager )
				)
				( objectStatus "R3P59" )
				( pin "a"
					( attribute "PN" "1"
						( Origin gPackager )
					)
					( objectStatus "R3P59.1" )
				)
				( pin "b"
					( attribute "PN" "2"
						( Origin gPackager )
					)
					( objectStatus "R3P59.2" )
				)
			)
			( gate "@baseboard_fab2_lib.baseboard_fab2(sch_1):page92_i98"
				( attribute "BOM_COST" "PROC"
					( Origin gFrontEnd )
				)
				( attribute "CDS_LIB" "mstr_discrete"
					( Origin gPackager )
				)
				( attribute "CDS_LOCATION" "R3P58"
					( Origin gPackager )
				)
				( attribute "CDS_SEC" "1"
					( Origin gPackager )
				)
				( attribute "LOCATION" "R3P58"
					( Origin gFrontEnd )
				)
				( attribute "MATERIAL" "CHIP"
					( Origin gFrontEnd )
				)
				( attribute "PACK_TYPE" "0402"
					( Origin gFrontEnd )
				)
				( attribute "PART_NUMBER" "G21497-005"
					( Origin gFrontEnd )
				)
				( attribute "PHYS_PAGE" "92"
					( Origin gFrontEnd )
				)
				( attribute "ROOM" "PROC_SIDEBAND"
					( Origin gFrontEnd )
				)
				( attribute "ROT" "0"
					( Origin gFrontEnd )
				)
				( attribute "SEC" "1"
					( Origin gFrontEnd )
				)
				( attribute "SEC_TYPE" "0402"
					( Origin gFrontEnd )
				)
				( attribute "TOLERANCE" "5%"
					( Origin gFrontEnd )
				)
				( attribute "VALUE" "0.0"
					( Origin gFrontEnd )
				)
				( attribute "VER" "1"
					( Origin gFrontEnd )
				)
				( attribute "WATTAGE" "1/16W"
					( Origin gFrontEnd )
				)
				( attribute "XY" "(-3750,4100)"
					( Origin gFrontEnd )
				)
				( attribute "CHIPS_PART_NAME" "RES"
					( Origin gPackager )
				)
				( attribute "CDS_PART_NAME" "RES_0402-0.0,5%,1/16W,CHIP,G21A"
					( Origin gPackager )
				)
				( objectStatus "R3P58" )
				( pin "a"
					( attribute "PN" "1"
						( Origin gPackager )
					)
					( objectStatus "R3P58.1" )
				)
				( pin "b"
					( attribute "PN" "2"
						( Origin gPackager )
					)
					( objectStatus "R3P58.2" )
				)
			)
			( gate "@baseboard_fab2_lib.baseboard_fab2(sch_1):page92_i100"
				( attribute "BOM_COST" "PROC"
					( Origin gFrontEnd )
				)
				( attribute "CDS_LIB" "mstr_discrete"
					( Origin gPackager )
				)
				( attribute "CDS_LOCATION" "R7P18"
					( Origin gPackager )
				)
				( attribute "CDS_SEC" "1"
					( Origin gPackager )
				)
				( attribute "LOCATION" "R7P18"
					( Origin gFrontEnd )
				)
				( attribute "MATERIAL" "CHIP"
					( Origin gFrontEnd )
				)
				( attribute "PACK_TYPE" "0402"
					( Origin gFrontEnd )
				)
				( attribute "PART_NUMBER" "G21796-009"
					( Origin gFrontEnd )
				)
				( attribute "PHYS_PAGE" "92"
					( Origin gFrontEnd )
				)
				( attribute "ROOM" "PROC_SIDEBAND"
					( Origin gFrontEnd )
				)
				( attribute "ROT" "0"
					( Origin gFrontEnd )
				)
				( attribute "SEC" "1"
					( Origin gFrontEnd )
				)
				( attribute "SEC_TYPE" "0402"
					( Origin gFrontEnd )
				)
				( attribute "TOLERANCE" "1%"
					( Origin gFrontEnd )
				)
				( attribute "VALUE" "150.0"
					( Origin gFrontEnd )
				)
				( attribute "VER" "2"
					( Origin gFrontEnd )
				)
				( attribute "WATTAGE" "1/16W"
					( Origin gFrontEnd )
				)
				( attribute "XY" "(-4350,4600)"
					( Origin gFrontEnd )
				)
				( attribute "CHIPS_PART_NAME" "RES"
					( Origin gPackager )
				)
				( attribute "CDS_PART_NAME" "RES_0402-150.0,1%,1/16W,CHIP,GA"
					( Origin gPackager )
				)
				( objectStatus "R7P18" )
				( pin "a"
					( attribute "PN" "1"
						( Origin gPackager )
					)
					( objectStatus "R7P18.1" )
				)
				( pin "b"
					( attribute "PN" "2"
						( Origin gPackager )
					)
					( objectStatus "R7P18.2" )
				)
			)
			( gate "@baseboard_fab2_lib.baseboard_fab2(sch_1):page92_i101"
				( attribute "BOM_COST" "PROC"
					( Origin gFrontEnd )
				)
				( attribute "CDS_LIB" "mstr_discrete"
					( Origin gPackager )
				)
				( attribute "CDS_LOCATION" "R4R2"
					( Origin gPackager )
				)
				( attribute "CDS_SEC" "1"
					( Origin gPackager )
				)
				( attribute "LOCATION" "R4R2"
					( Origin gFrontEnd )
				)
				( attribute "MATERIAL" "CHIP"
					( Origin gFrontEnd )
				)
				( attribute "PACK_TYPE" "0402"
					( Origin gFrontEnd )
				)
				( attribute "PART_NUMBER" "G21796-009"
					( Origin gFrontEnd )
				)
				( attribute "PHYS_PAGE" "92"
					( Origin gFrontEnd )
				)
				( attribute "ROOM" "PROC_SIDEBAND"
					( Origin gFrontEnd )
				)
				( attribute "ROT" "2"
					( Origin gFrontEnd )
				)
				( attribute "SEC" "1"
					( Origin gFrontEnd )
				)
				( attribute "SEC_TYPE" "0402"
					( Origin gFrontEnd )
				)
				( attribute "TOLERANCE" "1%"
					( Origin gFrontEnd )
				)
				( attribute "VALUE" "150.0"
					( Origin gFrontEnd )
				)
				( attribute "VER" "2"
					( Origin gFrontEnd )
				)
				( attribute "WATTAGE" "1/16W"
					( Origin gFrontEnd )
				)
				( attribute "XY" "(-4450,4600)"
					( Origin gFrontEnd )
				)
				( attribute "CHIPS_PART_NAME" "RES"
					( Origin gPackager )
				)
				( attribute "CDS_PART_NAME" "RES_0402-150.0,1%,1/16W,CHIP,GA"
					( Origin gPackager )
				)
				( objectStatus "R4R2" )
				( pin "a"
					( attribute "PN" "1"
						( Origin gPackager )
					)
					( objectStatus "R4R2.1" )
				)
				( pin "b"
					( attribute "PN" "2"
						( Origin gPackager )
					)
					( objectStatus "R4R2.2" )
				)
			)
			( gate "@baseboard_fab2_lib.baseboard_fab2(sch_1):page93_i13"
				( attribute "BOM_COST" "PROC"
					( Origin gFrontEnd )
				)
				( attribute "CDS_LIB" "mstr_discrete"
					( Origin gPackager )
				)
				( attribute "CDS_LOCATION" "R2T27"
					( Origin gPackager )
				)
				( attribute "CDS_SEC" "1"
					( Origin gPackager )
				)
				( attribute "LOCATION" "R2T27"
					( Origin gFrontEnd )
				)
				( attribute "MATERIAL" "CHIP"
					( Origin gFrontEnd )
				)
				( attribute "PACK_TYPE" "0402"
					( Origin gFrontEnd )
				)
				( attribute "PART_NUMBER" "G21497-005"
					( Origin gFrontEnd )
				)
				( attribute "PHYS_PAGE" "93"
					( Origin gFrontEnd )
				)
				( attribute "ROOM" "PROC_SIDEBAND"
					( Origin gFrontEnd )
				)
				( attribute "ROT" "0"
					( Origin gFrontEnd )
				)
				( attribute "SEC" "1"
					( Origin gFrontEnd )
				)
				( attribute "SEC_TYPE" "0402"
					( Origin gFrontEnd )
				)
				( attribute "TOLERANCE" "5%"
					( Origin gFrontEnd )
				)
				( attribute "VALUE" "0.0"
					( Origin gFrontEnd )
				)
				( attribute "VER" "1"
					( Origin gFrontEnd )
				)
				( attribute "WATTAGE" "1/16W"
					( Origin gFrontEnd )
				)
				( attribute "XY" "(-2750,3200)"
					( Origin gFrontEnd )
				)
				( attribute "CHIPS_PART_NAME" "RES"
					( Origin gPackager )
				)
				( attribute "CDS_PART_NAME" "RES_0402-0.0,5%,1/16W,CHIP,G21A"
					( Origin gPackager )
				)
				( objectStatus "R2T27" )
				( pin "a"
					( attribute "PN" "1"
						( Origin gPackager )
					)
					( objectStatus "R2T27.1" )
				)
				( pin "b"
					( attribute "PN" "2"
						( Origin gPackager )
					)
					( objectStatus "R2T27.2" )
				)
			)
			( gate "@baseboard_fab2_lib.baseboard_fab2(sch_1):page93_i15"
				( attribute "BOM_COST" "PROC"
					( Origin gFrontEnd )
				)
				( attribute "CDS_LIB" "mstr_discrete"
					( Origin gPackager )
				)
				( attribute "CDS_LOCATION" "R2T32"
					( Origin gPackager )
				)
				( attribute "CDS_SEC" "1"
					( Origin gPackager )
				)
				( attribute "LOCATION" "R2T32"
					( Origin gFrontEnd )
				)
				( attribute "MATERIAL" "CHIP"
					( Origin gFrontEnd )
				)
				( attribute "PACK_TYPE" "0402"
					( Origin gFrontEnd )
				)
				( attribute "PART_NUMBER" "G21497-005"
					( Origin gFrontEnd )
				)
				( attribute "PHYS_PAGE" "93"
					( Origin gFrontEnd )
				)
				( attribute "ROOM" "PROC_SIDEBAND"
					( Origin gFrontEnd )
				)
				( attribute "ROT" "0"
					( Origin gFrontEnd )
				)
				( attribute "SEC" "1"
					( Origin gFrontEnd )
				)
				( attribute "SEC_TYPE" "0402"
					( Origin gFrontEnd )
				)
				( attribute "TOLERANCE" "5%"
					( Origin gFrontEnd )
				)
				( attribute "VALUE" "0.0"
					( Origin gFrontEnd )
				)
				( attribute "VER" "1"
					( Origin gFrontEnd )
				)
				( attribute "WATTAGE" "1/16W"
					( Origin gFrontEnd )
				)
				( attribute "XY" "(-2750,3425)"
					( Origin gFrontEnd )
				)
				( attribute "CHIPS_PART_NAME" "RES"
					( Origin gPackager )
				)
				( attribute "CDS_PART_NAME" "RES_0402-0.0,5%,1/16W,CHIP,G21A"
					( Origin gPackager )
				)
				( objectStatus "R2T32" )
				( pin "a"
					( attribute "PN" "1"
						( Origin gPackager )
					)
					( objectStatus "R2T32.1" )
				)
				( pin "b"
					( attribute "PN" "2"
						( Origin gPackager )
					)
					( objectStatus "R2T32.2" )
				)
			)
			( gate "@baseboard_fab2_lib.baseboard_fab2(sch_1):page93_i16"
				( attribute "BOM_COST" "PROC"
					( Origin gFrontEnd )
				)
				( attribute "CDS_LIB" "mstr_discrete"
					( Origin gPackager )
				)
				( attribute "CDS_LOCATION" "R2T20"
					( Origin gPackager )
				)
				( attribute "CDS_SEC" "1"
					( Origin gPackager )
				)
				( attribute "LOCATION" "R2T20"
					( Origin gFrontEnd )
				)
				( attribute "MATERIAL" "CHIP"
					( Origin gFrontEnd )
				)
				( attribute "PACK_TYPE" "0402"
					( Origin gFrontEnd )
				)
				( attribute "PART_NUMBER" "G21497-005"
					( Origin gFrontEnd )
				)
				( attribute "PHYS_PAGE" "93"
					( Origin gFrontEnd )
				)
				( attribute "ROOM" "PROC_SIDEBAND"
					( Origin gFrontEnd )
				)
				( attribute "ROT" "0"
					( Origin gFrontEnd )
				)
				( attribute "SEC" "1"
					( Origin gFrontEnd )
				)
				( attribute "SEC_TYPE" "0402"
					( Origin gFrontEnd )
				)
				( attribute "TOLERANCE" "5%"
					( Origin gFrontEnd )
				)
				( attribute "VALUE" "0.0"
					( Origin gFrontEnd )
				)
				( attribute "VER" "1"
					( Origin gFrontEnd )
				)
				( attribute "WATTAGE" "1/16W"
					( Origin gFrontEnd )
				)
				( attribute "XY" "(-2750,3725)"
					( Origin gFrontEnd )
				)
				( attribute "CHIPS_PART_NAME" "RES"
					( Origin gPackager )
				)
				( attribute "CDS_PART_NAME" "RES_0402-0.0,5%,1/16W,CHIP,G21A"
					( Origin gPackager )
				)
				( objectStatus "R2T20" )
				( pin "a"
					( attribute "PN" "1"
						( Origin gPackager )
					)
					( objectStatus "R2T20.1" )
				)
				( pin "b"
					( attribute "PN" "2"
						( Origin gPackager )
					)
					( objectStatus "R2T20.2" )
				)
			)
			( gate "@baseboard_fab2_lib.baseboard_fab2(sch_1):page93_i23"
				( attribute "BOM_COST" "PROC"
					( Origin gFrontEnd )
				)
				( attribute "CDS_LIB" "mstr_discrete"
					( Origin gPackager )
				)
				( attribute "CDS_LOCATION" "R2T17"
					( Origin gPackager )
				)
				( attribute "CDS_SEC" "1"
					( Origin gPackager )
				)
				( attribute "LOCATION" "R2T17"
					( Origin gFrontEnd )
				)
				( attribute "MATERIAL" "CHIP"
					( Origin gFrontEnd )
				)
				( attribute "PACK_TYPE" "0402"
					( Origin gFrontEnd )
				)
				( attribute "PART_NUMBER" "G21497-005"
					( Origin gFrontEnd )
				)
				( attribute "PHYS_PAGE" "93"
					( Origin gFrontEnd )
				)
				( attribute "ROOM" "PROC_SIDEBAND"
					( Origin gFrontEnd )
				)
				( attribute "ROT" "0"
					( Origin gFrontEnd )
				)
				( attribute "SEC" "1"
					( Origin gFrontEnd )
				)
				( attribute "SEC_TYPE" "0402"
					( Origin gFrontEnd )
				)
				( attribute "TOLERANCE" "5%"
					( Origin gFrontEnd )
				)
				( attribute "VALUE" "0.0"
					( Origin gFrontEnd )
				)
				( attribute "VER" "1"
					( Origin gFrontEnd )
				)
				( attribute "WATTAGE" "1/16W"
					( Origin gFrontEnd )
				)
				( attribute "XY" "(-2750,3975)"
					( Origin gFrontEnd )
				)
				( attribute "CHIPS_PART_NAME" "RES"
					( Origin gPackager )
				)
				( attribute "CDS_PART_NAME" "RES_0402-0.0,5%,1/16W,CHIP,G21A"
					( Origin gPackager )
				)
				( objectStatus "R2T17" )
				( pin "a"
					( attribute "PN" "1"
						( Origin gPackager )
					)
					( objectStatus "R2T17.1" )
				)
				( pin "b"
					( attribute "PN" "2"
						( Origin gPackager )
					)
					( objectStatus "R2T17.2" )
				)
			)
			( gate "@baseboard_fab2_lib.baseboard_fab2(sch_1):page93_i30"
				( attribute "BOM_COST" "PROC"
					( Origin gFrontEnd )
				)
				( attribute "CDS_LIB" "mstr_digital"
					( Origin gPackager )
				)
				( attribute "CDS_LOCATION" "U2T4"
					( Origin gPackager )
				)
				( attribute "CDS_SEC" "1"
					( Origin gPackager )
				)
				( attribute "LOCATION" "U2T4"
					( Origin gFrontEnd )
				)
				( attribute "MATERIAL" "IC"
					( Origin gFrontEnd )
				)
				( attribute "PACK_TYPE" "SM"
					( Origin gFrontEnd )
				)
				( attribute "PART_NUMBER" "D66151-001"
					( Origin gFrontEnd )
				)
				( attribute "PHYS_PAGE" "93"
					( Origin gFrontEnd )
				)
				( attribute "ROOM" "PROC_SIDEBAND"
					( Origin gFrontEnd )
				)
				( attribute "ROT" "2"
					( Origin gFrontEnd )
				)
				( attribute "SEC" "1"
					( Origin gFrontEnd )
				)
				( attribute "SEC_TYPE" "SM"
					( Origin gFrontEnd )
				)
				( attribute "VER" "1"
					( Origin gFrontEnd )
				)
				( attribute "XY" "(425,3350)"
					( Origin gFrontEnd )
				)
				( attribute "CHIPS_PART_NAME" "GTL2014"
					( Origin gPackager )
				)
				( attribute "CDS_PART_NAME" "GTL2014_SM-IC,D66151-001"
					( Origin gPackager )
				)
				( objectStatus "U2T4" )
				( pin "a0"
					( attribute "PN" "13"
						( Origin gPackager )
					)
					( objectStatus "U2T4.13" )
				)
				( pin "a1"
					( attribute "PN" "12"
						( Origin gPackager )
					)
					( objectStatus "U2T4.12" )
				)
				( pin "a2"
					( attribute "PN" "10"
						( Origin gPackager )
					)
					( objectStatus "U2T4.10" )
				)
				( pin "a3"
					( attribute "PN" "9"
						( Origin gPackager )
					)
					( objectStatus "U2T4.9" )
				)
				( pin "b0"
					( attribute "PN" "2"
						( Origin gPackager )
					)
					( objectStatus "U2T4.2" )
				)
				( pin "b1"
					( attribute "PN" "3"
						( Origin gPackager )
					)
					( objectStatus "U2T4.3" )
				)
				( pin "b2"
					( attribute "PN" "5"
						( Origin gPackager )
					)
					( objectStatus "U2T4.5" )
				)
				( pin "b3"
					( attribute "PN" "6"
						( Origin gPackager )
					)
					( objectStatus "U2T4.6" )
				)
				( pin "dir"
					( attribute "PN" "1"
						( Origin gPackager )
					)
					( objectStatus "U2T4.1" )
				)
				( pin "gnd(0)"
					( attribute "PN" "7"
						( Origin gPackager )
					)
					( objectStatus "U2T4.7" )
				)
				( pin "gnd(1)"
					( attribute "PN" "8"
						( Origin gPackager )
					)
					( objectStatus "U2T4.8" )
				)
				( pin "gnd(2)"
					( attribute "PN" "11"
						( Origin gPackager )
					)
					( objectStatus "U2T4.11" )
				)
				( pin "vcc"
					( attribute "PN" "14"
						( Origin gPackager )
					)
					( objectStatus "U2T4.14" )
				)
				( pin "vref"
					( attribute "PN" "4"
						( Origin gPackager )
					)
					( objectStatus "U2T4.4" )
				)
			)
			( gate "@baseboard_fab2_lib.baseboard_fab2(sch_1):page93_i39"
				( attribute "BOM_COST" "PROC"
					( Origin gFrontEnd )
				)
				( attribute "CDS_LIB" "mstr_discrete"
					( Origin gPackager )
				)
				( attribute "CDS_LOCATION" "R2T38"
					( Origin gPackager )
				)
				( attribute "CDS_SEC" "1"
					( Origin gPackager )
				)
				( attribute "LOCATION" "R2T38"
					( Origin gFrontEnd )
				)
				( attribute "MATERIAL" "CHIP"
					( Origin gFrontEnd )
				)
				( attribute "PACK_TYPE" "0402"
					( Origin gFrontEnd )
				)
				( attribute "PART_NUMBER" "G21796-074"
					( Origin gFrontEnd )
				)
				( attribute "PHYS_PAGE" "93"
					( Origin gFrontEnd )
				)
				( attribute "ROOM" "PROC_SIDEBAND"
					( Origin gFrontEnd )
				)
				( attribute "ROT" "0"
					( Origin gFrontEnd )
				)
				( attribute "SEC" "1"
					( Origin gFrontEnd )
				)
				( attribute "SEC_TYPE" "0402"
					( Origin gFrontEnd )
				)
				( attribute "TOLERANCE" "1%"
					( Origin gFrontEnd )
				)
				( attribute "VALUE" "33.2"
					( Origin gFrontEnd )
				)
				( attribute "VER" "1"
					( Origin gFrontEnd )
				)
				( attribute "WATTAGE" "1/16W"
					( Origin gFrontEnd )
				)
				( attribute "XY" "(2950,2850)"
					( Origin gFrontEnd )
				)
				( attribute "CHIPS_PART_NAME" "RES"
					( Origin gPackager )
				)
				( attribute "CDS_PART_NAME" "RES_0402-33.2,1%,1/16W,CHIP,G2A"
					( Origin gPackager )
				)
				( objectStatus "R2T38" )
				( pin "a"
					( attribute "PN" "1"
						( Origin gPackager )
					)
					( objectStatus "R2T38.1" )
				)
				( pin "b"
					( attribute "PN" "2"
						( Origin gPackager )
					)
					( objectStatus "R2T38.2" )
				)
			)
			( gate "@baseboard_fab2_lib.baseboard_fab2(sch_1):page93_i40"
				( attribute "BOM_COST" "PROC"
					( Origin gFrontEnd )
				)
				( attribute "CDS_LIB" "mstr_discrete"
					( Origin gPackager )
				)
				( attribute "CDS_LOCATION" "R2T33"
					( Origin gPackager )
				)
				( attribute "CDS_SEC" "1"
					( Origin gPackager )
				)
				( attribute "LOCATION" "R2T33"
					( Origin gFrontEnd )
				)
				( attribute "MATERIAL" "CHIP"
					( Origin gFrontEnd )
				)
				( attribute "PACK_TYPE" "0402"
					( Origin gFrontEnd )
				)
				( attribute "PART_NUMBER" "G21796-074"
					( Origin gFrontEnd )
				)
				( attribute "PHYS_PAGE" "93"
					( Origin gFrontEnd )
				)
				( attribute "ROOM" "PROC_SIDEBAND"
					( Origin gFrontEnd )
				)
				( attribute "ROT" "0"
					( Origin gFrontEnd )
				)
				( attribute "SEC" "1"
					( Origin gFrontEnd )
				)
				( attribute "SEC_TYPE" "0402"
					( Origin gFrontEnd )
				)
				( attribute "TOLERANCE" "1%"
					( Origin gFrontEnd )
				)
				( attribute "VALUE" "33.2"
					( Origin gFrontEnd )
				)
				( attribute "VER" "1"
					( Origin gFrontEnd )
				)
				( attribute "WATTAGE" "1/16W"
					( Origin gFrontEnd )
				)
				( attribute "XY" "(2950,3100)"
					( Origin gFrontEnd )
				)
				( attribute "CHIPS_PART_NAME" "RES"
					( Origin gPackager )
				)
				( attribute "CDS_PART_NAME" "RES_0402-33.2,1%,1/16W,CHIP,G2A"
					( Origin gPackager )
				)
				( objectStatus "R2T33" )
				( pin "a"
					( attribute "PN" "1"
						( Origin gPackager )
					)
					( objectStatus "R2T33.1" )
				)
				( pin "b"
					( attribute "PN" "2"
						( Origin gPackager )
					)
					( objectStatus "R2T33.2" )
				)
			)
			( gate "@baseboard_fab2_lib.baseboard_fab2(sch_1):page93_i42"
				( attribute "BOM_COST" "PROC"
					( Origin gFrontEnd )
				)
				( attribute "CDS_LIB" "mstr_discrete"
					( Origin gPackager )
				)
				( attribute "CDS_LOCATION" "R2T30"
					( Origin gPackager )
				)
				( attribute "CDS_SEC" "1"
					( Origin gPackager )
				)
				( attribute "LOCATION" "R2T30"
					( Origin gFrontEnd )
				)
				( attribute "MATERIAL" "CHIP"
					( Origin gFrontEnd )
				)
				( attribute "PACK_TYPE" "0402"
					( Origin gFrontEnd )
				)
				( attribute "PART_NUMBER" "G21796-074"
					( Origin gFrontEnd )
				)
				( attribute "PHYS_PAGE" "93"
					( Origin gFrontEnd )
				)
				( attribute "ROOM" "PROC_SIDEBAND"
					( Origin gFrontEnd )
				)
				( attribute "ROT" "0"
					( Origin gFrontEnd )
				)
				( attribute "SEC" "1"
					( Origin gFrontEnd )
				)
				( attribute "SEC_TYPE" "0402"
					( Origin gFrontEnd )
				)
				( attribute "TOLERANCE" "1%"
					( Origin gFrontEnd )
				)
				( attribute "VALUE" "33.2"
					( Origin gFrontEnd )
				)
				( attribute "VER" "1"
					( Origin gFrontEnd )
				)
				( attribute "WATTAGE" "1/16W"
					( Origin gFrontEnd )
				)
				( attribute "XY" "(2950,3350)"
					( Origin gFrontEnd )
				)
				( attribute "CHIPS_PART_NAME" "RES"
					( Origin gPackager )
				)
				( attribute "CDS_PART_NAME" "RES_0402-33.2,1%,1/16W,CHIP,G2A"
					( Origin gPackager )
				)
				( objectStatus "R2T30" )
				( pin "a"
					( attribute "PN" "1"
						( Origin gPackager )
					)
					( objectStatus "R2T30.1" )
				)
				( pin "b"
					( attribute "PN" "2"
						( Origin gPackager )
					)
					( objectStatus "R2T30.2" )
				)
			)
			( gate "@baseboard_fab2_lib.baseboard_fab2(sch_1):page93_i62"
				( attribute "BOM_COST" "PROC"
					( Origin gFrontEnd )
				)
				( attribute "CDS_LIB" "mstr_discrete"
					( Origin gPackager )
				)
				( attribute "CDS_LOCATION" "R7D24"
					( Origin gPackager )
				)
				( attribute "CDS_SEC" "1"
					( Origin gPackager )
				)
				( attribute "LOCATION" "R7D24"
					( Origin gFrontEnd )
				)
				( attribute "MATERIAL" "CHIP"
					( Origin gFrontEnd )
				)
				( attribute "PACK_TYPE" "0402"
					( Origin gFrontEnd )
				)
				( attribute "PART_NUMBER" "G21796-074"
					( Origin gFrontEnd )
				)
				( attribute "PHYS_PAGE" "93"
					( Origin gFrontEnd )
				)
				( attribute "ROOM" "PROC_SIDEBAND"
					( Origin gFrontEnd )
				)
				( attribute "ROT" "0"
					( Origin gFrontEnd )
				)
				( attribute "SEC" "1"
					( Origin gFrontEnd )
				)
				( attribute "SEC_TYPE" "0402"
					( Origin gFrontEnd )
				)
				( attribute "TOLERANCE" "1%"
					( Origin gFrontEnd )
				)
				( attribute "VALUE" "33.2"
					( Origin gFrontEnd )
				)
				( attribute "VER" "1"
					( Origin gFrontEnd )
				)
				( attribute "WATTAGE" "1/16W"
					( Origin gFrontEnd )
				)
				( attribute "XY" "(2950,2575)"
					( Origin gFrontEnd )
				)
				( attribute "CHIPS_PART_NAME" "RES"
					( Origin gPackager )
				)
				( attribute "CDS_PART_NAME" "RES_0402-33.2,1%,1/16W,CHIP,G2A"
					( Origin gPackager )
				)
				( objectStatus "R7D24" )
				( pin "a"
					( attribute "PN" "1"
						( Origin gPackager )
					)
					( objectStatus "R7D24.1" )
				)
				( pin "b"
					( attribute "PN" "2"
						( Origin gPackager )
					)
					( objectStatus "R7D24.2" )
				)
			)
			( gate "@baseboard_fab2_lib.baseboard_fab2(sch_1):page93_i63"
				( attribute "BOM_COST" "PROC"
					( Origin gFrontEnd )
				)
				( attribute "CDS_LIB" "mstr_discrete"
					( Origin gPackager )
				)
				( attribute "CDS_LOCATION" "R2T19"
					( Origin gPackager )
				)
				( attribute "CDS_SEC" "1"
					( Origin gPackager )
				)
				( attribute "LOCATION" "R2T19"
					( Origin gFrontEnd )
				)
				( attribute "MATERIAL" "CHIP"
					( Origin gFrontEnd )
				)
				( attribute "PACK_TYPE" "0402"
					( Origin gFrontEnd )
				)
				( attribute "PART_NUMBER" "G21796-004"
					( Origin gFrontEnd )
				)
				( attribute "PHYS_PAGE" "93"
					( Origin gFrontEnd )
				)
				( attribute "ROOM" "PROC_SIDEBAND"
					( Origin gFrontEnd )
				)
				( attribute "ROT" "0"
					( Origin gFrontEnd )
				)
				( attribute "SEC" "1"
					( Origin gFrontEnd )
				)
				( attribute "SEC_TYPE" "0402"
					( Origin gFrontEnd )
				)
				( attribute "TOLERANCE" "1%"
					( Origin gFrontEnd )
				)
				( attribute "VALUE" "200.0"
					( Origin gFrontEnd )
				)
				( attribute "VER" "2"
					( Origin gFrontEnd )
				)
				( attribute "WATTAGE" "1/16W"
					( Origin gFrontEnd )
				)
				( attribute "XY" "(-2325,4050)"
					( Origin gFrontEnd )
				)
				( attribute "CHIPS_PART_NAME" "RES"
					( Origin gPackager )
				)
				( attribute "CDS_PART_NAME" "RES_0402-200.0,1%,1/16W,CHIP,GA"
					( Origin gPackager )
				)
				( objectStatus "R2T19" )
				( pin "a"
					( attribute "PN" "1"
						( Origin gPackager )
					)
					( objectStatus "R2T19.1" )
				)
				( pin "b"
					( attribute "PN" "2"
						( Origin gPackager )
					)
					( objectStatus "R2T19.2" )
				)
			)
			( gate "@baseboard_fab2_lib.baseboard_fab2(sch_1):page93_i67"
				( attribute "CDS_LIB" "mstr_discrete"
					( Origin gPackager )
				)
				( attribute "CDS_LOCATION" "R2T16"
					( Origin gPackager )
				)
				( attribute "CDS_SEC" "1"
					( Origin gPackager )
				)
				( attribute "LOCATION" "R2T16"
					( Origin gFrontEnd )
				)
				( attribute "MATERIAL" "CHIP"
					( Origin gFrontEnd )
				)
				( attribute "PACK_TYPE" "0402"
					( Origin gFrontEnd )
				)
				( attribute "PART_NUMBER" "G21796-267"
					( Origin gFrontEnd )
				)
				( attribute "PHYS_PAGE" "93"
					( Origin gFrontEnd )
				)
				( attribute "ROOM" "PROC_SIDEBAND"
					( Origin gFrontEnd )
				)
				( attribute "ROT" "0"
					( Origin gFrontEnd )
				)
				( attribute "SEC" "1"
					( Origin gFrontEnd )
				)
				( attribute "SEC_TYPE" "0402"
					( Origin gFrontEnd )
				)
				( attribute "TOLERANCE" "1.0%"
					( Origin gFrontEnd )
				)
				( attribute "VALUE" "75"
					( Origin gFrontEnd )
				)
				( attribute "VER" "1"
					( Origin gFrontEnd )
				)
				( attribute "WATTAGE" "1/16W"
					( Origin gFrontEnd )
				)
				( attribute "XY" "(-925,3825)"
					( Origin gFrontEnd )
				)
				( attribute "CHIPS_PART_NAME" "RES"
					( Origin gPackager )
				)
				( attribute "CDS_PART_NAME" "RES_0402-75,1.0%,1/16W,CHIP,G2A"
					( Origin gPackager )
				)
				( objectStatus "R2T16" )
				( pin "a"
					( attribute "PN" "1"
						( Origin gPackager )
					)
					( objectStatus "R2T16.1" )
				)
				( pin "b"
					( attribute "PN" "2"
						( Origin gPackager )
					)
					( objectStatus "R2T16.2" )
				)
			)
			( gate "@baseboard_fab2_lib.baseboard_fab2(sch_1):page93_i68"
				( attribute "CDS_LIB" "mstr_discrete"
					( Origin gPackager )
				)
				( attribute "CDS_LOCATION" "R2T31"
					( Origin gPackager )
				)
				( attribute "CDS_SEC" "1"
					( Origin gPackager )
				)
				( attribute "LOCATION" "R2T31"
					( Origin gFrontEnd )
				)
				( attribute "MATERIAL" "CHIP"
					( Origin gFrontEnd )
				)
				( attribute "PACK_TYPE" "0402"
					( Origin gFrontEnd )
				)
				( attribute "PART_NUMBER" "G21796-267"
					( Origin gFrontEnd )
				)
				( attribute "PHYS_PAGE" "93"
					( Origin gFrontEnd )
				)
				( attribute "ROOM" "PROC_SIDEBAND"
					( Origin gFrontEnd )
				)
				( attribute "ROT" "0"
					( Origin gFrontEnd )
				)
				( attribute "SEC" "1"
					( Origin gFrontEnd )
				)
				( attribute "SEC_TYPE" "0402"
					( Origin gFrontEnd )
				)
				( attribute "TOLERANCE" "1.0%"
					( Origin gFrontEnd )
				)
				( attribute "VALUE" "75"
					( Origin gFrontEnd )
				)
				( attribute "VER" "1"
					( Origin gFrontEnd )
				)
				( attribute "WATTAGE" "1/16W"
					( Origin gFrontEnd )
				)
				( attribute "XY" "(-925,3300)"
					( Origin gFrontEnd )
				)
				( attribute "CHIPS_PART_NAME" "RES"
					( Origin gPackager )
				)
				( attribute "CDS_PART_NAME" "RES_0402-75,1.0%,1/16W,CHIP,G2A"
					( Origin gPackager )
				)
				( objectStatus "R2T31" )
				( pin "a"
					( attribute "PN" "1"
						( Origin gPackager )
					)
					( objectStatus "R2T31.1" )
				)
				( pin "b"
					( attribute "PN" "2"
						( Origin gPackager )
					)
					( objectStatus "R2T31.2" )
				)
			)
			( gate "@baseboard_fab2_lib.baseboard_fab2(sch_1):page93_i72"
				( attribute "BOM_COST" "PROC"
					( Origin gFrontEnd )
				)
				( attribute "CDS_LIB" "dev_discrete"
					( Origin gPackager )
				)
				( attribute "CDS_LOCATION" "C2T33"
					( Origin gPackager )
				)
				( attribute "CDS_SEC" "1"
					( Origin gPackager )
				)
				( attribute "LOCATION" "C2T33"
					( Origin gFrontEnd )
				)
				( attribute "MATERIAL" "X6S"
					( Origin gFrontEnd )
				)
				( attribute "PACK_TYPE" "0402V"
					( Origin gFrontEnd )
				)
				( attribute "PART_NUMBER" "D97712-004"
					( Origin gFrontEnd )
				)
				( attribute "PHYS_PAGE" "93"
					( Origin gFrontEnd )
				)
				( attribute "ROOM" "PROC_SIDEBAND"
					( Origin gFrontEnd )
				)
				( attribute "ROT" "0"
					( Origin gFrontEnd )
				)
				( attribute "SEC" "1"
					( Origin gFrontEnd )
				)
				( attribute "SEC_TYPE" "0402V"
					( Origin gFrontEnd )
				)
				( attribute "TOLERANCE" "10%"
					( Origin gFrontEnd )
				)
				( attribute "VALUE" "1.0UF"
					( Origin gFrontEnd )
				)
				( attribute "VER" "1"
					( Origin gFrontEnd )
				)
				( attribute "VOLTAGE" "6.3V"
					( Units "uVoltage" "V" 1.000000)
					( Origin gFrontEnd )
				)
				( attribute "XY" "(1150,3875)"
					( Origin gFrontEnd )
				)
				( attribute "CHIPS_PART_NAME" "CAP_A"
					( Origin gPackager )
				)
				( attribute "CDS_PART_NAME" "CAP_A_0402V-1.0UF,6.3V,10%,X6SA"
					( Origin gPackager )
				)
				( objectStatus "C2T33" )
				( pin "a"
					( attribute "PN" "1"
						( Origin gPackager )
					)
					( objectStatus "C2T33.1" )
				)
				( pin "b"
					( attribute "PN" "2"
						( Origin gPackager )
					)
					( objectStatus "C2T33.2" )
				)
			)
			( gate "@baseboard_fab2_lib.baseboard_fab2(sch_1):page93_i79"
				( attribute "BOM_COST" "PROC_SIDEBAND"
					( Origin gFrontEnd )
				)
				( attribute "CDS_LIB" "mstr_discrete"
					( Origin gPackager )
				)
				( attribute "CDS_LOCATION" "R4R3"
					( Origin gPackager )
				)
				( attribute "CDS_SEC" "1"
					( Origin gPackager )
				)
				( attribute "LOCATION" "R4R3"
					( Origin gFrontEnd )
				)
				( attribute "MATERIAL" "CHIP"
					( Origin gFrontEnd )
				)
				( attribute "PACK_TYPE" "0402"
					( Origin gFrontEnd )
				)
				( attribute "PART_NUMBER" "G21796-009"
					( Origin gFrontEnd )
				)
				( attribute "PHYS_PAGE" "93"
					( Origin gFrontEnd )
				)
				( attribute "ROOM" "PROC_SIDEBAND"
					( Origin gFrontEnd )
				)
				( attribute "ROT" "0"
					( Origin gFrontEnd )
				)
				( attribute "SEC" "1"
					( Origin gFrontEnd )
				)
				( attribute "SEC_TYPE" "0402"
					( Origin gFrontEnd )
				)
				( attribute "TOLERANCE" "1%"
					( Origin gFrontEnd )
				)
				( attribute "VALUE" "150.0"
					( Origin gFrontEnd )
				)
				( attribute "VER" "2"
					( Origin gFrontEnd )
				)
				( attribute "WATTAGE" "1/16W"
					( Origin gFrontEnd )
				)
				( attribute "XY" "(-2750,2525)"
					( Origin gFrontEnd )
				)
				( attribute "CHIPS_PART_NAME" "RES"
					( Origin gPackager )
				)
				( attribute "CDS_PART_NAME" "RES_0402-150.0,1%,1/16W,CHIP,GA"
					( Origin gPackager )
				)
				( objectStatus "R4R3" )
				( pin "a"
					( attribute "PN" "1"
						( Origin gPackager )
					)
					( objectStatus "R4R3.1" )
				)
				( pin "b"
					( attribute "PN" "2"
						( Origin gPackager )
					)
					( objectStatus "R4R3.2" )
				)
			)
			( gate "@baseboard_fab2_lib.baseboard_fab2(sch_1):page93_i87"
				( attribute "BOM_COST" "PROC"
					( Origin gFrontEnd )
				)
				( attribute "CDS_LIB" "mstr_discrete"
					( Origin gPackager )
				)
				( attribute "CDS_LOCATION" "R2T26"
					( Origin gPackager )
				)
				( attribute "CDS_SEC" "1"
					( Origin gPackager )
				)
				( attribute "LOCATION" "R2T26"
					( Origin gFrontEnd )
				)
				( attribute "MATERIAL" "CHIP"
					( Origin gFrontEnd )
				)
				( attribute "PACK_TYPE" "0402"
					( Origin gFrontEnd )
				)
				( attribute "PART_NUMBER" "G21796-004"
					( Origin gFrontEnd )
				)
				( attribute "PHYS_PAGE" "93"
					( Origin gFrontEnd )
				)
				( attribute "ROOM" "PROC_SIDEBAND"
					( Origin gFrontEnd )
				)
				( attribute "ROT" "0"
					( Origin gFrontEnd )
				)
				( attribute "SEC" "1"
					( Origin gFrontEnd )
				)
				( attribute "SEC_TYPE" "0402"
					( Origin gFrontEnd )
				)
				( attribute "TOLERANCE" "1%"
					( Origin gFrontEnd )
				)
				( attribute "VALUE" "200.0"
					( Origin gFrontEnd )
				)
				( attribute "VER" "2"
					( Origin gFrontEnd )
				)
				( attribute "WATTAGE" "1/16W"
					( Origin gFrontEnd )
				)
				( attribute "XY" "(-2025,4050)"
					( Origin gFrontEnd )
				)
				( attribute "CHIPS_PART_NAME" "RES"
					( Origin gPackager )
				)
				( attribute "CDS_PART_NAME" "RES_0402-200.0,1%,1/16W,CHIP,GA"
					( Origin gPackager )
				)
				( objectStatus "R2T26" )
				( pin "a"
					( attribute "PN" "1"
						( Origin gPackager )
					)
					( objectStatus "R2T26.1" )
				)
				( pin "b"
					( attribute "PN" "2"
						( Origin gPackager )
					)
					( objectStatus "R2T26.2" )
				)
			)
			( gate "@baseboard_fab2_lib.baseboard_fab2(sch_1):page93_i88"
				( attribute "CDS_LIB" "mstr_discrete"
					( Origin gPackager )
				)
				( attribute "CDS_LOCATION" "R2T57"
					( Origin gPackager )
				)
				( attribute "CDS_SEC" "1"
					( Origin gPackager )
				)
				( attribute "LOCATION" "R2T57"
					( Origin gFrontEnd )
				)
				( attribute "MATERIAL" "EMPTY"
					( Origin gFrontEnd )
				)
				( attribute "PACK_TYPE" "0402"
					( Origin gFrontEnd )
				)
				( attribute "PART_NUMBER" "G21497-005"
					( Origin gFrontEnd )
				)
				( attribute "PHYS_PAGE" "93"
					( Origin gFrontEnd )
				)
				( attribute "ROT" "0"
					( Origin gFrontEnd )
				)
				( attribute "SEC" "1"
					( Origin gFrontEnd )
				)
				( attribute "SEC_TYPE" "0402"
					( Origin gFrontEnd )
				)
				( attribute "TOLERANCE" "5%"
					( Origin gFrontEnd )
				)
				( attribute "VALUE" "0.0"
					( Origin gFrontEnd )
				)
				( attribute "VER" "2"
					( Origin gFrontEnd )
				)
				( attribute "WATTAGE" "1/16W"
					( Origin gFrontEnd )
				)
				( attribute "XY" "(-1375,4125)"
					( Origin gFrontEnd )
				)
				( attribute "CHIPS_PART_NAME" "RES"
					( Origin gPackager )
				)
				( attribute "CDS_PART_NAME" "RES_0402-0.0,5%,1/16W,EMPTY,G2A"
					( Origin gPackager )
				)
				( objectStatus "R2T57" )
				( pin "a"
					( attribute "PN" "1"
						( Origin gPackager )
					)
					( objectStatus "R2T57.1" )
				)
				( pin "b"
					( attribute "PN" "2"
						( Origin gPackager )
					)
					( objectStatus "R2T57.2" )
				)
			)
			( gate "@baseboard_fab2_lib.baseboard_fab2(sch_1):page93_i89"
				( attribute "CDS_LIB" "mstr_discrete"
					( Origin gPackager )
				)
				( attribute "CDS_LOCATION" "R2T61"
					( Origin gPackager )
				)
				( attribute "CDS_SEC" "1"
					( Origin gPackager )
				)
				( attribute "LOCATION" "R2T61"
					( Origin gFrontEnd )
				)
				( attribute "MATERIAL" "EMPTY"
					( Origin gFrontEnd )
				)
				( attribute "PACK_TYPE" "0402"
					( Origin gFrontEnd )
				)
				( attribute "PART_NUMBER" "G21497-005"
					( Origin gFrontEnd )
				)
				( attribute "PHYS_PAGE" "93"
					( Origin gFrontEnd )
				)
				( attribute "ROT" "0"
					( Origin gFrontEnd )
				)
				( attribute "SEC" "1"
					( Origin gFrontEnd )
				)
				( attribute "SEC_TYPE" "0402"
					( Origin gFrontEnd )
				)
				( attribute "TOLERANCE" "5%"
					( Origin gFrontEnd )
				)
				( attribute "VALUE" "0.0"
					( Origin gFrontEnd )
				)
				( attribute "VER" "2"
					( Origin gFrontEnd )
				)
				( attribute "WATTAGE" "1/16W"
					( Origin gFrontEnd )
				)
				( attribute "XY" "(-1100,4125)"
					( Origin gFrontEnd )
				)
				( attribute "CHIPS_PART_NAME" "RES"
					( Origin gPackager )
				)
				( attribute "CDS_PART_NAME" "RES_0402-0.0,5%,1/16W,EMPTY,G2A"
					( Origin gPackager )
				)
				( objectStatus "R2T61" )
				( pin "a"
					( attribute "PN" "1"
						( Origin gPackager )
					)
					( objectStatus "R2T61.1" )
				)
				( pin "b"
					( attribute "PN" "2"
						( Origin gPackager )
					)
					( objectStatus "R2T61.2" )
				)
			)
			( gate "@baseboard_fab2_lib.baseboard_fab2(sch_1):page93_i93"
				( attribute "CDS_LIB" "mstr_discrete"
					( Origin gPackager )
				)
				( attribute "CDS_LOCATION" "R2T62"
					( Origin gPackager )
				)
				( attribute "CDS_SEC" "1"
					( Origin gPackager )
				)
				( attribute "LOCATION" "R2T62"
					( Origin gFrontEnd )
				)
				( attribute "MATERIAL" "EMPTY"
					( Origin gFrontEnd )
				)
				( attribute "PACK_TYPE" "0402"
					( Origin gFrontEnd )
				)
				( attribute "PART_NUMBER" "G21497-005"
					( Origin gFrontEnd )
				)
				( attribute "PHYS_PAGE" "93"
					( Origin gFrontEnd )
				)
				( attribute "ROT" "0"
					( Origin gFrontEnd )
				)
				( attribute "SEC" "1"
					( Origin gFrontEnd )
				)
				( attribute "SEC_TYPE" "0402"
					( Origin gFrontEnd )
				)
				( attribute "TOLERANCE" "5%"
					( Origin gFrontEnd )
				)
				( attribute "VALUE" "0.0"
					( Origin gFrontEnd )
				)
				( attribute "VER" "2"
					( Origin gFrontEnd )
				)
				( attribute "WATTAGE" "1/16W"
					( Origin gFrontEnd )
				)
				( attribute "XY" "(2025,3850)"
					( Origin gFrontEnd )
				)
				( attribute "CHIPS_PART_NAME" "RES"
					( Origin gPackager )
				)
				( attribute "CDS_PART_NAME" "RES_0402-0.0,5%,1/16W,EMPTY,G2A"
					( Origin gPackager )
				)
				( objectStatus "R2T62" )
				( pin "a"
					( attribute "PN" "1"
						( Origin gPackager )
					)
					( objectStatus "R2T62.1" )
				)
				( pin "b"
					( attribute "PN" "2"
						( Origin gPackager )
					)
					( objectStatus "R2T62.2" )
				)
			)
			( gate "@baseboard_fab2_lib.baseboard_fab2(sch_1):page93_i94"
				( attribute "CDS_LIB" "mstr_discrete"
					( Origin gPackager )
				)
				( attribute "CDS_LOCATION" "R2T58"
					( Origin gPackager )
				)
				( attribute "CDS_SEC" "1"
					( Origin gPackager )
				)
				( attribute "LOCATION" "R2T58"
					( Origin gFrontEnd )
				)
				( attribute "MATERIAL" "EMPTY"
					( Origin gFrontEnd )
				)
				( attribute "PACK_TYPE" "0402"
					( Origin gFrontEnd )
				)
				( attribute "PART_NUMBER" "G21497-005"
					( Origin gFrontEnd )
				)
				( attribute "PHYS_PAGE" "93"
					( Origin gFrontEnd )
				)
				( attribute "ROT" "0"
					( Origin gFrontEnd )
				)
				( attribute "SEC" "1"
					( Origin gFrontEnd )
				)
				( attribute "SEC_TYPE" "0402"
					( Origin gFrontEnd )
				)
				( attribute "TOLERANCE" "5%"
					( Origin gFrontEnd )
				)
				( attribute "VALUE" "0.0"
					( Origin gFrontEnd )
				)
				( attribute "VER" "2"
					( Origin gFrontEnd )
				)
				( attribute "WATTAGE" "1/16W"
					( Origin gFrontEnd )
				)
				( attribute "XY" "(2400,3850)"
					( Origin gFrontEnd )
				)
				( attribute "CHIPS_PART_NAME" "RES"
					( Origin gPackager )
				)
				( attribute "CDS_PART_NAME" "RES_0402-0.0,5%,1/16W,EMPTY,G2A"
					( Origin gPackager )
				)
				( objectStatus "R2T58" )
				( pin "a"
					( attribute "PN" "1"
						( Origin gPackager )
					)
					( objectStatus "R2T58.1" )
				)
				( pin "b"
					( attribute "PN" "2"
						( Origin gPackager )
					)
					( objectStatus "R2T58.2" )
				)
			)
			( gate "@baseboard_fab2_lib.baseboard_fab2(sch_1):page93_i95"
				( attribute "BOM_COST" "PROC"
					( Origin gFrontEnd )
				)
				( attribute "CDS_LIB" "dev_discrete"
					( Origin gPackager )
				)
				( attribute "CDS_LOCATION" "C2T32"
					( Origin gPackager )
				)
				( attribute "CDS_SEC" "1"
					( Origin gPackager )
				)
				( attribute "LOCATION" "C2T32"
					( Origin gFrontEnd )
				)
				( attribute "MATERIAL" "X7R"
					( Origin gFrontEnd )
				)
				( attribute "PACK_TYPE" "0402V"
					( Origin gFrontEnd )
				)
				( attribute "PART_NUMBER" "A36096-030"
					( Origin gFrontEnd )
				)
				( attribute "PHYS_PAGE" "93"
					( Origin gFrontEnd )
				)
				( attribute "ROOM" "PROC_SIDEBAND"
					( Origin gFrontEnd )
				)
				( attribute "ROT" "0"
					( Origin gFrontEnd )
				)
				( attribute "SEC" "1"
					( Origin gFrontEnd )
				)
				( attribute "SEC_TYPE" "0402V"
					( Origin gFrontEnd )
				)
				( attribute "TOLERANCE" "10%"
					( Origin gFrontEnd )
				)
				( attribute "VALUE" "0.1UF"
					( Origin gFrontEnd )
				)
				( attribute "VER" "1"
					( Origin gFrontEnd )
				)
				( attribute "VOLTAGE" "16V"
					( Units "uVoltage" "V" 1.000000)
					( Origin gFrontEnd )
				)
				( attribute "XY" "(1925,625)"
					( Origin gFrontEnd )
				)
				( attribute "CHIPS_PART_NAME" "CAP_A"
					( Origin gPackager )
				)
				( attribute "CDS_PART_NAME" "CAP_A_0402V-0.1UF,16V,10%,X7R,A"
					( Origin gPackager )
				)
				( objectStatus "C2T32" )
				( pin "a"
					( attribute "PN" "1"
						( Origin gPackager )
					)
					( objectStatus "C2T32.1" )
				)
				( pin "b"
					( attribute "PN" "2"
						( Origin gPackager )
					)
					( objectStatus "C2T32.2" )
				)
			)
			( gate "@baseboard_fab2_lib.baseboard_fab2(sch_1):page93_i97"
				( attribute "BOM_COST" "PROC"
					( Origin gFrontEnd )
				)
				( attribute "CDS_LIB" "mstr_discrete"
					( Origin gPackager )
				)
				( attribute "CDS_LOCATION" "R2T36"
					( Origin gPackager )
				)
				( attribute "CDS_SEC" "1"
					( Origin gPackager )
				)
				( attribute "LOCATION" "R2T36"
					( Origin gFrontEnd )
				)
				( attribute "MATERIAL" "CHIP"
					( Origin gFrontEnd )
				)
				( attribute "PACK_TYPE" "0402"
					( Origin gFrontEnd )
				)
				( attribute "PART_NUMBER" "G21796-047"
					( Origin gFrontEnd )
				)
				( attribute "PHYS_PAGE" "93"
					( Origin gFrontEnd )
				)
				( attribute "ROOM" "PROC_SIDEBAND"
					( Origin gFrontEnd )
				)
				( attribute "ROT" "0"
					( Origin gFrontEnd )
				)
				( attribute "SEC" "1"
					( Origin gFrontEnd )
				)
				( attribute "SEC_TYPE" "0402"
					( Origin gFrontEnd )
				)
				( attribute "TOLERANCE" "1%"
					( Origin gFrontEnd )
				)
				( attribute "VALUE" "49.9"
					( Origin gFrontEnd )
				)
				( attribute "VER" "2"
					( Origin gFrontEnd )
				)
				( attribute "WATTAGE" "1/16W"
					( Origin gFrontEnd )
				)
				( attribute "XY" "(2275,1100)"
					( Origin gFrontEnd )
				)
				( attribute "CHIPS_PART_NAME" "RES"
					( Origin gPackager )
				)
				( attribute "CDS_PART_NAME" "RES_0402-49.9,1%,1/16W,CHIP,G2A"
					( Origin gPackager )
				)
				( objectStatus "R2T36" )
				( pin "a"
					( attribute "PN" "1"
						( Origin gPackager )
					)
					( objectStatus "R2T36.1" )
				)
				( pin "b"
					( attribute "PN" "2"
						( Origin gPackager )
					)
					( objectStatus "R2T36.2" )
				)
			)
			( gate "@baseboard_fab2_lib.baseboard_fab2(sch_1):page93_i98"
				( attribute "BOM_COST" "PROC"
					( Origin gFrontEnd )
				)
				( attribute "CDS_LIB" "mstr_discrete"
					( Origin gPackager )
				)
				( attribute "CDS_LOCATION" "R2T39"
					( Origin gPackager )
				)
				( attribute "CDS_SEC" "1"
					( Origin gPackager )
				)
				( attribute "LOCATION" "R2T39"
					( Origin gFrontEnd )
				)
				( attribute "MATERIAL" "CHIP"
					( Origin gFrontEnd )
				)
				( attribute "PACK_TYPE" "0402"
					( Origin gFrontEnd )
				)
				( attribute "PART_NUMBER" "G21796-017"
					( Origin gFrontEnd )
				)
				( attribute "PHYS_PAGE" "93"
					( Origin gFrontEnd )
				)
				( attribute "ROOM" "PROC_SIDEBAND"
					( Origin gFrontEnd )
				)
				( attribute "ROT" "0"
					( Origin gFrontEnd )
				)
				( attribute "SEC" "1"
					( Origin gFrontEnd )
				)
				( attribute "SEC_TYPE" "0402"
					( Origin gFrontEnd )
				)
				( attribute "TOLERANCE" "1%"
					( Origin gFrontEnd )
				)
				( attribute "VALUE" "100.0"
					( Origin gFrontEnd )
				)
				( attribute "VER" "2"
					( Origin gFrontEnd )
				)
				( attribute "WATTAGE" "1/16W"
					( Origin gFrontEnd )
				)
				( attribute "XY" "(2275,575)"
					( Origin gFrontEnd )
				)
				( attribute "CHIPS_PART_NAME" "RES"
					( Origin gPackager )
				)
				( attribute "CDS_PART_NAME" "RES_0402-100.0,1%,1/16W,CHIP,GA"
					( Origin gPackager )
				)
				( objectStatus "R2T39" )
				( pin "a"
					( attribute "PN" "1"
						( Origin gPackager )
					)
					( objectStatus "R2T39.1" )
				)
				( pin "b"
					( attribute "PN" "2"
						( Origin gPackager )
					)
					( objectStatus "R2T39.2" )
				)
			)
			( gate "@baseboard_fab2_lib.baseboard_fab2(sch_1):page93_i102"
				( attribute "CDS_LIB" "mstr_discrete"
					( Origin gPackager )
				)
				( attribute "CDS_LOCATION" "R2T68"
					( Origin gPackager )
				)
				( attribute "CDS_SEC" "1"
					( Origin gPackager )
				)
				( attribute "LOCATION" "R2T68"
					( Origin gFrontEnd )
				)
				( attribute "MATERIAL" "CHIP"
					( Origin gFrontEnd )
				)
				( attribute "PACK_TYPE" "0402"
					( Origin gFrontEnd )
				)
				( attribute "PART_NUMBER" "G21497-005"
					( Origin gFrontEnd )
				)
				( attribute "PHYS_PAGE" "93"
					( Origin gFrontEnd )
				)
				( attribute "ROT" "0"
					( Origin gFrontEnd )
				)
				( attribute "SEC" "1"
					( Origin gFrontEnd )
				)
				( attribute "SEC_TYPE" "0402"
					( Origin gFrontEnd )
				)
				( attribute "TOLERANCE" "5%"
					( Origin gFrontEnd )
				)
				( attribute "VALUE" "0.0"
					( Origin gFrontEnd )
				)
				( attribute "VER" "1"
					( Origin gFrontEnd )
				)
				( attribute "WATTAGE" "1/16W"
					( Origin gFrontEnd )
				)
				( attribute "XY" "(-825,2175)"
					( Origin gFrontEnd )
				)
				( attribute "CHIPS_PART_NAME" "RES"
					( Origin gPackager )
				)
				( attribute "CDS_PART_NAME" "RES_0402-0.0,5%,1/16W,CHIP,G21A"
					( Origin gPackager )
				)
				( objectStatus "R2T68" )
				( pin "a"
					( attribute "PN" "1"
						( Origin gPackager )
					)
					( objectStatus "R2T68.1" )
				)
				( pin "b"
					( attribute "PN" "2"
						( Origin gPackager )
					)
					( objectStatus "R2T68.2" )
				)
			)
			( gate "@baseboard_fab2_lib.baseboard_fab2(sch_1):page93_i103"
				( attribute "CDS_LIB" "mstr_discrete"
					( Origin gPackager )
				)
				( attribute "CDS_LOCATION" "R2T60"
					( Origin gPackager )
				)
				( attribute "CDS_SEC" "1"
					( Origin gPackager )
				)
				( attribute "LOCATION" "R2T60"
					( Origin gFrontEnd )
				)
				( attribute "MATERIAL" "CHIP"
					( Origin gFrontEnd )
				)
				( attribute "PACK_TYPE" "0402"
					( Origin gFrontEnd )
				)
				( attribute "PART_NUMBER" "G21497-005"
					( Origin gFrontEnd )
				)
				( attribute "PHYS_PAGE" "93"
					( Origin gFrontEnd )
				)
				( attribute "ROT" "0"
					( Origin gFrontEnd )
				)
				( attribute "SEC" "1"
					( Origin gFrontEnd )
				)
				( attribute "SEC_TYPE" "0402"
					( Origin gFrontEnd )
				)
				( attribute "TOLERANCE" "5%"
					( Origin gFrontEnd )
				)
				( attribute "VALUE" "0.0"
					( Origin gFrontEnd )
				)
				( attribute "VER" "1"
					( Origin gFrontEnd )
				)
				( attribute "WATTAGE" "1/16W"
					( Origin gFrontEnd )
				)
				( attribute "XY" "(-825,2300)"
					( Origin gFrontEnd )
				)
				( attribute "CHIPS_PART_NAME" "RES"
					( Origin gPackager )
				)
				( attribute "CDS_PART_NAME" "RES_0402-0.0,5%,1/16W,CHIP,G21A"
					( Origin gPackager )
				)
				( objectStatus "R2T60" )
				( pin "a"
					( attribute "PN" "1"
						( Origin gPackager )
					)
					( objectStatus "R2T60.1" )
				)
				( pin "b"
					( attribute "PN" "2"
						( Origin gPackager )
					)
					( objectStatus "R2T60.2" )
				)
			)
			( gate "@baseboard_fab2_lib.baseboard_fab2(sch_1):page93_i106"
				( attribute "BOM_COST" "PROC_SIDEBAND"
					( Origin gFrontEnd )
				)
				( attribute "CDS_LIB" "mstr_discrete"
					( Origin gPackager )
				)
				( attribute "CDS_LOCATION" "R7P28"
					( Origin gPackager )
				)
				( attribute "CDS_SEC" "1"
					( Origin gPackager )
				)
				( attribute "LOCATION" "R7P28"
					( Origin gFrontEnd )
				)
				( attribute "MATERIAL" "CHIP"
					( Origin gFrontEnd )
				)
				( attribute "PACK_TYPE" "0402"
					( Origin gFrontEnd )
				)
				( attribute "PART_NUMBER" "G21796-009"
					( Origin gFrontEnd )
				)
				( attribute "PHYS_PAGE" "93"
					( Origin gFrontEnd )
				)
				( attribute "ROOM" "PROC_SIDEBAND"
					( Origin gFrontEnd )
				)
				( attribute "ROT" "0"
					( Origin gFrontEnd )
				)
				( attribute "SEC" "1"
					( Origin gFrontEnd )
				)
				( attribute "SEC_TYPE" "0402"
					( Origin gFrontEnd )
				)
				( attribute "TOLERANCE" "1%"
					( Origin gFrontEnd )
				)
				( attribute "VALUE" "150.0"
					( Origin gFrontEnd )
				)
				( attribute "VER" "2"
					( Origin gFrontEnd )
				)
				( attribute "WATTAGE" "1/16W"
					( Origin gFrontEnd )
				)
				( attribute "XY" "(-2200,2500)"
					( Origin gFrontEnd )
				)
				( attribute "CHIPS_PART_NAME" "RES"
					( Origin gPackager )
				)
				( attribute "CDS_PART_NAME" "RES_0402-150.0,1%,1/16W,CHIP,GA"
					( Origin gPackager )
				)
				( objectStatus "R7P28" )
				( pin "a"
					( attribute "PN" "1"
						( Origin gPackager )
					)
					( objectStatus "R7P28.1" )
				)
				( pin "b"
					( attribute "PN" "2"
						( Origin gPackager )
					)
					( objectStatus "R7P28.2" )
				)
			)
			( gate "@baseboard_fab2_lib.baseboard_fab2(sch_1):page93_i107"
				( attribute "CDS_LIB" "mstr_discrete"
					( Origin gPackager )
				)
				( attribute "CDS_LOCATION" "R2T59"
					( Origin gPackager )
				)
				( attribute "CDS_SEC" "1"
					( Origin gPackager )
				)
				( attribute "LOCATION" "R2T59"
					( Origin gFrontEnd )
				)
				( attribute "MATERIAL" "EMPTY"
					( Origin gFrontEnd )
				)
				( attribute "PACK_TYPE" "0402"
					( Origin gFrontEnd )
				)
				( attribute "PART_NUMBER" "G21497-005"
					( Origin gFrontEnd )
				)
				( attribute "PHYS_PAGE" "93"
					( Origin gFrontEnd )
				)
				( attribute "ROT" "0"
					( Origin gFrontEnd )
				)
				( attribute "SEC" "1"
					( Origin gFrontEnd )
				)
				( attribute "SEC_TYPE" "0402"
					( Origin gFrontEnd )
				)
				( attribute "TOLERANCE" "5%"
					( Origin gFrontEnd )
				)
				( attribute "VALUE" "0.0"
					( Origin gFrontEnd )
				)
				( attribute "VER" "2"
					( Origin gFrontEnd )
				)
				( attribute "WATTAGE" "1/16W"
					( Origin gFrontEnd )
				)
				( attribute "XY" "(-1100,1900)"
					( Origin gFrontEnd )
				)
				( attribute "CHIPS_PART_NAME" "RES"
					( Origin gPackager )
				)
				( attribute "CDS_PART_NAME" "RES_0402-0.0,5%,1/16W,EMPTY,G2A"
					( Origin gPackager )
				)
				( objectStatus "R2T59" )
				( pin "a"
					( attribute "PN" "1"
						( Origin gPackager )
					)
					( objectStatus "R2T59.1" )
				)
				( pin "b"
					( attribute "PN" "2"
						( Origin gPackager )
					)
					( objectStatus "R2T59.2" )
				)
			)
			( gate "@baseboard_fab2_lib.baseboard_fab2(sch_1):page93_i108"
				( attribute "CDS_LIB" "mstr_discrete"
					( Origin gPackager )
				)
				( attribute "CDS_LOCATION" "R2T69"
					( Origin gPackager )
				)
				( attribute "CDS_SEC" "1"
					( Origin gPackager )
				)
				( attribute "LOCATION" "R2T69"
					( Origin gFrontEnd )
				)
				( attribute "MATERIAL" "EMPTY"
					( Origin gFrontEnd )
				)
				( attribute "PACK_TYPE" "0402"
					( Origin gFrontEnd )
				)
				( attribute "PART_NUMBER" "G21497-005"
					( Origin gFrontEnd )
				)
				( attribute "PHYS_PAGE" "93"
					( Origin gFrontEnd )
				)
				( attribute "ROT" "0"
					( Origin gFrontEnd )
				)
				( attribute "SEC" "1"
					( Origin gFrontEnd )
				)
				( attribute "SEC_TYPE" "0402"
					( Origin gFrontEnd )
				)
				( attribute "TOLERANCE" "5%"
					( Origin gFrontEnd )
				)
				( attribute "VALUE" "0.0"
					( Origin gFrontEnd )
				)
				( attribute "VER" "2"
					( Origin gFrontEnd )
				)
				( attribute "WATTAGE" "1/16W"
					( Origin gFrontEnd )
				)
				( attribute "XY" "(-1400,1900)"
					( Origin gFrontEnd )
				)
				( attribute "CHIPS_PART_NAME" "RES"
					( Origin gPackager )
				)
				( attribute "CDS_PART_NAME" "RES_0402-0.0,5%,1/16W,EMPTY,G2A"
					( Origin gPackager )
				)
				( objectStatus "R2T69" )
				( pin "a"
					( attribute "PN" "1"
						( Origin gPackager )
					)
					( objectStatus "R2T69.1" )
				)
				( pin "b"
					( attribute "PN" "2"
						( Origin gPackager )
					)
					( objectStatus "R2T69.2" )
				)
			)
			( gate "@baseboard_fab2_lib.baseboard_fab2(sch_1):page93_i109"
				( attribute "CDS_LIB" "mstr_discrete"
					( Origin gPackager )
				)
				( attribute "CDS_LOCATION" "R2T71"
					( Origin gPackager )
				)
				( attribute "CDS_SEC" "1"
					( Origin gPackager )
				)
				( attribute "LOCATION" "R2T71"
					( Origin gFrontEnd )
				)
				( attribute "MATERIAL" "EMPTY"
					( Origin gFrontEnd )
				)
				( attribute "PACK_TYPE" "0402"
					( Origin gFrontEnd )
				)
				( attribute "PART_NUMBER" "G21497-005"
					( Origin gFrontEnd )
				)
				( attribute "PHYS_PAGE" "93"
					( Origin gFrontEnd )
				)
				( attribute "ROT" "0"
					( Origin gFrontEnd )
				)
				( attribute "SEC" "1"
					( Origin gFrontEnd )
				)
				( attribute "SEC_TYPE" "0402"
					( Origin gFrontEnd )
				)
				( attribute "TOLERANCE" "5%"
					( Origin gFrontEnd )
				)
				( attribute "VALUE" "0.0"
					( Origin gFrontEnd )
				)
				( attribute "VER" "2"
					( Origin gFrontEnd )
				)
				( attribute "WATTAGE" "1/16W"
					( Origin gFrontEnd )
				)
				( attribute "XY" "(2025,2225)"
					( Origin gFrontEnd )
				)
				( attribute "CHIPS_PART_NAME" "RES"
					( Origin gPackager )
				)
				( attribute "CDS_PART_NAME" "RES_0402-0.0,5%,1/16W,EMPTY,G2A"
					( Origin gPackager )
				)
				( objectStatus "R2T71" )
				( pin "a"
					( attribute "PN" "1"
						( Origin gPackager )
					)
					( objectStatus "R2T71.1" )
				)
				( pin "b"
					( attribute "PN" "2"
						( Origin gPackager )
					)
					( objectStatus "R2T71.2" )
				)
			)
			( gate "@baseboard_fab2_lib.baseboard_fab2(sch_1):page93_i110"
				( attribute "CDS_LIB" "mstr_discrete"
					( Origin gPackager )
				)
				( attribute "CDS_LOCATION" "R7D43"
					( Origin gPackager )
				)
				( attribute "CDS_SEC" "1"
					( Origin gPackager )
				)
				( attribute "LOCATION" "R7D43"
					( Origin gFrontEnd )
				)
				( attribute "MATERIAL" "EMPTY"
					( Origin gFrontEnd )
				)
				( attribute "PACK_TYPE" "0402"
					( Origin gFrontEnd )
				)
				( attribute "PART_NUMBER" "G21497-005"
					( Origin gFrontEnd )
				)
				( attribute "PHYS_PAGE" "93"
					( Origin gFrontEnd )
				)
				( attribute "ROT" "0"
					( Origin gFrontEnd )
				)
				( attribute "SEC" "1"
					( Origin gFrontEnd )
				)
				( attribute "SEC_TYPE" "0402"
					( Origin gFrontEnd )
				)
				( attribute "TOLERANCE" "5%"
					( Origin gFrontEnd )
				)
				( attribute "VALUE" "0.0"
					( Origin gFrontEnd )
				)
				( attribute "VER" "2"
					( Origin gFrontEnd )
				)
				( attribute "WATTAGE" "1/16W"
					( Origin gFrontEnd )
				)
				( attribute "XY" "(2400,2225)"
					( Origin gFrontEnd )
				)
				( attribute "CHIPS_PART_NAME" "RES"
					( Origin gPackager )
				)
				( attribute "CDS_PART_NAME" "RES_0402-0.0,5%,1/16W,EMPTY,G2A"
					( Origin gPackager )
				)
				( objectStatus "R7D43" )
				( pin "a"
					( attribute "PN" "1"
						( Origin gPackager )
					)
					( objectStatus "R7D43.1" )
				)
				( pin "b"
					( attribute "PN" "2"
						( Origin gPackager )
					)
					( objectStatus "R7D43.2" )
				)
			)
			( gate "@baseboard_fab2_lib.baseboard_fab2(sch_1):page93_i111"
				( attribute "CDS_LIB" "mstr_discrete"
					( Origin gPackager )
				)
				( attribute "CDS_LOCATION" "R2T65"
					( Origin gPackager )
				)
				( attribute "CDS_SEC" "1"
					( Origin gPackager )
				)
				( attribute "LOCATION" "R2T65"
					( Origin gFrontEnd )
				)
				( attribute "MATERIAL" "CHIP"
					( Origin gFrontEnd )
				)
				( attribute "PACK_TYPE" "0402"
					( Origin gFrontEnd )
				)
				( attribute "PART_NUMBER" "G21497-005"
					( Origin gFrontEnd )
				)
				( attribute "PHYS_PAGE" "93"
					( Origin gFrontEnd )
				)
				( attribute "ROT" "0"
					( Origin gFrontEnd )
				)
				( attribute "SEC" "1"
					( Origin gFrontEnd )
				)
				( attribute "SEC_TYPE" "0402"
					( Origin gFrontEnd )
				)
				( attribute "TOLERANCE" "5%"
					( Origin gFrontEnd )
				)
				( attribute "VALUE" "0.0"
					( Origin gFrontEnd )
				)
				( attribute "VER" "1"
					( Origin gFrontEnd )
				)
				( attribute "WATTAGE" "1/16W"
					( Origin gFrontEnd )
				)
				( attribute "XY" "(1875,3350)"
					( Origin gFrontEnd )
				)
				( attribute "CHIPS_PART_NAME" "RES"
					( Origin gPackager )
				)
				( attribute "CDS_PART_NAME" "RES_0402-0.0,5%,1/16W,CHIP,G21A"
					( Origin gPackager )
				)
				( objectStatus "R2T65" )
				( pin "a"
					( attribute "PN" "1"
						( Origin gPackager )
					)
					( objectStatus "R2T65.1" )
				)
				( pin "b"
					( attribute "PN" "2"
						( Origin gPackager )
					)
					( objectStatus "R2T65.2" )
				)
			)
			( gate "@baseboard_fab2_lib.baseboard_fab2(sch_1):page93_i112"
				( attribute "CDS_LIB" "mstr_discrete"
					( Origin gPackager )
				)
				( attribute "CDS_LOCATION" "R2T66"
					( Origin gPackager )
				)
				( attribute "CDS_SEC" "1"
					( Origin gPackager )
				)
				( attribute "LOCATION" "R2T66"
					( Origin gFrontEnd )
				)
				( attribute "MATERIAL" "CHIP"
					( Origin gFrontEnd )
				)
				( attribute "PACK_TYPE" "0402"
					( Origin gFrontEnd )
				)
				( attribute "PART_NUMBER" "G21497-005"
					( Origin gFrontEnd )
				)
				( attribute "PHYS_PAGE" "93"
					( Origin gFrontEnd )
				)
				( attribute "ROT" "0"
					( Origin gFrontEnd )
				)
				( attribute "SEC" "1"
					( Origin gFrontEnd )
				)
				( attribute "SEC_TYPE" "0402"
					( Origin gFrontEnd )
				)
				( attribute "TOLERANCE" "5%"
					( Origin gFrontEnd )
				)
				( attribute "VALUE" "0.0"
					( Origin gFrontEnd )
				)
				( attribute "VER" "1"
					( Origin gFrontEnd )
				)
				( attribute "WATTAGE" "1/16W"
					( Origin gFrontEnd )
				)
				( attribute "XY" "(1875,3100)"
					( Origin gFrontEnd )
				)
				( attribute "CHIPS_PART_NAME" "RES"
					( Origin gPackager )
				)
				( attribute "CDS_PART_NAME" "RES_0402-0.0,5%,1/16W,CHIP,G21A"
					( Origin gPackager )
				)
				( objectStatus "R2T66" )
				( pin "a"
					( attribute "PN" "1"
						( Origin gPackager )
					)
					( objectStatus "R2T66.1" )
				)
				( pin "b"
					( attribute "PN" "2"
						( Origin gPackager )
					)
					( objectStatus "R2T66.2" )
				)
			)
			( gate "@baseboard_fab2_lib.baseboard_fab2(sch_1):page93_i113"
				( attribute "CDS_LIB" "mstr_discrete"
					( Origin gPackager )
				)
				( attribute "CDS_LOCATION" "R2T67"
					( Origin gPackager )
				)
				( attribute "CDS_SEC" "1"
					( Origin gPackager )
				)
				( attribute "LOCATION" "R2T67"
					( Origin gFrontEnd )
				)
				( attribute "MATERIAL" "CHIP"
					( Origin gFrontEnd )
				)
				( attribute "PACK_TYPE" "0402"
					( Origin gFrontEnd )
				)
				( attribute "PART_NUMBER" "G21497-005"
					( Origin gFrontEnd )
				)
				( attribute "PHYS_PAGE" "93"
					( Origin gFrontEnd )
				)
				( attribute "ROT" "0"
					( Origin gFrontEnd )
				)
				( attribute "SEC" "1"
					( Origin gFrontEnd )
				)
				( attribute "SEC_TYPE" "0402"
					( Origin gFrontEnd )
				)
				( attribute "TOLERANCE" "5%"
					( Origin gFrontEnd )
				)
				( attribute "VALUE" "0.0"
					( Origin gFrontEnd )
				)
				( attribute "VER" "1"
					( Origin gFrontEnd )
				)
				( attribute "WATTAGE" "1/16W"
					( Origin gFrontEnd )
				)
				( attribute "XY" "(1875,2850)"
					( Origin gFrontEnd )
				)
				( attribute "CHIPS_PART_NAME" "RES"
					( Origin gPackager )
				)
				( attribute "CDS_PART_NAME" "RES_0402-0.0,5%,1/16W,CHIP,G21A"
					( Origin gPackager )
				)
				( objectStatus "R2T67" )
				( pin "a"
					( attribute "PN" "1"
						( Origin gPackager )
					)
					( objectStatus "R2T67.1" )
				)
				( pin "b"
					( attribute "PN" "2"
						( Origin gPackager )
					)
					( objectStatus "R2T67.2" )
				)
			)
			( gate "@baseboard_fab2_lib.baseboard_fab2(sch_1):page93_i114"
				( attribute "CDS_LIB" "mstr_discrete"
					( Origin gPackager )
				)
				( attribute "CDS_LOCATION" "R7D41"
					( Origin gPackager )
				)
				( attribute "CDS_SEC" "1"
					( Origin gPackager )
				)
				( attribute "LOCATION" "R7D41"
					( Origin gFrontEnd )
				)
				( attribute "MATERIAL" "CHIP"
					( Origin gFrontEnd )
				)
				( attribute "PACK_TYPE" "0402"
					( Origin gFrontEnd )
				)
				( attribute "PART_NUMBER" "G21497-005"
					( Origin gFrontEnd )
				)
				( attribute "PHYS_PAGE" "93"
					( Origin gFrontEnd )
				)
				( attribute "ROT" "0"
					( Origin gFrontEnd )
				)
				( attribute "SEC" "1"
					( Origin gFrontEnd )
				)
				( attribute "SEC_TYPE" "0402"
					( Origin gFrontEnd )
				)
				( attribute "TOLERANCE" "5%"
					( Origin gFrontEnd )
				)
				( attribute "VALUE" "0.0"
					( Origin gFrontEnd )
				)
				( attribute "VER" "1"
					( Origin gFrontEnd )
				)
				( attribute "WATTAGE" "1/16W"
					( Origin gFrontEnd )
				)
				( attribute "XY" "(1875,2575)"
					( Origin gFrontEnd )
				)
				( attribute "CHIPS_PART_NAME" "RES"
					( Origin gPackager )
				)
				( attribute "CDS_PART_NAME" "RES_0402-0.0,5%,1/16W,CHIP,G21A"
					( Origin gPackager )
				)
				( objectStatus "R7D41" )
				( pin "a"
					( attribute "PN" "1"
						( Origin gPackager )
					)
					( objectStatus "R7D41.1" )
				)
				( pin "b"
					( attribute "PN" "2"
						( Origin gPackager )
					)
					( objectStatus "R7D41.2" )
				)
			)
			( gate "@baseboard_fab2_lib.baseboard_fab2(sch_1):page93_i119"
				( attribute "CDS_LIB" "mstr_discrete"
					( Origin gPackager )
				)
				( attribute "CDS_LOCATION" "R8F38"
					( Origin gPackager )
				)
				( attribute "CDS_SEC" "1"
					( Origin gPackager )
				)
				( attribute "LOCATION" "R8F38"
					( Origin gFrontEnd )
				)
				( attribute "MATERIAL" "CHIP"
					( Origin gFrontEnd )
				)
				( attribute "PACK_TYPE" "0402"
					( Origin gFrontEnd )
				)
				( attribute "PART_NUMBER" "G21497-005"
					( Origin gFrontEnd )
				)
				( attribute "PHYS_PAGE" "93"
					( Origin gFrontEnd )
				)
				( attribute "ROT" "0"
					( Origin gFrontEnd )
				)
				( attribute "SEC" "1"
					( Origin gFrontEnd )
				)
				( attribute "SEC_TYPE" "0402"
					( Origin gFrontEnd )
				)
				( attribute "TOLERANCE" "5%"
					( Origin gFrontEnd )
				)
				( attribute "VALUE" "0.0"
					( Origin gFrontEnd )
				)
				( attribute "VER" "1"
					( Origin gFrontEnd )
				)
				( attribute "WATTAGE" "1/16W"
					( Origin gFrontEnd )
				)
				( attribute "XY" "(-2225,1450)"
					( Origin gFrontEnd )
				)
				( attribute "CHIPS_PART_NAME" "RES"
					( Origin gPackager )
				)
				( attribute "CDS_PART_NAME" "RES_0402-0.0,5%,1/16W,CHIP,G21A"
					( Origin gPackager )
				)
				( objectStatus "R8F38" )
				( pin "a"
					( attribute "PN" "1"
						( Origin gPackager )
					)
					( objectStatus "R8F38.1" )
				)
				( pin "b"
					( attribute "PN" "2"
						( Origin gPackager )
					)
					( objectStatus "R8F38.2" )
				)
			)
			( gate "@baseboard_fab2_lib.baseboard_fab2(sch_1):page93_i121"
				( attribute "CDS_LIB" "mstr_discrete"
					( Origin gPackager )
				)
				( attribute "CDS_LOCATION" "R2T64"
					( Origin gPackager )
				)
				( attribute "CDS_SEC" "1"
					( Origin gPackager )
				)
				( attribute "LOCATION" "R2T64"
					( Origin gFrontEnd )
				)
				( attribute "MATERIAL" "CHIP"
					( Origin gFrontEnd )
				)
				( attribute "PACK_TYPE" "0402"
					( Origin gFrontEnd )
				)
				( attribute "PART_NUMBER" "G21497-005"
					( Origin gFrontEnd )
				)
				( attribute "PHYS_PAGE" "93"
					( Origin gFrontEnd )
				)
				( attribute "ROT" "0"
					( Origin gFrontEnd )
				)
				( attribute "SEC" "1"
					( Origin gFrontEnd )
				)
				( attribute "SEC_TYPE" "0402"
					( Origin gFrontEnd )
				)
				( attribute "TOLERANCE" "5%"
					( Origin gFrontEnd )
				)
				( attribute "VALUE" "0.0"
					( Origin gFrontEnd )
				)
				( attribute "VER" "1"
					( Origin gFrontEnd )
				)
				( attribute "WATTAGE" "1/16W"
					( Origin gFrontEnd )
				)
				( attribute "XY" "(-2225,1050)"
					( Origin gFrontEnd )
				)
				( attribute "CHIPS_PART_NAME" "RES"
					( Origin gPackager )
				)
				( attribute "CDS_PART_NAME" "RES_0402-0.0,5%,1/16W,CHIP,G21A"
					( Origin gPackager )
				)
				( objectStatus "R2T64" )
				( pin "a"
					( attribute "PN" "1"
						( Origin gPackager )
					)
					( objectStatus "R2T64.1" )
				)
				( pin "b"
					( attribute "PN" "2"
						( Origin gPackager )
					)
					( objectStatus "R2T64.2" )
				)
			)
			( gate "@baseboard_fab2_lib.baseboard_fab2(sch_1):page93_i122"
				( attribute "CDS_LIB" "mstr_discrete"
					( Origin gPackager )
				)
				( attribute "CDS_LOCATION" "R1T36"
					( Origin gPackager )
				)
				( attribute "CDS_SEC" "1"
					( Origin gPackager )
				)
				( attribute "LOCATION" "R1T36"
					( Origin gFrontEnd )
				)
				( attribute "MATERIAL" "CHIP"
					( Origin gFrontEnd )
				)
				( attribute "PACK_TYPE" "0402"
					( Origin gFrontEnd )
				)
				( attribute "PART_NUMBER" "G21497-005"
					( Origin gFrontEnd )
				)
				( attribute "PHYS_PAGE" "93"
					( Origin gFrontEnd )
				)
				( attribute "ROT" "0"
					( Origin gFrontEnd )
				)
				( attribute "SEC" "1"
					( Origin gFrontEnd )
				)
				( attribute "SEC_TYPE" "0402"
					( Origin gFrontEnd )
				)
				( attribute "TOLERANCE" "5%"
					( Origin gFrontEnd )
				)
				( attribute "VALUE" "0.0"
					( Origin gFrontEnd )
				)
				( attribute "VER" "1"
					( Origin gFrontEnd )
				)
				( attribute "WATTAGE" "1/16W"
					( Origin gFrontEnd )
				)
				( attribute "XY" "(-2225,675)"
					( Origin gFrontEnd )
				)
				( attribute "CHIPS_PART_NAME" "RES"
					( Origin gPackager )
				)
				( attribute "CDS_PART_NAME" "RES_0402-0.0,5%,1/16W,CHIP,G21A"
					( Origin gPackager )
				)
				( objectStatus "R1T36" )
				( pin "a"
					( attribute "PN" "1"
						( Origin gPackager )
					)
					( objectStatus "R1T36.1" )
				)
				( pin "b"
					( attribute "PN" "2"
						( Origin gPackager )
					)
					( objectStatus "R1T36.2" )
				)
			)
			( gate "@baseboard_fab2_lib.baseboard_fab2(sch_1):page93_i123"
				( attribute "CDS_LIB" "mstr_discrete"
					( Origin gPackager )
				)
				( attribute "CDS_LOCATION" "R1T37"
					( Origin gPackager )
				)
				( attribute "CDS_SEC" "1"
					( Origin gPackager )
				)
				( attribute "LOCATION" "R1T37"
					( Origin gFrontEnd )
				)
				( attribute "MATERIAL" "CHIP"
					( Origin gFrontEnd )
				)
				( attribute "PACK_TYPE" "0402"
					( Origin gFrontEnd )
				)
				( attribute "PART_NUMBER" "G21497-005"
					( Origin gFrontEnd )
				)
				( attribute "PHYS_PAGE" "93"
					( Origin gFrontEnd )
				)
				( attribute "ROT" "0"
					( Origin gFrontEnd )
				)
				( attribute "SEC" "1"
					( Origin gFrontEnd )
				)
				( attribute "SEC_TYPE" "0402"
					( Origin gFrontEnd )
				)
				( attribute "TOLERANCE" "5%"
					( Origin gFrontEnd )
				)
				( attribute "VALUE" "0.0"
					( Origin gFrontEnd )
				)
				( attribute "VER" "1"
					( Origin gFrontEnd )
				)
				( attribute "WATTAGE" "1/16W"
					( Origin gFrontEnd )
				)
				( attribute "XY" "(-2225,275)"
					( Origin gFrontEnd )
				)
				( attribute "CHIPS_PART_NAME" "RES"
					( Origin gPackager )
				)
				( attribute "CDS_PART_NAME" "RES_0402-0.0,5%,1/16W,CHIP,G21A"
					( Origin gPackager )
				)
				( objectStatus "R1T37" )
				( pin "a"
					( attribute "PN" "1"
						( Origin gPackager )
					)
					( objectStatus "R1T37.1" )
				)
				( pin "b"
					( attribute "PN" "2"
						( Origin gPackager )
					)
					( objectStatus "R1T37.2" )
				)
			)
			( gate "@baseboard_fab2_lib.baseboard_fab2(sch_1):page93_i127"
				( attribute "BOM_COST" "PROC"
					( Origin gFrontEnd )
				)
				( attribute "CDS_LIB" "mstr_discrete"
					( Origin gPackager )
				)
				( attribute "CDS_LOCATION" "R2T50"
					( Origin gPackager )
				)
				( attribute "CDS_SEC" "1"
					( Origin gPackager )
				)
				( attribute "LOCATION" "R2T50"
					( Origin gFrontEnd )
				)
				( attribute "MATERIAL" "CHIP"
					( Origin gFrontEnd )
				)
				( attribute "PACK_TYPE" "0402"
					( Origin gFrontEnd )
				)
				( attribute "PART_NUMBER" "G21796-026"
					( Origin gFrontEnd )
				)
				( attribute "PHYS_PAGE" "93"
					( Origin gFrontEnd )
				)
				( attribute "ROOM" "PROC_SIDEBAND"
					( Origin gFrontEnd )
				)
				( attribute "ROT" "0"
					( Origin gFrontEnd )
				)
				( attribute "SEC" "1"
					( Origin gFrontEnd )
				)
				( attribute "SEC_TYPE" "0402"
					( Origin gFrontEnd )
				)
				( attribute "TOLERANCE" "1%"
					( Origin gFrontEnd )
				)
				( attribute "VALUE" "1.00K"
					( Origin gFrontEnd )
				)
				( attribute "VER" "2"
					( Origin gFrontEnd )
				)
				( attribute "WATTAGE" "1/16W"
					( Origin gFrontEnd )
				)
				( attribute "XY" "(3700,425)"
					( Origin gFrontEnd )
				)
				( attribute "CHIPS_PART_NAME" "RES"
					( Origin gPackager )
				)
				( attribute "CDS_PART_NAME" "RES_0402-1.00K,1%,1/16W,CHIP,GA"
					( Origin gPackager )
				)
				( objectStatus "R2T50" )
				( pin "a"
					( attribute "PN" "1"
						( Origin gPackager )
					)
					( objectStatus "R2T50.1" )
				)
				( pin "b"
					( attribute "PN" "2"
						( Origin gPackager )
					)
					( objectStatus "R2T50.2" )
				)
			)
			( gate "@baseboard_fab2_lib.baseboard_fab2(sch_1):page93_i131"
				( attribute "CDS_LIB" "mstr_discrete"
					( Origin gPackager )
				)
				( attribute "CDS_LOCATION" "R8F37"
					( Origin gPackager )
				)
				( attribute "CDS_SEC" "1"
					( Origin gPackager )
				)
				( attribute "LOCATION" "R8F37"
					( Origin gFrontEnd )
				)
				( attribute "MATERIAL" "EMPTY"
					( Origin gFrontEnd )
				)
				( attribute "PACK_TYPE" "0402"
					( Origin gFrontEnd )
				)
				( attribute "PART_NUMBER" "G21497-005"
					( Origin gFrontEnd )
				)
				( attribute "PHYS_PAGE" "93"
					( Origin gFrontEnd )
				)
				( attribute "ROT" "0"
					( Origin gFrontEnd )
				)
				( attribute "SEC" "1"
					( Origin gFrontEnd )
				)
				( attribute "SEC_TYPE" "0402"
					( Origin gFrontEnd )
				)
				( attribute "TOLERANCE" "5%"
					( Origin gFrontEnd )
				)
				( attribute "VALUE" "0.0"
					( Origin gFrontEnd )
				)
				( attribute "VER" "1"
					( Origin gFrontEnd )
				)
				( attribute "WATTAGE" "1/16W"
					( Origin gFrontEnd )
				)
				( attribute "XY" "(-2225,1250)"
					( Origin gFrontEnd )
				)
				( attribute "CHIPS_PART_NAME" "RES"
					( Origin gPackager )
				)
				( attribute "CDS_PART_NAME" "RES_0402-0.0,5%,1/16W,EMPTY,G2A"
					( Origin gPackager )
				)
				( objectStatus "R8F37" )
				( pin "a"
					( attribute "PN" "1"
						( Origin gPackager )
					)
					( objectStatus "R8F37.1" )
				)
				( pin "b"
					( attribute "PN" "2"
						( Origin gPackager )
					)
					( objectStatus "R8F37.2" )
				)
			)
			( gate "@baseboard_fab2_lib.baseboard_fab2(sch_1):page93_i133"
				( attribute "CDS_LIB" "mstr_discrete"
					( Origin gPackager )
				)
				( attribute "CDS_LOCATION" "R2T63"
					( Origin gPackager )
				)
				( attribute "CDS_SEC" "1"
					( Origin gPackager )
				)
				( attribute "LOCATION" "R2T63"
					( Origin gFrontEnd )
				)
				( attribute "MATERIAL" "EMPTY"
					( Origin gFrontEnd )
				)
				( attribute "PACK_TYPE" "0402"
					( Origin gFrontEnd )
				)
				( attribute "PART_NUMBER" "G21497-005"
					( Origin gFrontEnd )
				)
				( attribute "PHYS_PAGE" "93"
					( Origin gFrontEnd )
				)
				( attribute "ROT" "0"
					( Origin gFrontEnd )
				)
				( attribute "SEC" "1"
					( Origin gFrontEnd )
				)
				( attribute "SEC_TYPE" "0402"
					( Origin gFrontEnd )
				)
				( attribute "TOLERANCE" "5%"
					( Origin gFrontEnd )
				)
				( attribute "VALUE" "0.0"
					( Origin gFrontEnd )
				)
				( attribute "VER" "1"
					( Origin gFrontEnd )
				)
				( attribute "WATTAGE" "1/16W"
					( Origin gFrontEnd )
				)
				( attribute "XY" "(-2225,850)"
					( Origin gFrontEnd )
				)
				( attribute "CHIPS_PART_NAME" "RES"
					( Origin gPackager )
				)
				( attribute "CDS_PART_NAME" "RES_0402-0.0,5%,1/16W,EMPTY,G2A"
					( Origin gPackager )
				)
				( objectStatus "R2T63" )
				( pin "a"
					( attribute "PN" "1"
						( Origin gPackager )
					)
					( objectStatus "R2T63.1" )
				)
				( pin "b"
					( attribute "PN" "2"
						( Origin gPackager )
					)
					( objectStatus "R2T63.2" )
				)
			)
			( gate "@baseboard_fab2_lib.baseboard_fab2(sch_1):page93_i135"
				( attribute "CDS_LIB" "mstr_discrete"
					( Origin gPackager )
				)
				( attribute "CDS_LOCATION" "R1T35"
					( Origin gPackager )
				)
				( attribute "CDS_SEC" "1"
					( Origin gPackager )
				)
				( attribute "LOCATION" "R1T35"
					( Origin gFrontEnd )
				)
				( attribute "MATERIAL" "EMPTY"
					( Origin gFrontEnd )
				)
				( attribute "PACK_TYPE" "0402"
					( Origin gFrontEnd )
				)
				( attribute "PART_NUMBER" "G21497-005"
					( Origin gFrontEnd )
				)
				( attribute "PHYS_PAGE" "93"
					( Origin gFrontEnd )
				)
				( attribute "ROT" "0"
					( Origin gFrontEnd )
				)
				( attribute "SEC" "1"
					( Origin gFrontEnd )
				)
				( attribute "SEC_TYPE" "0402"
					( Origin gFrontEnd )
				)
				( attribute "TOLERANCE" "5%"
					( Origin gFrontEnd )
				)
				( attribute "VALUE" "0.0"
					( Origin gFrontEnd )
				)
				( attribute "VER" "1"
					( Origin gFrontEnd )
				)
				( attribute "WATTAGE" "1/16W"
					( Origin gFrontEnd )
				)
				( attribute "XY" "(-2225,475)"
					( Origin gFrontEnd )
				)
				( attribute "CHIPS_PART_NAME" "RES"
					( Origin gPackager )
				)
				( attribute "CDS_PART_NAME" "RES_0402-0.0,5%,1/16W,EMPTY,G2A"
					( Origin gPackager )
				)
				( objectStatus "R1T35" )
				( pin "a"
					( attribute "PN" "1"
						( Origin gPackager )
					)
					( objectStatus "R1T35.1" )
				)
				( pin "b"
					( attribute "PN" "2"
						( Origin gPackager )
					)
					( objectStatus "R1T35.2" )
				)
			)
			( gate "@baseboard_fab2_lib.baseboard_fab2(sch_1):page93_i137"
				( attribute "CDS_LIB" "mstr_discrete"
					( Origin gPackager )
				)
				( attribute "CDS_LOCATION" "R1T38"
					( Origin gPackager )
				)
				( attribute "CDS_SEC" "1"
					( Origin gPackager )
				)
				( attribute "LOCATION" "R1T38"
					( Origin gFrontEnd )
				)
				( attribute "MATERIAL" "EMPTY"
					( Origin gFrontEnd )
				)
				( attribute "PACK_TYPE" "0402"
					( Origin gFrontEnd )
				)
				( attribute "PART_NUMBER" "G21497-005"
					( Origin gFrontEnd )
				)
				( attribute "PHYS_PAGE" "93"
					( Origin gFrontEnd )
				)
				( attribute "ROT" "0"
					( Origin gFrontEnd )
				)
				( attribute "SEC" "1"
					( Origin gFrontEnd )
				)
				( attribute "SEC_TYPE" "0402"
					( Origin gFrontEnd )
				)
				( attribute "TOLERANCE" "5%"
					( Origin gFrontEnd )
				)
				( attribute "VALUE" "0.0"
					( Origin gFrontEnd )
				)
				( attribute "VER" "1"
					( Origin gFrontEnd )
				)
				( attribute "WATTAGE" "1/16W"
					( Origin gFrontEnd )
				)
				( attribute "XY" "(-2225,75)"
					( Origin gFrontEnd )
				)
				( attribute "CHIPS_PART_NAME" "RES"
					( Origin gPackager )
				)
				( attribute "CDS_PART_NAME" "RES_0402-0.0,5%,1/16W,EMPTY,G2A"
					( Origin gPackager )
				)
				( objectStatus "R1T38" )
				( pin "a"
					( attribute "PN" "1"
						( Origin gPackager )
					)
					( objectStatus "R1T38.1" )
				)
				( pin "b"
					( attribute "PN" "2"
						( Origin gPackager )
					)
					( objectStatus "R1T38.2" )
				)
			)
			( gate "@baseboard_fab2_lib.baseboard_fab2(sch_1):page93_i143"
				( attribute "BOM_COST" "PROC_SIDEBAND"
					( Origin gFrontEnd )
				)
				( attribute "CDS_LIB" "mstr_discrete"
					( Origin gPackager )
				)
				( attribute "CDS_LOCATION" "R2T72"
					( Origin gPackager )
				)
				( attribute "CDS_SEC" "1"
					( Origin gPackager )
				)
				( attribute "LOCATION" "R2T72"
					( Origin gFrontEnd )
				)
				( attribute "MATERIAL" "CHIP"
					( Origin gFrontEnd )
				)
				( attribute "PACK_TYPE" "0402"
					( Origin gFrontEnd )
				)
				( attribute "PART_NUMBER" "G21796-009"
					( Origin gFrontEnd )
				)
				( attribute "PHYS_PAGE" "93"
					( Origin gFrontEnd )
				)
				( attribute "ROOM" "PROC_SIDEBAND"
					( Origin gFrontEnd )
				)
				( attribute "ROT" "0"
					( Origin gFrontEnd )
				)
				( attribute "SEC" "1"
					( Origin gFrontEnd )
				)
				( attribute "SEC_TYPE" "0402"
					( Origin gFrontEnd )
				)
				( attribute "TOLERANCE" "1%"
					( Origin gFrontEnd )
				)
				( attribute "VALUE" "150.0"
					( Origin gFrontEnd )
				)
				( attribute "VER" "2"
					( Origin gFrontEnd )
				)
				( attribute "WATTAGE" "1/16W"
					( Origin gFrontEnd )
				)
				( attribute "XY" "(-2475,2525)"
					( Origin gFrontEnd )
				)
				( attribute "CHIPS_PART_NAME" "RES"
					( Origin gPackager )
				)
				( attribute "CDS_PART_NAME" "RES_0402-150.0,1%,1/16W,CHIP,GA"
					( Origin gPackager )
				)
				( objectStatus "R2T72" )
				( pin "a"
					( attribute "PN" "1"
						( Origin gPackager )
					)
					( objectStatus "R2T72.1" )
				)
				( pin "b"
					( attribute "PN" "2"
						( Origin gPackager )
					)
					( objectStatus "R2T72.2" )
				)
			)
			( gate "@baseboard_fab2_lib.baseboard_fab2(sch_1):page93_i144"
				( attribute "BOM_COST" "PROC_SIDEBAND"
					( Origin gFrontEnd )
				)
				( attribute "CDS_LIB" "mstr_discrete"
					( Origin gPackager )
				)
				( attribute "CDS_LOCATION" "R2T73"
					( Origin gPackager )
				)
				( attribute "CDS_SEC" "1"
					( Origin gPackager )
				)
				( attribute "LOCATION" "R2T73"
					( Origin gFrontEnd )
				)
				( attribute "MATERIAL" "CHIP"
					( Origin gFrontEnd )
				)
				( attribute "PACK_TYPE" "0402"
					( Origin gFrontEnd )
				)
				( attribute "PART_NUMBER" "G21796-009"
					( Origin gFrontEnd )
				)
				( attribute "PHYS_PAGE" "93"
					( Origin gFrontEnd )
				)
				( attribute "ROOM" "PROC_SIDEBAND"
					( Origin gFrontEnd )
				)
				( attribute "ROT" "0"
					( Origin gFrontEnd )
				)
				( attribute "SEC" "1"
					( Origin gFrontEnd )
				)
				( attribute "SEC_TYPE" "0402"
					( Origin gFrontEnd )
				)
				( attribute "TOLERANCE" "1%"
					( Origin gFrontEnd )
				)
				( attribute "VALUE" "150.0"
					( Origin gFrontEnd )
				)
				( attribute "VER" "2"
					( Origin gFrontEnd )
				)
				( attribute "WATTAGE" "1/16W"
					( Origin gFrontEnd )
				)
				( attribute "XY" "(-1900,2500)"
					( Origin gFrontEnd )
				)
				( attribute "CHIPS_PART_NAME" "RES"
					( Origin gPackager )
				)
				( attribute "CDS_PART_NAME" "RES_0402-150.0,1%,1/16W,CHIP,GA"
					( Origin gPackager )
				)
				( objectStatus "R2T73" )
				( pin "a"
					( attribute "PN" "1"
						( Origin gPackager )
					)
					( objectStatus "R2T73.1" )
				)
				( pin "b"
					( attribute "PN" "2"
						( Origin gPackager )
					)
					( objectStatus "R2T73.2" )
				)
			)
			( gate "@baseboard_fab2_lib.baseboard_fab2(sch_1):page94_i49"
				( attribute "CDS_LIB" "mstr_discrete"
					( Origin gPackager )
				)
				( attribute "CDS_LOCATION" "Q3U1"
					( Origin gPackager )
				)
				( attribute "CDS_SEC" "1"
					( Origin gPackager )
				)
				( attribute "LOCATION" "Q3U1"
					( Origin gFrontEnd )
				)
				( attribute "MATERIAL" "FET"
					( Origin gFrontEnd )
				)
				( attribute "PACK_TYPE" "SMLF"
					( Origin gFrontEnd )
				)
				( attribute "PART_NUMBER" "E40049-001"
					( Origin gFrontEnd )
				)
				( attribute "PHYS_PAGE" "94"
					( Origin gFrontEnd )
				)
				( attribute "ROOM" "PROC_SIDEBAND"
					( Origin gFrontEnd )
				)
				( attribute "ROT" "0"
					( Origin gFrontEnd )
				)
				( attribute "SEC" "1"
					( Origin gFrontEnd )
				)
				( attribute "SEC_TYPE" "SMLF"
					( Origin gFrontEnd )
				)
				( attribute "VALUE" "NTJD4001N"
					( Origin gFrontEnd )
				)
				( attribute "VER" "5"
					( Origin gFrontEnd )
				)
				( attribute "XY" "(-2150,1925)"
					( Origin gFrontEnd )
				)
				( attribute "CHIPS_PART_NAME" "FET_N_DUAL"
					( Origin gPackager )
				)
				( attribute "CDS_PART_NAME" "FET_N_DUAL_SMLF-NTJD4001N,FET,A"
					( Origin gPackager )
				)
				( objectStatus "Q3U1" )
				( pin "drain(0)"
					( attribute "PN" "6"
						( Origin gPackager )
					)
					( objectStatus "Q3U1.6" )
				)
				( pin "gate(0)"
					( attribute "PN" "2"
						( Origin gPackager )
					)
					( objectStatus "Q3U1.2" )
				)
				( pin "source(0)"
					( attribute "PN" "1"
						( Origin gPackager )
					)
					( objectStatus "Q3U1.1" )
				)
			)
			( gate "@baseboard_fab2_lib.baseboard_fab2(sch_1):page94_i51"
				( attribute "BOM_COST" "PROC_SIDEBAND"
					( Origin gFrontEnd )
				)
				( attribute "CDS_LIB" "mstr_discrete"
					( Origin gPackager )
				)
				( attribute "CDS_LOCATION" "R7G7"
					( Origin gPackager )
				)
				( attribute "CDS_SEC" "1"
					( Origin gPackager )
				)
				( attribute "LOCATION" "R7G7"
					( Origin gFrontEnd )
				)
				( attribute "MATERIAL" "CHIP"
					( Origin gFrontEnd )
				)
				( attribute "PACK_TYPE" "0402"
					( Origin gFrontEnd )
				)
				( attribute "PART_NUMBER" "G21796-072"
					( Origin gFrontEnd )
				)
				( attribute "PHYS_PAGE" "94"
					( Origin gFrontEnd )
				)
				( attribute "ROOM" "PROC_SIDEBAND"
					( Origin gFrontEnd )
				)
				( attribute "ROT" "2"
					( Origin gFrontEnd )
				)
				( attribute "SEC" "1"
					( Origin gPackager )
				)
				( attribute "TOLERANCE" "1%"
					( Origin gFrontEnd )
				)
				( attribute "VALUE" "4.75K"
					( Origin gFrontEnd )
				)
				( attribute "VER" "2"
					( Origin gFrontEnd )
				)
				( attribute "WATTAGE" "1/16W"
					( Origin gFrontEnd )
				)
				( attribute "XY" "(-2150,2375)"
					( Origin gFrontEnd )
				)
				( attribute "CHIPS_PART_NAME" "RES"
					( Origin gPackager )
				)
				( attribute "CDS_PART_NAME" "RES_0402-4.75K,1%,1/16W,CHIP,GA"
					( Origin gPackager )
				)
				( objectStatus "R7G7" )
				( pin "a"
					( attribute "PN" "1"
						( Origin gPackager )
					)
					( objectStatus "R7G7.1" )
				)
				( pin "b"
					( attribute "PN" "2"
						( Origin gPackager )
					)
					( objectStatus "R7G7.2" )
				)
			)
			( gate "@baseboard_fab2_lib.baseboard_fab2(sch_1):page94_i60"
				( attribute "CDS_LIB" "mstr_discrete"
					( Origin gPackager )
				)
				( attribute "CDS_LOCATION" "Q7E1"
					( Origin gPackager )
				)
				( attribute "CDS_SEC" "1"
					( Origin gPackager )
				)
				( attribute "LOCATION" "Q7E1"
					( Origin gFrontEnd )
				)
				( attribute "MATERIAL" "FET"
					( Origin gFrontEnd )
				)
				( attribute "PACK_TYPE" "SMLF"
					( Origin gFrontEnd )
				)
				( attribute "PART_NUMBER" "E40049-001"
					( Origin gFrontEnd )
				)
				( attribute "PHYS_PAGE" "94"
					( Origin gFrontEnd )
				)
				( attribute "ROOM" "PROC_SIDEBAND"
					( Origin gFrontEnd )
				)
				( attribute "ROT" "0"
					( Origin gFrontEnd )
				)
				( attribute "SEC" "1"
					( Origin gFrontEnd )
				)
				( attribute "SEC_TYPE" "SMLF"
					( Origin gFrontEnd )
				)
				( attribute "VALUE" "NTJD4001N"
					( Origin gFrontEnd )
				)
				( attribute "VER" "5"
					( Origin gFrontEnd )
				)
				( attribute "XY" "(-2150,825)"
					( Origin gFrontEnd )
				)
				( attribute "CHIPS_PART_NAME" "FET_N_DUAL"
					( Origin gPackager )
				)
				( attribute "CDS_PART_NAME" "FET_N_DUAL_SMLF-NTJD4001N,FET,A"
					( Origin gPackager )
				)
				( objectStatus "Q7E1" )
				( pin "drain(0)"
					( attribute "PN" "6"
						( Origin gPackager )
					)
					( objectStatus "Q7E1.6" )
				)
				( pin "gate(0)"
					( attribute "PN" "2"
						( Origin gPackager )
					)
					( objectStatus "Q7E1.2" )
				)
				( pin "source(0)"
					( attribute "PN" "1"
						( Origin gPackager )
					)
					( objectStatus "Q7E1.1" )
				)
			)
			( gate "@baseboard_fab2_lib.baseboard_fab2(sch_1):page94_i64"
				( attribute "CDS_LIB" "mstr_discrete"
					( Origin gPackager )
				)
				( attribute "CDS_LOCATION" "Q7E1"
					( Origin gPackager )
				)
				( attribute "CDS_SEC" "2"
					( Origin gPackager )
				)
				( attribute "LOCATION" "Q7E1"
					( Origin gFrontEnd )
				)
				( attribute "MATERIAL" "FET"
					( Origin gFrontEnd )
				)
				( attribute "PACK_TYPE" "SMLF"
					( Origin gFrontEnd )
				)
				( attribute "PART_NUMBER" "E40049-001"
					( Origin gFrontEnd )
				)
				( attribute "PHYS_PAGE" "94"
					( Origin gFrontEnd )
				)
				( attribute "ROOM" "PROC_SIDEBAND"
					( Origin gFrontEnd )
				)
				( attribute "ROT" "0"
					( Origin gFrontEnd )
				)
				( attribute "SEC" "2"
					( Origin gFrontEnd )
				)
				( attribute "SEC_TYPE" "SMLF"
					( Origin gFrontEnd )
				)
				( attribute "VALUE" "NTJD4001N"
					( Origin gFrontEnd )
				)
				( attribute "VER" "5"
					( Origin gFrontEnd )
				)
				( attribute "XY" "(-1425,950)"
					( Origin gFrontEnd )
				)
				( attribute "CHIPS_PART_NAME" "FET_N_DUAL"
					( Origin gPackager )
				)
				( attribute "CDS_PART_NAME" "FET_N_DUAL_SMLF-NTJD4001N,FET,A"
					( Origin gPackager )
				)
				( objectStatus "Q7E1" )
				( pin "drain(0)"
					( attribute "PN" "3"
						( Origin gPackager )
					)
					( objectStatus "Q7E1.3" )
				)
				( pin "gate(0)"
					( attribute "PN" "5"
						( Origin gPackager )
					)
					( objectStatus "Q7E1.5" )
				)
				( pin "source(0)"
					( attribute "PN" "4"
						( Origin gPackager )
					)
					( objectStatus "Q7E1.4" )
				)
			)
			( gate "@baseboard_fab2_lib.baseboard_fab2(sch_1):page94_i66"
				( attribute "BOM_COST" "PROC_SIDEBAND"
					( Origin gFrontEnd )
				)
				( attribute "CDS_LIB" "mstr_discrete"
					( Origin gPackager )
				)
				( attribute "CDS_LOCATION" "R3R4"
					( Origin gPackager )
				)
				( attribute "CDS_SEC" "1"
					( Origin gPackager )
				)
				( attribute "LOCATION" "R3R4"
					( Origin gFrontEnd )
				)
				( attribute "MATERIAL" "CHIP"
					( Origin gFrontEnd )
				)
				( attribute "PACK_TYPE" "0402"
					( Origin gFrontEnd )
				)
				( attribute "PART_NUMBER" "G21796-072"
					( Origin gFrontEnd )
				)
				( attribute "PHYS_PAGE" "94"
					( Origin gFrontEnd )
				)
				( attribute "ROOM" "PROC_SIDEBAND"
					( Origin gFrontEnd )
				)
				( attribute "ROT" "2"
					( Origin gFrontEnd )
				)
				( attribute "SEC" "1"
					( Origin gPackager )
				)
				( attribute "TOLERANCE" "1%"
					( Origin gFrontEnd )
				)
				( attribute "VALUE" "4.75K"
					( Origin gFrontEnd )
				)
				( attribute "VER" "2"
					( Origin gFrontEnd )
				)
				( attribute "WATTAGE" "1/16W"
					( Origin gFrontEnd )
				)
				( attribute "XY" "(-2150,1275)"
					( Origin gFrontEnd )
				)
				( attribute "CHIPS_PART_NAME" "RES"
					( Origin gPackager )
				)
				( attribute "CDS_PART_NAME" "RES_0402-4.75K,1%,1/16W,CHIP,GA"
					( Origin gPackager )
				)
				( objectStatus "R3R4" )
				( pin "a"
					( attribute "PN" "1"
						( Origin gPackager )
					)
					( objectStatus "R3R4.1" )
				)
				( pin "b"
					( attribute "PN" "2"
						( Origin gPackager )
					)
					( objectStatus "R3R4.2" )
				)
			)
			( gate "@baseboard_fab2_lib.baseboard_fab2(sch_1):page94_i69"
				( attribute "CDS_LIB" "mstr_discrete"
					( Origin gPackager )
				)
				( attribute "CDS_LOCATION" "Q7E2"
					( Origin gPackager )
				)
				( attribute "CDS_SEC" "1"
					( Origin gPackager )
				)
				( attribute "LOCATION" "Q7E2"
					( Origin gFrontEnd )
				)
				( attribute "MATERIAL" "FET"
					( Origin gFrontEnd )
				)
				( attribute "PACK_TYPE" "SMLF"
					( Origin gFrontEnd )
				)
				( attribute "PART_NUMBER" "E40049-001"
					( Origin gFrontEnd )
				)
				( attribute "PHYS_PAGE" "94"
					( Origin gFrontEnd )
				)
				( attribute "ROOM" "PROC_SIDEBAND"
					( Origin gFrontEnd )
				)
				( attribute "ROT" "0"
					( Origin gFrontEnd )
				)
				( attribute "SEC" "1"
					( Origin gFrontEnd )
				)
				( attribute "SEC_TYPE" "SMLF"
					( Origin gFrontEnd )
				)
				( attribute "VALUE" "NTJD4001N"
					( Origin gFrontEnd )
				)
				( attribute "VER" "5"
					( Origin gFrontEnd )
				)
				( attribute "XY" "(1175,1975)"
					( Origin gFrontEnd )
				)
				( attribute "CHIPS_PART_NAME" "FET_N_DUAL"
					( Origin gPackager )
				)
				( attribute "CDS_PART_NAME" "FET_N_DUAL_SMLF-NTJD4001N,FET,A"
					( Origin gPackager )
				)
				( objectStatus "Q7E2" )
				( pin "drain(0)"
					( attribute "PN" "6"
						( Origin gPackager )
					)
					( objectStatus "Q7E2.6" )
				)
				( pin "gate(0)"
					( attribute "PN" "2"
						( Origin gPackager )
					)
					( objectStatus "Q7E2.2" )
				)
				( pin "source(0)"
					( attribute "PN" "1"
						( Origin gPackager )
					)
					( objectStatus "Q7E2.1" )
				)
			)
			( gate "@baseboard_fab2_lib.baseboard_fab2(sch_1):page94_i75"
				( attribute "CDS_LIB" "mstr_discrete"
					( Origin gPackager )
				)
				( attribute "CDS_LOCATION" "Q7E2"
					( Origin gPackager )
				)
				( attribute "CDS_SEC" "2"
					( Origin gPackager )
				)
				( attribute "LOCATION" "Q7E2"
					( Origin gFrontEnd )
				)
				( attribute "MATERIAL" "FET"
					( Origin gFrontEnd )
				)
				( attribute "PACK_TYPE" "SMLF"
					( Origin gFrontEnd )
				)
				( attribute "PART_NUMBER" "E40049-001"
					( Origin gFrontEnd )
				)
				( attribute "PHYS_PAGE" "94"
					( Origin gFrontEnd )
				)
				( attribute "ROOM" "PROC_SIDEBAND"
					( Origin gFrontEnd )
				)
				( attribute "ROT" "0"
					( Origin gFrontEnd )
				)
				( attribute "SEC" "2"
					( Origin gFrontEnd )
				)
				( attribute "SEC_TYPE" "SMLF"
					( Origin gFrontEnd )
				)
				( attribute "VALUE" "NTJD4001N"
					( Origin gFrontEnd )
				)
				( attribute "VER" "5"
					( Origin gFrontEnd )
				)
				( attribute "XY" "(1900,2100)"
					( Origin gFrontEnd )
				)
				( attribute "CHIPS_PART_NAME" "FET_N_DUAL"
					( Origin gPackager )
				)
				( attribute "CDS_PART_NAME" "FET_N_DUAL_SMLF-NTJD4001N,FET,A"
					( Origin gPackager )
				)
				( objectStatus "Q7E2" )
				( pin "drain(0)"
					( attribute "PN" "3"
						( Origin gPackager )
					)
					( objectStatus "Q7E2.3" )
				)
				( pin "gate(0)"
					( attribute "PN" "5"
						( Origin gPackager )
					)
					( objectStatus "Q7E2.5" )
				)
				( pin "source(0)"
					( attribute "PN" "4"
						( Origin gPackager )
					)
					( objectStatus "Q7E2.4" )
				)
			)
			( gate "@baseboard_fab2_lib.baseboard_fab2(sch_1):page94_i77"
				( attribute "CDS_LIB" "mstr_discrete"
					( Origin gPackager )
				)
				( attribute "CDS_LOCATION" "Q4B1"
					( Origin gPackager )
				)
				( attribute "CDS_SEC" "2"
					( Origin gPackager )
				)
				( attribute "LOCATION" "Q4B1"
					( Origin gFrontEnd )
				)
				( attribute "MATERIAL" "FET"
					( Origin gFrontEnd )
				)
				( attribute "PACK_TYPE" "SMLF"
					( Origin gFrontEnd )
				)
				( attribute "PART_NUMBER" "E40049-001"
					( Origin gFrontEnd )
				)
				( attribute "PHYS_PAGE" "94"
					( Origin gFrontEnd )
				)
				( attribute "ROOM" "PROC_SIDEBAND"
					( Origin gFrontEnd )
				)
				( attribute "ROT" "0"
					( Origin gFrontEnd )
				)
				( attribute "SEC" "2"
					( Origin gFrontEnd )
				)
				( attribute "SEC_TYPE" "SMLF"
					( Origin gFrontEnd )
				)
				( attribute "VALUE" "NTJD4001N"
					( Origin gFrontEnd )
				)
				( attribute "VER" "5"
					( Origin gFrontEnd )
				)
				( attribute "XY" "(1900,1000)"
					( Origin gFrontEnd )
				)
				( attribute "CHIPS_PART_NAME" "FET_N_DUAL"
					( Origin gPackager )
				)
				( attribute "CDS_PART_NAME" "FET_N_DUAL_SMLF-NTJD4001N,FET,A"
					( Origin gPackager )
				)
				( objectStatus "Q4B1" )
				( pin "drain(0)"
					( attribute "PN" "3"
						( Origin gPackager )
					)
					( objectStatus "Q4B1.3" )
				)
				( pin "gate(0)"
					( attribute "PN" "5"
						( Origin gPackager )
					)
					( objectStatus "Q4B1.5" )
				)
				( pin "source(0)"
					( attribute "PN" "4"
						( Origin gPackager )
					)
					( objectStatus "Q4B1.4" )
				)
			)
			( gate "@baseboard_fab2_lib.baseboard_fab2(sch_1):page94_i79"
				( attribute "BOM_COST" "PROC_SIDEBAND"
					( Origin gFrontEnd )
				)
				( attribute "CDS_LIB" "mstr_discrete"
					( Origin gPackager )
				)
				( attribute "CDS_LOCATION" "R3R10"
					( Origin gPackager )
				)
				( attribute "CDS_SEC" "1"
					( Origin gPackager )
				)
				( attribute "LOCATION" "R3R10"
					( Origin gFrontEnd )
				)
				( attribute "MATERIAL" "CHIP"
					( Origin gFrontEnd )
				)
				( attribute "PACK_TYPE" "0402"
					( Origin gFrontEnd )
				)
				( attribute "PART_NUMBER" "G21796-072"
					( Origin gFrontEnd )
				)
				( attribute "PHYS_PAGE" "94"
					( Origin gFrontEnd )
				)
				( attribute "ROOM" "PROC_SIDEBAND"
					( Origin gFrontEnd )
				)
				( attribute "ROT" "2"
					( Origin gFrontEnd )
				)
				( attribute "SEC" "1"
					( Origin gPackager )
				)
				( attribute "TOLERANCE" "1%"
					( Origin gFrontEnd )
				)
				( attribute "VALUE" "4.75K"
					( Origin gFrontEnd )
				)
				( attribute "VER" "2"
					( Origin gFrontEnd )
				)
				( attribute "WATTAGE" "1/16W"
					( Origin gFrontEnd )
				)
				( attribute "XY" "(1175,2425)"
					( Origin gFrontEnd )
				)
				( attribute "CHIPS_PART_NAME" "RES"
					( Origin gPackager )
				)
				( attribute "CDS_PART_NAME" "RES_0402-4.75K,1%,1/16W,CHIP,GA"
					( Origin gPackager )
				)
				( objectStatus "R3R10" )
				( pin "a"
					( attribute "PN" "1"
						( Origin gPackager )
					)
					( objectStatus "R3R10.1" )
				)
				( pin "b"
					( attribute "PN" "2"
						( Origin gPackager )
					)
					( objectStatus "R3R10.2" )
				)
			)
			( gate "@baseboard_fab2_lib.baseboard_fab2(sch_1):page94_i82"
				( attribute "BOM_COST" "PROC_SIDEBAND"
					( Origin gFrontEnd )
				)
				( attribute "CDS_LIB" "mstr_discrete"
					( Origin gPackager )
				)
				( attribute "CDS_LOCATION" "R6M4"
					( Origin gPackager )
				)
				( attribute "CDS_SEC" "1"
					( Origin gPackager )
				)
				( attribute "LOCATION" "R6M4"
					( Origin gFrontEnd )
				)
				( attribute "MATERIAL" "CHIP"
					( Origin gFrontEnd )
				)
				( attribute "PACK_TYPE" "0402"
					( Origin gFrontEnd )
				)
				( attribute "PART_NUMBER" "G21796-072"
					( Origin gFrontEnd )
				)
				( attribute "PHYS_PAGE" "94"
					( Origin gFrontEnd )
				)
				( attribute "ROOM" "PROC_SIDEBAND"
					( Origin gFrontEnd )
				)
				( attribute "ROT" "2"
					( Origin gFrontEnd )
				)
				( attribute "SEC" "1"
					( Origin gPackager )
				)
				( attribute "TOLERANCE" "1%"
					( Origin gFrontEnd )
				)
				( attribute "VALUE" "4.75K"
					( Origin gFrontEnd )
				)
				( attribute "VER" "2"
					( Origin gFrontEnd )
				)
				( attribute "WATTAGE" "1/16W"
					( Origin gFrontEnd )
				)
				( attribute "XY" "(1175,1325)"
					( Origin gFrontEnd )
				)
				( attribute "CHIPS_PART_NAME" "RES"
					( Origin gPackager )
				)
				( attribute "CDS_PART_NAME" "RES_0402-4.75K,1%,1/16W,CHIP,GA"
					( Origin gPackager )
				)
				( objectStatus "R6M4" )
				( pin "a"
					( attribute "PN" "1"
						( Origin gPackager )
					)
					( objectStatus "R6M4.1" )
				)
				( pin "b"
					( attribute "PN" "2"
						( Origin gPackager )
					)
					( objectStatus "R6M4.2" )
				)
			)
			( gate "@baseboard_fab2_lib.baseboard_fab2(sch_1):page94_i84"
				( attribute "CDS_LIB" "mstr_discrete"
					( Origin gPackager )
				)
				( attribute "CDS_LOCATION" "Q4B1"
					( Origin gPackager )
				)
				( attribute "CDS_SEC" "1"
					( Origin gPackager )
				)
				( attribute "LOCATION" "Q4B1"
					( Origin gFrontEnd )
				)
				( attribute "MATERIAL" "FET"
					( Origin gFrontEnd )
				)
				( attribute "PACK_TYPE" "SMLF"
					( Origin gFrontEnd )
				)
				( attribute "PART_NUMBER" "E40049-001"
					( Origin gFrontEnd )
				)
				( attribute "PHYS_PAGE" "94"
					( Origin gFrontEnd )
				)
				( attribute "ROOM" "PROC_SIDEBAND"
					( Origin gFrontEnd )
				)
				( attribute "ROT" "0"
					( Origin gFrontEnd )
				)
				( attribute "SEC" "1"
					( Origin gFrontEnd )
				)
				( attribute "SEC_TYPE" "SMLF"
					( Origin gFrontEnd )
				)
				( attribute "VALUE" "NTJD4001N"
					( Origin gFrontEnd )
				)
				( attribute "VER" "5"
					( Origin gFrontEnd )
				)
				( attribute "XY" "(1175,875)"
					( Origin gFrontEnd )
				)
				( attribute "CHIPS_PART_NAME" "FET_N_DUAL"
					( Origin gPackager )
				)
				( attribute "CDS_PART_NAME" "FET_N_DUAL_SMLF-NTJD4001N,FET,A"
					( Origin gPackager )
				)
				( objectStatus "Q4B1" )
				( pin "drain(0)"
					( attribute "PN" "6"
						( Origin gPackager )
					)
					( objectStatus "Q4B1.6" )
				)
				( pin "gate(0)"
					( attribute "PN" "2"
						( Origin gPackager )
					)
					( objectStatus "Q4B1.2" )
				)
				( pin "source(0)"
					( attribute "PN" "1"
						( Origin gPackager )
					)
					( objectStatus "Q4B1.1" )
				)
			)
			( gate "@baseboard_fab2_lib.baseboard_fab2(sch_1):page94_i89"
				( attribute "CDS_LIB" "mstr_discrete"
					( Origin gPackager )
				)
				( attribute "CDS_LOCATION" "Q3U1"
					( Origin gPackager )
				)
				( attribute "CDS_SEC" "2"
					( Origin gPackager )
				)
				( attribute "LOCATION" "Q3U1"
					( Origin gFrontEnd )
				)
				( attribute "MATERIAL" "FET"
					( Origin gFrontEnd )
				)
				( attribute "PACK_TYPE" "SMLF"
					( Origin gFrontEnd )
				)
				( attribute "PART_NUMBER" "E40049-001"
					( Origin gFrontEnd )
				)
				( attribute "PHYS_PAGE" "94"
					( Origin gFrontEnd )
				)
				( attribute "ROOM" "PROC_SIDEBAND"
					( Origin gFrontEnd )
				)
				( attribute "ROT" "0"
					( Origin gFrontEnd )
				)
				( attribute "SEC" "2"
					( Origin gFrontEnd )
				)
				( attribute "SEC_TYPE" "SMLF"
					( Origin gFrontEnd )
				)
				( attribute "VALUE" "NTJD4001N"
					( Origin gFrontEnd )
				)
				( attribute "VER" "5"
					( Origin gFrontEnd )
				)
				( attribute "XY" "(-1425,2050)"
					( Origin gFrontEnd )
				)
				( attribute "CHIPS_PART_NAME" "FET_N_DUAL"
					( Origin gPackager )
				)
				( attribute "CDS_PART_NAME" "FET_N_DUAL_SMLF-NTJD4001N,FET,A"
					( Origin gPackager )
				)
				( objectStatus "Q3U1" )
				( pin "drain(0)"
					( attribute "PN" "3"
						( Origin gPackager )
					)
					( objectStatus "Q3U1.3" )
				)
				( pin "gate(0)"
					( attribute "PN" "5"
						( Origin gPackager )
					)
					( objectStatus "Q3U1.5" )
				)
				( pin "source(0)"
					( attribute "PN" "4"
						( Origin gPackager )
					)
					( objectStatus "Q3U1.4" )
				)
			)
			( gate "@baseboard_fab2_lib.baseboard_fab2(sch_1):page94_i91"
				( attribute "BOM_COST" "PROC_SIDEBAND"
					( Origin gFrontEnd )
				)
				( attribute "CDS_LIB" "mstr_discrete"
					( Origin gPackager )
				)
				( attribute "CDS_LOCATION" "R4U1"
					( Origin gPackager )
				)
				( attribute "CDS_SEC" "1"
					( Origin gPackager )
				)
				( attribute "LOCATION" "R4U1"
					( Origin gFrontEnd )
				)
				( attribute "MATERIAL" "CHIP"
					( Origin gFrontEnd )
				)
				( attribute "PACK_TYPE" "0402"
					( Origin gFrontEnd )
				)
				( attribute "PART_NUMBER" "G21796-072"
					( Origin gFrontEnd )
				)
				( attribute "PHYS_PAGE" "94"
					( Origin gFrontEnd )
				)
				( attribute "ROOM" "PROC_SIDEBAND"
					( Origin gFrontEnd )
				)
				( attribute "ROT" "2"
					( Origin gFrontEnd )
				)
				( attribute "SEC" "1"
					( Origin gFrontEnd )
				)
				( attribute "SEC_TYPE" "0402"
					( Origin gFrontEnd )
				)
				( attribute "TOLERANCE" "1%"
					( Origin gFrontEnd )
				)
				( attribute "VALUE" "4.75K"
					( Origin gFrontEnd )
				)
				( attribute "VER" "2"
					( Origin gFrontEnd )
				)
				( attribute "WATTAGE" "1/16W"
					( Origin gFrontEnd )
				)
				( attribute "XY" "(1400,4400)"
					( Origin gFrontEnd )
				)
				( attribute "CHIPS_PART_NAME" "RES"
					( Origin gPackager )
				)
				( attribute "CDS_PART_NAME" "RES_0402-4.75K,1%,1/16W,CHIP,GA"
					( Origin gPackager )
				)
				( objectStatus "R4U1" )
				( pin "a"
					( attribute "PN" "1"
						( Origin gPackager )
					)
					( objectStatus "R4U1.1" )
				)
				( pin "b"
					( attribute "PN" "2"
						( Origin gPackager )
					)
					( objectStatus "R4U1.2" )
				)
			)
			( gate "@baseboard_fab2_lib.baseboard_fab2(sch_1):page94_i94"
				( attribute "BOM_COST" "PROC_SIDEBAND"
					( Origin gFrontEnd )
				)
				( attribute "CDS_LIB" "mstr_discrete"
					( Origin gPackager )
				)
				( attribute "CDS_LOCATION" "R4U3"
					( Origin gPackager )
				)
				( attribute "CDS_SEC" "1"
					( Origin gPackager )
				)
				( attribute "LOCATION" "R4U3"
					( Origin gFrontEnd )
				)
				( attribute "MATERIAL" "CHIP"
					( Origin gFrontEnd )
				)
				( attribute "PACK_TYPE" "0402"
					( Origin gFrontEnd )
				)
				( attribute "PART_NUMBER" "G21796-072"
					( Origin gFrontEnd )
				)
				( attribute "PHYS_PAGE" "94"
					( Origin gFrontEnd )
				)
				( attribute "ROOM" "PROC_SIDEBAND"
					( Origin gFrontEnd )
				)
				( attribute "ROT" "2"
					( Origin gFrontEnd )
				)
				( attribute "SEC" "1"
					( Origin gFrontEnd )
				)
				( attribute "SEC_TYPE" "0402"
					( Origin gFrontEnd )
				)
				( attribute "TOLERANCE" "1%"
					( Origin gFrontEnd )
				)
				( attribute "VALUE" "4.75K"
					( Origin gFrontEnd )
				)
				( attribute "VER" "2"
					( Origin gFrontEnd )
				)
				( attribute "WATTAGE" "1/16W"
					( Origin gFrontEnd )
				)
				( attribute "XY" "(175,4075)"
					( Origin gFrontEnd )
				)
				( attribute "CHIPS_PART_NAME" "RES"
					( Origin gPackager )
				)
				( attribute "CDS_PART_NAME" "RES_0402-4.75K,1%,1/16W,CHIP,GA"
					( Origin gPackager )
				)
				( objectStatus "R4U3" )
				( pin "a"
					( attribute "PN" "1"
						( Origin gPackager )
					)
					( objectStatus "R4U3.1" )
				)
				( pin "b"
					( attribute "PN" "2"
						( Origin gPackager )
					)
					( objectStatus "R4U3.2" )
				)
			)
			( gate "@baseboard_fab2_lib.baseboard_fab2(sch_1):page94_i98"
				( attribute "BOM_COST" "PROC_SIDEBAND"
					( Origin gFrontEnd )
				)
				( attribute "CDS_LIB" "mstr_discrete"
					( Origin gPackager )
				)
				( attribute "CDS_LOCATION" "Q4U1"
					( Origin gPackager )
				)
				( attribute "CDS_SEC" "1"
					( Origin gPackager )
				)
				( attribute "LOCATION" "Q4U1"
					( Origin gFrontEnd )
				)
				( attribute "MATERIAL" "FET"
					( Origin gFrontEnd )
				)
				( attribute "PACK_TYPE" "SMLF"
					( Origin gFrontEnd )
				)
				( attribute "PART_NUMBER" "E40049-001"
					( Origin gFrontEnd )
				)
				( attribute "PHYS_PAGE" "94"
					( Origin gFrontEnd )
				)
				( attribute "ROOM" "PROC_SIDEBAND"
					( Origin gFrontEnd )
				)
				( attribute "ROT" "0"
					( Origin gFrontEnd )
				)
				( attribute "SEC" "1"
					( Origin gFrontEnd )
				)
				( attribute "SEC_TYPE" "SMLF"
					( Origin gFrontEnd )
				)
				( attribute "VALUE" "NTJD4001N"
					( Origin gFrontEnd )
				)
				( attribute "VER" "5"
					( Origin gFrontEnd )
				)
				( attribute "XY" "(175,3525)"
					( Origin gFrontEnd )
				)
				( attribute "CHIPS_PART_NAME" "FET_N_DUAL"
					( Origin gPackager )
				)
				( attribute "CDS_PART_NAME" "FET_N_DUAL_SMLF-NTJD4001N,FET,A"
					( Origin gPackager )
				)
				( objectStatus "Q4U1" )
				( pin "drain(0)"
					( attribute "PN" "6"
						( Origin gPackager )
					)
					( objectStatus "Q4U1.6" )
				)
				( pin "gate(0)"
					( attribute "PN" "2"
						( Origin gPackager )
					)
					( objectStatus "Q4U1.2" )
				)
				( pin "source(0)"
					( attribute "PN" "1"
						( Origin gPackager )
					)
					( objectStatus "Q4U1.1" )
				)
			)
			( gate "@baseboard_fab2_lib.baseboard_fab2(sch_1):page94_i100"
				( attribute "BOM_COST" "PROC_SIDEBAND"
					( Origin gFrontEnd )
				)
				( attribute "CDS_LIB" "mstr_discrete"
					( Origin gPackager )
				)
				( attribute "CDS_LOCATION" "R4U2"
					( Origin gPackager )
				)
				( attribute "CDS_SEC" "1"
					( Origin gPackager )
				)
				( attribute "LOCATION" "R4U2"
					( Origin gFrontEnd )
				)
				( attribute "MATERIAL" "CHIP"
					( Origin gFrontEnd )
				)
				( attribute "PACK_TYPE" "0402"
					( Origin gFrontEnd )
				)
				( attribute "PART_NUMBER" "G21796-112"
					( Origin gFrontEnd )
				)
				( attribute "PHYS_PAGE" "94"
					( Origin gFrontEnd )
				)
				( attribute "ROOM" "PROC_SIDEBAND"
					( Origin gFrontEnd )
				)
				( attribute "ROT" "2"
					( Origin gFrontEnd )
				)
				( attribute "SEC" "1"
					( Origin gFrontEnd )
				)
				( attribute "SEC_TYPE" "0402"
					( Origin gFrontEnd )
				)
				( attribute "TOLERANCE" "1%"
					( Origin gFrontEnd )
				)
				( attribute "VALUE" "2.21K"
					( Origin gFrontEnd )
				)
				( attribute "VER" "2"
					( Origin gFrontEnd )
				)
				( attribute "WATTAGE" "1/16W"
					( Origin gFrontEnd )
				)
				( attribute "XY" "(-300,3650)"
					( Origin gFrontEnd )
				)
				( attribute "CHIPS_PART_NAME" "RES"
					( Origin gPackager )
				)
				( attribute "CDS_PART_NAME" "RES_0402-2.21K,1%,1/16W,CHIP,GA"
					( Origin gPackager )
				)
				( objectStatus "R4U2" )
				( pin "a"
					( attribute "PN" "1"
						( Origin gPackager )
					)
					( objectStatus "R4U2.1" )
				)
				( pin "b"
					( attribute "PN" "2"
						( Origin gPackager )
					)
					( objectStatus "R4U2.2" )
				)
			)
			( gate "@baseboard_fab2_lib.baseboard_fab2(sch_1):page94_i102"
				( attribute "BOM_COST" "PROC_SIDEBAND"
					( Origin gFrontEnd )
				)
				( attribute "CDS_LIB" "mstr_discrete"
					( Origin gPackager )
				)
				( attribute "CDS_LOCATION" "Q4U1"
					( Origin gPackager )
				)
				( attribute "CDS_SEC" "2"
					( Origin gPackager )
				)
				( attribute "LOCATION" "Q4U1"
					( Origin gFrontEnd )
				)
				( attribute "MATERIAL" "FET"
					( Origin gFrontEnd )
				)
				( attribute "PACK_TYPE" "SMLF"
					( Origin gFrontEnd )
				)
				( attribute "PART_NUMBER" "E40049-001"
					( Origin gFrontEnd )
				)
				( attribute "PHYS_PAGE" "94"
					( Origin gFrontEnd )
				)
				( attribute "ROOM" "PROC_SIDEBAND"
					( Origin gFrontEnd )
				)
				( attribute "ROT" "0"
					( Origin gFrontEnd )
				)
				( attribute "SEC" "2"
					( Origin gFrontEnd )
				)
				( attribute "SEC_TYPE" "SMLF"
					( Origin gFrontEnd )
				)
				( attribute "VALUE" "NTJD4001N"
					( Origin gFrontEnd )
				)
				( attribute "VER" "5"
					( Origin gFrontEnd )
				)
				( attribute "XY" "(1400,3950)"
					( Origin gFrontEnd )
				)
				( attribute "CHIPS_PART_NAME" "FET_N_DUAL"
					( Origin gPackager )
				)
				( attribute "CDS_PART_NAME" "FET_N_DUAL_SMLF-NTJD4001N,FET,A"
					( Origin gPackager )
				)
				( objectStatus "Q4U1" )
				( pin "drain(0)"
					( attribute "PN" "3"
						( Origin gPackager )
					)
					( objectStatus "Q4U1.3" )
				)
				( pin "gate(0)"
					( attribute "PN" "5"
						( Origin gPackager )
					)
					( objectStatus "Q4U1.5" )
				)
				( pin "source(0)"
					( attribute "PN" "4"
						( Origin gPackager )
					)
					( objectStatus "Q4U1.4" )
				)
			)
			( gate "@baseboard_fab2_lib.baseboard_fab2(sch_1):page94_i104"
				( attribute "CDS_LIB" "mstr_discrete"
					( Origin gPackager )
				)
				( attribute "CDS_LOCATION" "R4U4"
					( Origin gPackager )
				)
				( attribute "CDS_SEC" "1"
					( Origin gPackager )
				)
				( attribute "LOCATION" "R4U4"
					( Origin gFrontEnd )
				)
				( attribute "MATERIAL" "CHIP"
					( Origin gFrontEnd )
				)
				( attribute "PACK_TYPE" "0402"
					( Origin gFrontEnd )
				)
				( attribute "PART_NUMBER" "G21497-023"
					( Origin gFrontEnd )
				)
				( attribute "PHYS_PAGE" "94"
					( Origin gFrontEnd )
				)
				( attribute "ROT" "0"
					( Origin gFrontEnd )
				)
				( attribute "SEC" "1"
					( Origin gFrontEnd )
				)
				( attribute "SEC_TYPE" "0402"
					( Origin gFrontEnd )
				)
				( attribute "TOLERANCE" "5%"
					( Origin gFrontEnd )
				)
				( attribute "VALUE" "33.0K"
					( Origin gFrontEnd )
				)
				( attribute "VER" "2"
					( Origin gFrontEnd )
				)
				( attribute "WATTAGE" "1/16W"
					( Origin gFrontEnd )
				)
				( attribute "XY" "(750,3575)"
					( Origin gFrontEnd )
				)
				( attribute "CHIPS_PART_NAME" "RES"
					( Origin gPackager )
				)
				( attribute "CDS_PART_NAME" "RES_0402-33.0K,5%,1/16W,CHIP,GA"
					( Origin gPackager )
				)
				( objectStatus "R4U4" )
				( pin "a"
					( attribute "PN" "1"
						( Origin gPackager )
					)
					( objectStatus "R4U4.1" )
				)
				( pin "b"
					( attribute "PN" "2"
						( Origin gPackager )
					)
					( objectStatus "R4U4.2" )
				)
			)
			( gate "@baseboard_fab2_lib.baseboard_fab2(sch_1):page95_i28"
				( attribute "BOM_COST" "PROC_SIDEBAND"
					( Origin gFrontEnd )
				)
				( attribute "CDS_LIB" "mstr_discrete"
					( Origin gPackager )
				)
				( attribute "CDS_LOCATION" "Q2U1"
					( Origin gPackager )
				)
				( attribute "CDS_SEC" "1"
					( Origin gPackager )
				)
				( attribute "LOCATION" "Q2U1"
					( Origin gFrontEnd )
				)
				( attribute "MATERIAL" "FET"
					( Origin gFrontEnd )
				)
				( attribute "PACK_TYPE" "SMLF"
					( Origin gFrontEnd )
				)
				( attribute "PART_NUMBER" "E40049-001"
					( Origin gFrontEnd )
				)
				( attribute "PHYS_PAGE" "95"
					( Origin gFrontEnd )
				)
				( attribute "ROOM" "PROC_SIDEBAND"
					( Origin gFrontEnd )
				)
				( attribute "ROT" "0"
					( Origin gFrontEnd )
				)
				( attribute "SEC" "1"
					( Origin gFrontEnd )
				)
				( attribute "SEC_TYPE" "SMLF"
					( Origin gFrontEnd )
				)
				( attribute "VALUE" "NTJD4001N"
					( Origin gFrontEnd )
				)
				( attribute "VER" "5"
					( Origin gFrontEnd )
				)
				( attribute "XY" "(-3100,2625)"
					( Origin gFrontEnd )
				)
				( attribute "CHIPS_PART_NAME" "FET_N_DUAL"
					( Origin gPackager )
				)
				( attribute "CDS_PART_NAME" "FET_N_DUAL_SMLF-NTJD4001N,FET,A"
					( Origin gPackager )
				)
				( objectStatus "Q2U1" )
				( pin "drain(0)"
					( attribute "PN" "6"
						( Origin gPackager )
					)
					( objectStatus "Q2U1.6" )
				)
				( pin "gate(0)"
					( attribute "PN" "2"
						( Origin gPackager )
					)
					( objectStatus "Q2U1.2" )
				)
				( pin "source(0)"
					( attribute "PN" "1"
						( Origin gPackager )
					)
					( objectStatus "Q2U1.1" )
				)
			)
			( gate "@baseboard_fab2_lib.baseboard_fab2(sch_1):page95_i32"
				( attribute "BOM_COST" "PROC_SIDEBAND"
					( Origin gFrontEnd )
				)
				( attribute "CDS_LIB" "mstr_discrete"
					( Origin gPackager )
				)
				( attribute "CDS_LOCATION" "Q4B2"
					( Origin gPackager )
				)
				( attribute "CDS_SEC" "1"
					( Origin gPackager )
				)
				( attribute "LOCATION" "Q4B2"
					( Origin gFrontEnd )
				)
				( attribute "MATERIAL" "FET"
					( Origin gFrontEnd )
				)
				( attribute "PACK_TYPE" "SMLF"
					( Origin gFrontEnd )
				)
				( attribute "PART_NUMBER" "E40049-001"
					( Origin gFrontEnd )
				)
				( attribute "PHYS_PAGE" "95"
					( Origin gFrontEnd )
				)
				( attribute "ROOM" "PROC_SIDEBAND"
					( Origin gFrontEnd )
				)
				( attribute "ROT" "0"
					( Origin gFrontEnd )
				)
				( attribute "SEC" "1"
					( Origin gFrontEnd )
				)
				( attribute "SEC_TYPE" "SMLF"
					( Origin gFrontEnd )
				)
				( attribute "VALUE" "NTJD4001N"
					( Origin gFrontEnd )
				)
				( attribute "VER" "5"
					( Origin gFrontEnd )
				)
				( attribute "XY" "(-3100,1300)"
					( Origin gFrontEnd )
				)
				( attribute "CHIPS_PART_NAME" "FET_N_DUAL"
					( Origin gPackager )
				)
				( attribute "CDS_PART_NAME" "FET_N_DUAL_SMLF-NTJD4001N,FET,A"
					( Origin gPackager )
				)
				( objectStatus "Q4B2" )
				( pin "drain(0)"
					( attribute "PN" "6"
						( Origin gPackager )
					)
					( objectStatus "Q4B2.6" )
				)
				( pin "gate(0)"
					( attribute "PN" "2"
						( Origin gPackager )
					)
					( objectStatus "Q4B2.2" )
				)
				( pin "source(0)"
					( attribute "PN" "1"
						( Origin gPackager )
					)
					( objectStatus "Q4B2.1" )
				)
			)
			( gate "@baseboard_fab2_lib.baseboard_fab2(sch_1):page95_i33"
				( attribute "BOM_COST" "PROC_SIDEBAND"
					( Origin gFrontEnd )
				)
				( attribute "CDS_LIB" "mstr_discrete"
					( Origin gPackager )
				)
				( attribute "CDS_LOCATION" "Q4B2"
					( Origin gPackager )
				)
				( attribute "CDS_SEC" "2"
					( Origin gPackager )
				)
				( attribute "LOCATION" "Q4B2"
					( Origin gFrontEnd )
				)
				( attribute "MATERIAL" "FET"
					( Origin gFrontEnd )
				)
				( attribute "PACK_TYPE" "SMLF"
					( Origin gFrontEnd )
				)
				( attribute "PART_NUMBER" "E40049-001"
					( Origin gFrontEnd )
				)
				( attribute "PHYS_PAGE" "95"
					( Origin gFrontEnd )
				)
				( attribute "ROOM" "PROC_SIDEBAND"
					( Origin gFrontEnd )
				)
				( attribute "ROT" "0"
					( Origin gFrontEnd )
				)
				( attribute "SEC" "2"
					( Origin gFrontEnd )
				)
				( attribute "SEC_TYPE" "SMLF"
					( Origin gFrontEnd )
				)
				( attribute "VALUE" "NTJD4001N"
					( Origin gFrontEnd )
				)
				( attribute "VER" "5"
					( Origin gFrontEnd )
				)
				( attribute "XY" "(-3100,700)"
					( Origin gFrontEnd )
				)
				( attribute "CHIPS_PART_NAME" "FET_N_DUAL"
					( Origin gPackager )
				)
				( attribute "CDS_PART_NAME" "FET_N_DUAL_SMLF-NTJD4001N,FET,A"
					( Origin gPackager )
				)
				( objectStatus "Q4B2" )
				( pin "drain(0)"
					( attribute "PN" "3"
						( Origin gPackager )
					)
					( objectStatus "Q4B2.3" )
				)
				( pin "gate(0)"
					( attribute "PN" "5"
						( Origin gPackager )
					)
					( objectStatus "Q4B2.5" )
				)
				( pin "source(0)"
					( attribute "PN" "4"
						( Origin gPackager )
					)
					( objectStatus "Q4B2.4" )
				)
			)
			( gate "@baseboard_fab2_lib.baseboard_fab2(sch_1):page95_i51"
				( attribute "BOM_COST" "PROC_SIDEBAND"
					( Origin gFrontEnd )
				)
				( attribute "CDS_LIB" "mstr_discrete"
					( Origin gPackager )
				)
				( attribute "CDS_LOCATION" "Q7E3"
					( Origin gPackager )
				)
				( attribute "CDS_SEC" "2"
					( Origin gPackager )
				)
				( attribute "LOCATION" "Q7E3"
					( Origin gFrontEnd )
				)
				( attribute "MATERIAL" "FET"
					( Origin gFrontEnd )
				)
				( attribute "PACK_TYPE" "SMLF"
					( Origin gFrontEnd )
				)
				( attribute "PART_NUMBER" "E40049-001"
					( Origin gFrontEnd )
				)
				( attribute "PHYS_PAGE" "95"
					( Origin gFrontEnd )
				)
				( attribute "ROOM" "PROC_SIDEBAND"
					( Origin gFrontEnd )
				)
				( attribute "ROT" "0"
					( Origin gFrontEnd )
				)
				( attribute "SEC" "2"
					( Origin gFrontEnd )
				)
				( attribute "SEC_TYPE" "SMLF"
					( Origin gFrontEnd )
				)
				( attribute "VALUE" "NTJD4001N"
					( Origin gFrontEnd )
				)
				( attribute "VER" "5"
					( Origin gFrontEnd )
				)
				( attribute "XY" "(-3100,3275)"
					( Origin gFrontEnd )
				)
				( attribute "CHIPS_PART_NAME" "FET_N_DUAL"
					( Origin gPackager )
				)
				( attribute "CDS_PART_NAME" "FET_N_DUAL_SMLF-NTJD4001N,FET,A"
					( Origin gPackager )
				)
				( objectStatus "Q7E3" )
				( pin "drain(0)"
					( attribute "PN" "3"
						( Origin gPackager )
					)
					( objectStatus "Q7E3.3" )
				)
				( pin "gate(0)"
					( attribute "PN" "5"
						( Origin gPackager )
					)
					( objectStatus "Q7E3.5" )
				)
				( pin "source(0)"
					( attribute "PN" "4"
						( Origin gPackager )
					)
					( objectStatus "Q7E3.4" )
				)
			)
			( gate "@baseboard_fab2_lib.baseboard_fab2(sch_1):page95_i52"
				( attribute "BOM_COST" "PROC_SIDEBAND"
					( Origin gFrontEnd )
				)
				( attribute "CDS_LIB" "mstr_discrete"
					( Origin gPackager )
				)
				( attribute "CDS_LOCATION" "Q7E3"
					( Origin gPackager )
				)
				( attribute "CDS_SEC" "1"
					( Origin gPackager )
				)
				( attribute "LOCATION" "Q7E3"
					( Origin gFrontEnd )
				)
				( attribute "MATERIAL" "FET"
					( Origin gFrontEnd )
				)
				( attribute "PACK_TYPE" "SMLF"
					( Origin gFrontEnd )
				)
				( attribute "PART_NUMBER" "E40049-001"
					( Origin gFrontEnd )
				)
				( attribute "PHYS_PAGE" "95"
					( Origin gFrontEnd )
				)
				( attribute "ROOM" "PROC_SIDEBAND"
					( Origin gFrontEnd )
				)
				( attribute "ROT" "0"
					( Origin gFrontEnd )
				)
				( attribute "SEC" "1"
					( Origin gFrontEnd )
				)
				( attribute "SEC_TYPE" "SMLF"
					( Origin gFrontEnd )
				)
				( attribute "VALUE" "NTJD4001N"
					( Origin gFrontEnd )
				)
				( attribute "VER" "5"
					( Origin gFrontEnd )
				)
				( attribute "XY" "(-3100,3950)"
					( Origin gFrontEnd )
				)
				( attribute "CHIPS_PART_NAME" "FET_N_DUAL"
					( Origin gPackager )
				)
				( attribute "CDS_PART_NAME" "FET_N_DUAL_SMLF-NTJD4001N,FET,A"
					( Origin gPackager )
				)
				( objectStatus "Q7E3" )
				( pin "drain(0)"
					( attribute "PN" "6"
						( Origin gPackager )
					)
					( objectStatus "Q7E3.6" )
				)
				( pin "gate(0)"
					( attribute "PN" "2"
						( Origin gPackager )
					)
					( objectStatus "Q7E3.2" )
				)
				( pin "source(0)"
					( attribute "PN" "1"
						( Origin gPackager )
					)
					( objectStatus "Q7E3.1" )
				)
			)
			( gate "@baseboard_fab2_lib.baseboard_fab2(sch_1):page95_i59"
				( attribute "BOM_COST" "PROC_SIDEBAND"
					( Origin gFrontEnd )
				)
				( attribute "CDS_LIB" "mstr_discrete"
					( Origin gPackager )
				)
				( attribute "CDS_LOCATION" "Q7E5"
					( Origin gPackager )
				)
				( attribute "CDS_SEC" "2"
					( Origin gPackager )
				)
				( attribute "LOCATION" "Q7E5"
					( Origin gFrontEnd )
				)
				( attribute "MATERIAL" "FET"
					( Origin gFrontEnd )
				)
				( attribute "PACK_TYPE" "SMLF"
					( Origin gFrontEnd )
				)
				( attribute "PART_NUMBER" "E40049-001"
					( Origin gFrontEnd )
				)
				( attribute "PHYS_PAGE" "95"
					( Origin gFrontEnd )
				)
				( attribute "ROOM" "HOT_EVENTS"
					( Origin gFrontEnd )
				)
				( attribute "ROT" "0"
					( Origin gFrontEnd )
				)
				( attribute "SEC" "2"
					( Origin gFrontEnd )
				)
				( attribute "SEC_TYPE" "SMLF"
					( Origin gFrontEnd )
				)
				( attribute "VALUE" "NTJD4001N"
					( Origin gFrontEnd )
				)
				( attribute "VER" "5"
					( Origin gFrontEnd )
				)
				( attribute "XY" "(3050,4725)"
					( Origin gFrontEnd )
				)
				( attribute "CHIPS_PART_NAME" "FET_N_DUAL"
					( Origin gPackager )
				)
				( attribute "CDS_PART_NAME" "FET_N_DUAL_SMLF-NTJD4001N,FET,A"
					( Origin gPackager )
				)
				( objectStatus "Q7E5" )
				( pin "drain(0)"
					( attribute "PN" "3"
						( Origin gPackager )
					)
					( objectStatus "Q7E5.3" )
				)
				( pin "gate(0)"
					( attribute "PN" "5"
						( Origin gPackager )
					)
					( objectStatus "Q7E5.5" )
				)
				( pin "source(0)"
					( attribute "PN" "4"
						( Origin gPackager )
					)
					( objectStatus "Q7E5.4" )
				)
			)
			( gate "@baseboard_fab2_lib.baseboard_fab2(sch_1):page95_i62"
				( attribute "BOM_COST" "PROC_SIDEBAND"
					( Origin gFrontEnd )
				)
				( attribute "CDS_LIB" "mstr_discrete"
					( Origin gPackager )
				)
				( attribute "CDS_LOCATION" "R7E10"
					( Origin gPackager )
				)
				( attribute "CDS_SEC" "1"
					( Origin gPackager )
				)
				( attribute "LOCATION" "R7E10"
					( Origin gFrontEnd )
				)
				( attribute "MATERIAL" "CHIP"
					( Origin gFrontEnd )
				)
				( attribute "PACK_TYPE" "0402"
					( Origin gFrontEnd )
				)
				( attribute "PART_NUMBER" "G21796-072"
					( Origin gFrontEnd )
				)
				( attribute "PHYS_PAGE" "95"
					( Origin gFrontEnd )
				)
				( attribute "ROOM" "HOT_EVENTS"
					( Origin gFrontEnd )
				)
				( attribute "ROT" "2"
					( Origin gFrontEnd )
				)
				( attribute "SEC" "1"
					( Origin gPackager )
				)
				( attribute "TOLERANCE" "1%"
					( Origin gFrontEnd )
				)
				( attribute "VALUE" "4.75K"
					( Origin gFrontEnd )
				)
				( attribute "VER" "2"
					( Origin gFrontEnd )
				)
				( attribute "WATTAGE" "1/16W"
					( Origin gFrontEnd )
				)
				( attribute "XY" "(2475,4800)"
					( Origin gFrontEnd )
				)
				( attribute "CHIPS_PART_NAME" "RES"
					( Origin gPackager )
				)
				( attribute "CDS_PART_NAME" "RES_0402-4.75K,1%,1/16W,CHIP,GA"
					( Origin gPackager )
				)
				( objectStatus "R7E10" )
				( pin "a"
					( attribute "PN" "1"
						( Origin gPackager )
					)
					( objectStatus "R7E10.1" )
				)
				( pin "b"
					( attribute "PN" "2"
						( Origin gPackager )
					)
					( objectStatus "R7E10.2" )
				)
			)
			( gate "@baseboard_fab2_lib.baseboard_fab2(sch_1):page95_i69"
				( attribute "BOM_COST" "PROC_SIDEBAND"
					( Origin gFrontEnd )
				)
				( attribute "CDS_LIB" "mstr_discrete"
					( Origin gPackager )
				)
				( attribute "CDS_LOCATION" "Q7E6"
					( Origin gPackager )
				)
				( attribute "CDS_SEC" "2"
					( Origin gPackager )
				)
				( attribute "LOCATION" "Q7E6"
					( Origin gFrontEnd )
				)
				( attribute "MATERIAL" "FET"
					( Origin gFrontEnd )
				)
				( attribute "PACK_TYPE" "SMLF"
					( Origin gFrontEnd )
				)
				( attribute "PART_NUMBER" "E40049-001"
					( Origin gFrontEnd )
				)
				( attribute "PHYS_PAGE" "95"
					( Origin gFrontEnd )
				)
				( attribute "ROOM" "HOT_EVENTS"
					( Origin gFrontEnd )
				)
				( attribute "ROT" "0"
					( Origin gFrontEnd )
				)
				( attribute "SEC" "2"
					( Origin gFrontEnd )
				)
				( attribute "SEC_TYPE" "SMLF"
					( Origin gFrontEnd )
				)
				( attribute "VALUE" "NTJD4001N"
					( Origin gFrontEnd )
				)
				( attribute "VER" "5"
					( Origin gFrontEnd )
				)
				( attribute "XY" "(3150,3275)"
					( Origin gFrontEnd )
				)
				( attribute "CHIPS_PART_NAME" "FET_N_DUAL"
					( Origin gPackager )
				)
				( attribute "CDS_PART_NAME" "FET_N_DUAL_SMLF-NTJD4001N,FET,A"
					( Origin gPackager )
				)
				( objectStatus "Q7E6" )
				( pin "drain(0)"
					( attribute "PN" "3"
						( Origin gPackager )
					)
					( objectStatus "Q7E6.3" )
				)
				( pin "gate(0)"
					( attribute "PN" "5"
						( Origin gPackager )
					)
					( objectStatus "Q7E6.5" )
				)
				( pin "source(0)"
					( attribute "PN" "4"
						( Origin gPackager )
					)
					( objectStatus "Q7E6.4" )
				)
			)
			( gate "@baseboard_fab2_lib.baseboard_fab2(sch_1):page95_i72"
				( attribute "BOM_COST" "PROC_SIDEBAND"
					( Origin gFrontEnd )
				)
				( attribute "CDS_LIB" "mstr_discrete"
					( Origin gPackager )
				)
				( attribute "CDS_LOCATION" "R7E11"
					( Origin gPackager )
				)
				( attribute "CDS_SEC" "1"
					( Origin gPackager )
				)
				( attribute "LOCATION" "R7E11"
					( Origin gFrontEnd )
				)
				( attribute "MATERIAL" "CHIP"
					( Origin gFrontEnd )
				)
				( attribute "PACK_TYPE" "0402"
					( Origin gFrontEnd )
				)
				( attribute "PART_NUMBER" "G21796-072"
					( Origin gFrontEnd )
				)
				( attribute "PHYS_PAGE" "95"
					( Origin gFrontEnd )
				)
				( attribute "ROOM" "HOT_EVENTS"
					( Origin gFrontEnd )
				)
				( attribute "ROT" "2"
					( Origin gFrontEnd )
				)
				( attribute "SEC" "1"
					( Origin gPackager )
				)
				( attribute "TOLERANCE" "1%"
					( Origin gFrontEnd )
				)
				( attribute "VALUE" "4.75K"
					( Origin gFrontEnd )
				)
				( attribute "VER" "2"
					( Origin gFrontEnd )
				)
				( attribute "WATTAGE" "1/16W"
					( Origin gFrontEnd )
				)
				( attribute "XY" "(2550,3375)"
					( Origin gFrontEnd )
				)
				( attribute "CHIPS_PART_NAME" "RES"
					( Origin gPackager )
				)
				( attribute "CDS_PART_NAME" "RES_0402-4.75K,1%,1/16W,CHIP,GA"
					( Origin gPackager )
				)
				( objectStatus "R7E11" )
				( pin "a"
					( attribute "PN" "1"
						( Origin gPackager )
					)
					( objectStatus "R7E11.1" )
				)
				( pin "b"
					( attribute "PN" "2"
						( Origin gPackager )
					)
					( objectStatus "R7E11.2" )
				)
			)
			( gate "@baseboard_fab2_lib.baseboard_fab2(sch_1):page95_i92"
				( attribute "BOM_COST" "PROC_SIDEBAND"
					( Origin gFrontEnd )
				)
				( attribute "CDS_LIB" "dev_discrete"
					( Origin gPackager )
				)
				( attribute "CDS_LOCATION" "C7E3"
					( Origin gPackager )
				)
				( attribute "CDS_SEC" "1"
					( Origin gPackager )
				)
				( attribute "LOCATION" "C7E3"
					( Origin gFrontEnd )
				)
				( attribute "MATERIAL" "X7R"
					( Origin gFrontEnd )
				)
				( attribute "PACK_TYPE" "0402V"
					( Origin gFrontEnd )
				)
				( attribute "PART_NUMBER" "A36096-030"
					( Origin gFrontEnd )
				)
				( attribute "PHYS_PAGE" "95"
					( Origin gFrontEnd )
				)
				( attribute "ROOM" "PROC_SIDEBAND"
					( Origin gFrontEnd )
				)
				( attribute "ROT" "0"
					( Origin gFrontEnd )
				)
				( attribute "SEC" "1"
					( Origin gFrontEnd )
				)
				( attribute "SEC_TYPE" "0402V"
					( Origin gFrontEnd )
				)
				( attribute "TOLERANCE" "10%"
					( Origin gFrontEnd )
				)
				( attribute "VALUE" "0.1UF"
					( Origin gFrontEnd )
				)
				( attribute "VER" "1"
					( Origin gFrontEnd )
				)
				( attribute "VOLTAGE" "16V"
					( Units "uVoltage" "V" 1.000000)
					( Origin gFrontEnd )
				)
				( attribute "XY" "(700,4775)"
					( Origin gFrontEnd )
				)
				( attribute "CHIPS_PART_NAME" "CAP_A"
					( Origin gPackager )
				)
				( attribute "CDS_PART_NAME" "CAP_A_0402V-0.1UF,16V,10%,X7R,A"
					( Origin gPackager )
				)
				( objectStatus "C7E3" )
				( pin "a"
					( attribute "PN" "1"
						( Origin gPackager )
					)
					( objectStatus "C7E3.1" )
				)
				( pin "b"
					( attribute "PN" "2"
						( Origin gPackager )
					)
					( objectStatus "C7E3.2" )
				)
			)
			( gate "@baseboard_fab2_lib.baseboard_fab2(sch_1):page95_i104"
				( attribute "CDS_LIB" "mstr_discrete"
					( Origin gPackager )
				)
				( attribute "CDS_LOCATION" "Q7E4"
					( Origin gPackager )
				)
				( attribute "CDS_SEC" "1"
					( Origin gPackager )
				)
				( attribute "LOCATION" "Q7E4"
					( Origin gFrontEnd )
				)
				( attribute "MATERIAL" "FET"
					( Origin gFrontEnd )
				)
				( attribute "PACK_TYPE" "SOT23"
					( Origin gFrontEnd )
				)
				( attribute "PART_NUMBER" "C79254-001"
					( Origin gFrontEnd )
				)
				( attribute "PHYS_PAGE" "95"
					( Origin gFrontEnd )
				)
				( attribute "ROOM" "PROC_SIDEBAND"
					( Origin gFrontEnd )
				)
				( attribute "ROT" "0"
					( Origin gFrontEnd )
				)
				( attribute "SEC" "1"
					( Origin gFrontEnd )
				)
				( attribute "SEC_TYPE" "SOT23"
					( Origin gFrontEnd )
				)
				( attribute "VALUE" "2N7002"
					( Origin gFrontEnd )
				)
				( attribute "VER" "8"
					( Origin gFrontEnd )
				)
				( attribute "XY" "(2150,1350)"
					( Origin gFrontEnd )
				)
				( attribute "CHIPS_PART_NAME" "FET_N"
					( Origin gPackager )
				)
				( attribute "CDS_PART_NAME" "FET_N_SOT23-2N7002,FET,C79254-A"
					( Origin gPackager )
				)
				( objectStatus "Q7E4" )
				( pin "drn"
					( attribute "PN" "3"
						( Origin gPackager )
					)
					( objectStatus "Q7E4.3" )
				)
				( pin "gate"
					( attribute "PN" "1"
						( Origin gPackager )
					)
					( objectStatus "Q7E4.1" )
				)
				( pin "src"
					( attribute "PN" "2"
						( Origin gPackager )
					)
					( objectStatus "Q7E4.2" )
				)
			)
			( gate "@baseboard_fab2_lib.baseboard_fab2(sch_1):page95_i106"
				( attribute "CDS_LIB" "mstr_discrete"
					( Origin gPackager )
				)
				( attribute "CDS_LOCATION" "R7E7"
					( Origin gPackager )
				)
				( attribute "CDS_SEC" "1"
					( Origin gPackager )
				)
				( attribute "LOCATION" "R7E7"
					( Origin gFrontEnd )
				)
				( attribute "MATERIAL" "CHIP"
					( Origin gFrontEnd )
				)
				( attribute "PACK_TYPE" "0402"
					( Origin gFrontEnd )
				)
				( attribute "PART_NUMBER" "G21796-072"
					( Origin gFrontEnd )
				)
				( attribute "PHYS_PAGE" "95"
					( Origin gFrontEnd )
				)
				( attribute "ROOM" "PROC_SIDEBAND"
					( Origin gFrontEnd )
				)
				( attribute "ROT" "0"
					( Origin gFrontEnd )
				)
				( attribute "SEC" "1"
					( Origin gFrontEnd )
				)
				( attribute "SEC_TYPE" "0402"
					( Origin gFrontEnd )
				)
				( attribute "TOLERANCE" "1%"
					( Origin gFrontEnd )
				)
				( attribute "VALUE" "4.75K"
					( Origin gFrontEnd )
				)
				( attribute "VER" "2"
					( Origin gFrontEnd )
				)
				( attribute "WATTAGE" "1/16W"
					( Origin gFrontEnd )
				)
				( attribute "XY" "(2150,1800)"
					( Origin gFrontEnd )
				)
				( attribute "CHIPS_PART_NAME" "RES"
					( Origin gPackager )
				)
				( attribute "CDS_PART_NAME" "RES_0402-4.75K,1%,1/16W,CHIP,GA"
					( Origin gPackager )
				)
				( objectStatus "R7E7" )
				( pin "a"
					( attribute "PN" "1"
						( Origin gPackager )
					)
					( objectStatus "R7E7.1" )
				)
				( pin "b"
					( attribute "PN" "2"
						( Origin gPackager )
					)
					( objectStatus "R7E7.2" )
				)
			)
			( gate "@baseboard_fab2_lib.baseboard_fab2(sch_1):page95_i108"
				( attribute "BOM_COST" "PROC_SIDEBAND"
					( Origin gFrontEnd )
				)
				( attribute "CDS_LIB" "mstr_discrete"
					( Origin gPackager )
				)
				( attribute "CDS_LOCATION" "R7E9"
					( Origin gPackager )
				)
				( attribute "CDS_SEC" "1"
					( Origin gPackager )
				)
				( attribute "LOCATION" "R7E9"
					( Origin gFrontEnd )
				)
				( attribute "MATERIAL" "CHIP"
					( Origin gFrontEnd )
				)
				( attribute "PACK_TYPE" "0402"
					( Origin gFrontEnd )
				)
				( attribute "PART_NUMBER" "G21497-005"
					( Origin gFrontEnd )
				)
				( attribute "PHYS_PAGE" "95"
					( Origin gFrontEnd )
				)
				( attribute "ROOM" "PROC_SIDEBAND"
					( Origin gFrontEnd )
				)
				( attribute "ROT" "0"
					( Origin gFrontEnd )
				)
				( attribute "SEC" "1"
					( Origin gFrontEnd )
				)
				( attribute "SEC_TYPE" "0402"
					( Origin gFrontEnd )
				)
				( attribute "TOLERANCE" "5%"
					( Origin gFrontEnd )
				)
				( attribute "VALUE" "0.0"
					( Origin gFrontEnd )
				)
				( attribute "VER" "1"
					( Origin gFrontEnd )
				)
				( attribute "WATTAGE" "1/16W"
					( Origin gFrontEnd )
				)
				( attribute "XY" "(1325,1250)"
					( Origin gFrontEnd )
				)
				( attribute "CHIPS_PART_NAME" "RES"
					( Origin gPackager )
				)
				( attribute "CDS_PART_NAME" "RES_0402-0.0,5%,1/16W,CHIP,G21A"
					( Origin gPackager )
				)
				( objectStatus "R7E9" )
				( pin "a"
					( attribute "PN" "1"
						( Origin gPackager )
					)
					( objectStatus "R7E9.1" )
				)
				( pin "b"
					( attribute "PN" "2"
						( Origin gPackager )
					)
					( objectStatus "R7E9.2" )
				)
			)
			( gate "@baseboard_fab2_lib.baseboard_fab2(sch_1):page95_i111"
				( attribute "BOM_COST" "PROC_SIDEBAND"
					( Origin gFrontEnd )
				)
				( attribute "CDS_LIB" "mstr_discrete"
					( Origin gPackager )
				)
				( attribute "CDS_LOCATION" "Q7E5"
					( Origin gPackager )
				)
				( attribute "CDS_SEC" "1"
					( Origin gPackager )
				)
				( attribute "LOCATION" "Q7E5"
					( Origin gFrontEnd )
				)
				( attribute "MATERIAL" "FET"
					( Origin gFrontEnd )
				)
				( attribute "PACK_TYPE" "SMLF"
					( Origin gFrontEnd )
				)
				( attribute "PART_NUMBER" "E40049-001"
					( Origin gFrontEnd )
				)
				( attribute "PHYS_PAGE" "95"
					( Origin gFrontEnd )
				)
				( attribute "ROOM" "HOT_EVENTS"
					( Origin gFrontEnd )
				)
				( attribute "ROT" "0"
					( Origin gFrontEnd )
				)
				( attribute "SEC" "1"
					( Origin gFrontEnd )
				)
				( attribute "SEC_TYPE" "SMLF"
					( Origin gFrontEnd )
				)
				( attribute "VALUE" "NTJD4001N"
					( Origin gFrontEnd )
				)
				( attribute "VER" "5"
					( Origin gFrontEnd )
				)
				( attribute "XY" "(2475,4325)"
					( Origin gFrontEnd )
				)
				( attribute "CHIPS_PART_NAME" "FET_N_DUAL"
					( Origin gPackager )
				)
				( attribute "CDS_PART_NAME" "FET_N_DUAL_SMLF-NTJD4001N,FET,A"
					( Origin gPackager )
				)
				( objectStatus "Q7E5" )
				( pin "drain(0)"
					( attribute "PN" "6"
						( Origin gPackager )
					)
					( objectStatus "Q7E5.6" )
				)
				( pin "gate(0)"
					( attribute "PN" "2"
						( Origin gPackager )
					)
					( objectStatus "Q7E5.2" )
				)
				( pin "source(0)"
					( attribute "PN" "1"
						( Origin gPackager )
					)
					( objectStatus "Q7E5.1" )
				)
			)
			( gate "@baseboard_fab2_lib.baseboard_fab2(sch_1):page95_i112"
				( attribute "BOM_COST" "PROC_SIDEBAND"
					( Origin gFrontEnd )
				)
				( attribute "CDS_LIB" "mstr_discrete"
					( Origin gPackager )
				)
				( attribute "CDS_LOCATION" "Q7E6"
					( Origin gPackager )
				)
				( attribute "CDS_SEC" "1"
					( Origin gPackager )
				)
				( attribute "LOCATION" "Q7E6"
					( Origin gFrontEnd )
				)
				( attribute "MATERIAL" "FET"
					( Origin gFrontEnd )
				)
				( attribute "PACK_TYPE" "SMLF"
					( Origin gFrontEnd )
				)
				( attribute "PART_NUMBER" "E40049-001"
					( Origin gFrontEnd )
				)
				( attribute "PHYS_PAGE" "95"
					( Origin gFrontEnd )
				)
				( attribute "ROOM" "HOT_EVENTS"
					( Origin gFrontEnd )
				)
				( attribute "ROT" "0"
					( Origin gFrontEnd )
				)
				( attribute "SEC" "1"
					( Origin gFrontEnd )
				)
				( attribute "SEC_TYPE" "SMLF"
					( Origin gFrontEnd )
				)
				( attribute "VALUE" "NTJD4001N"
					( Origin gFrontEnd )
				)
				( attribute "VER" "5"
					( Origin gFrontEnd )
				)
				( attribute "XY" "(2550,2875)"
					( Origin gFrontEnd )
				)
				( attribute "CHIPS_PART_NAME" "FET_N_DUAL"
					( Origin gPackager )
				)
				( attribute "CDS_PART_NAME" "FET_N_DUAL_SMLF-NTJD4001N,FET,A"
					( Origin gPackager )
				)
				( objectStatus "Q7E6" )
				( pin "drain(0)"
					( attribute "PN" "6"
						( Origin gPackager )
					)
					( objectStatus "Q7E6.6" )
				)
				( pin "gate(0)"
					( attribute "PN" "2"
						( Origin gPackager )
					)
					( objectStatus "Q7E6.2" )
				)
				( pin "source(0)"
					( attribute "PN" "1"
						( Origin gPackager )
					)
					( objectStatus "Q7E6.1" )
				)
			)
			( gate "@baseboard_fab2_lib.baseboard_fab2(sch_1):page95_i113"
				( attribute "BOM_COST" "PROC_SIDEBAND"
					( Origin gFrontEnd )
				)
				( attribute "CDS_LIB" "mstr_discrete"
					( Origin gPackager )
				)
				( attribute "CDS_LOCATION" "Q2U1"
					( Origin gPackager )
				)
				( attribute "CDS_SEC" "2"
					( Origin gPackager )
				)
				( attribute "LOCATION" "Q2U1"
					( Origin gFrontEnd )
				)
				( attribute "MATERIAL" "FET"
					( Origin gFrontEnd )
				)
				( attribute "PACK_TYPE" "SMLF"
					( Origin gFrontEnd )
				)
				( attribute "PART_NUMBER" "E40049-001"
					( Origin gFrontEnd )
				)
				( attribute "PHYS_PAGE" "95"
					( Origin gFrontEnd )
				)
				( attribute "ROOM" "PROC_SIDEBAND"
					( Origin gFrontEnd )
				)
				( attribute "ROT" "0"
					( Origin gFrontEnd )
				)
				( attribute "SEC" "2"
					( Origin gFrontEnd )
				)
				( attribute "SEC_TYPE" "SMLF"
					( Origin gFrontEnd )
				)
				( attribute "VALUE" "NTJD4001N"
					( Origin gFrontEnd )
				)
				( attribute "VER" "5"
					( Origin gFrontEnd )
				)
				( attribute "XY" "(-3100,1950)"
					( Origin gFrontEnd )
				)
				( attribute "CHIPS_PART_NAME" "FET_N_DUAL"
					( Origin gPackager )
				)
				( attribute "CDS_PART_NAME" "FET_N_DUAL_SMLF-NTJD4001N,FET,A"
					( Origin gPackager )
				)
				( objectStatus "Q2U1" )
				( pin "drain(0)"
					( attribute "PN" "3"
						( Origin gPackager )
					)
					( objectStatus "Q2U1.3" )
				)
				( pin "gate(0)"
					( attribute "PN" "5"
						( Origin gPackager )
					)
					( objectStatus "Q2U1.5" )
				)
				( pin "source(0)"
					( attribute "PN" "4"
						( Origin gPackager )
					)
					( objectStatus "Q2U1.4" )
				)
			)
			( gate "@baseboard_fab2_lib.baseboard_fab2(sch_1):page95_i115"
				( attribute "BOM_COST" "PROC_SIDEBAND"
					( Origin gFrontEnd )
				)
				( attribute "CDS_LIB" "dev_discrete"
					( Origin gPackager )
				)
				( attribute "CDS_LOCATION" "C7E4"
					( Origin gPackager )
				)
				( attribute "CDS_SEC" "1"
					( Origin gPackager )
				)
				( attribute "LOCATION" "C7E4"
					( Origin gFrontEnd )
				)
				( attribute "MATERIAL" "X7R"
					( Origin gFrontEnd )
				)
				( attribute "PACK_TYPE" "0402V"
					( Origin gFrontEnd )
				)
				( attribute "PART_NUMBER" "A36096-030"
					( Origin gFrontEnd )
				)
				( attribute "PHYS_PAGE" "95"
					( Origin gFrontEnd )
				)
				( attribute "ROOM" "PROC_SIDEBAND"
					( Origin gFrontEnd )
				)
				( attribute "ROT" "0"
					( Origin gFrontEnd )
				)
				( attribute "SEC" "1"
					( Origin gFrontEnd )
				)
				( attribute "SEC_TYPE" "0402V"
					( Origin gFrontEnd )
				)
				( attribute "TOLERANCE" "10%"
					( Origin gFrontEnd )
				)
				( attribute "VALUE" "0.1UF"
					( Origin gFrontEnd )
				)
				( attribute "VER" "1"
					( Origin gFrontEnd )
				)
				( attribute "VOLTAGE" "16V"
					( Units "uVoltage" "V" 1.000000)
					( Origin gFrontEnd )
				)
				( attribute "XY" "(1125,3450)"
					( Origin gFrontEnd )
				)
				( attribute "CHIPS_PART_NAME" "CAP_A"
					( Origin gPackager )
				)
				( attribute "CDS_PART_NAME" "CAP_A_0402V-0.1UF,16V,10%,X7R,A"
					( Origin gPackager )
				)
				( objectStatus "C7E4" )
				( pin "a"
					( attribute "PN" "1"
						( Origin gPackager )
					)
					( objectStatus "C7E4.1" )
				)
				( pin "b"
					( attribute "PN" "2"
						( Origin gPackager )
					)
					( objectStatus "C7E4.2" )
				)
			)
			( gate "@baseboard_fab2_lib.baseboard_fab2(sch_1):page95_i117"
				( attribute "BOM_COST" "PROC_SIDEBAND"
					( Origin gFrontEnd )
				)
				( attribute "CDS_LIB" "mstr_ttl"
					( Origin gPackager )
				)
				( attribute "CDS_LOCATION" "U7E2"
					( Origin gPackager )
				)
				( attribute "CDS_SEC" "1"
					( Origin gPackager )
				)
				( attribute "LOCATION" "U7E2"
					( Origin gFrontEnd )
				)
				( attribute "MATERIAL" "IC"
					( Origin gFrontEnd )
				)
				( attribute "PACK_TYPE" "SOTLF"
					( Origin gFrontEnd )
				)
				( attribute "PART_NUMBER" "D10321-001"
					( Origin gFrontEnd )
				)
				( attribute "PHYS_PAGE" "95"
					( Origin gFrontEnd )
				)
				( attribute "ROOM" "CAT_ERR"
					( Origin gFrontEnd )
				)
				( attribute "ROT" "0"
					( Origin gFrontEnd )
				)
				( attribute "SEC" "1"
					( Origin gFrontEnd )
				)
				( attribute "SEC_TYPE" "SOTLF"
					( Origin gFrontEnd )
				)
				( attribute "VALUE" "NC7SZ08"
					( Origin gFrontEnd )
				)
				( attribute "VER" "1"
					( Origin gFrontEnd )
				)
				( attribute "XY" "(1550,4225)"
					( Origin gFrontEnd )
				)
				( attribute "CHIPS_PART_NAME" "TTL1G08"
					( Origin gPackager )
				)
				( attribute "CDS_PART_NAME" "TTL1G08_SOTLF-NC7SZ08,IC,D1032B"
					( Origin gPackager )
				)
				( objectStatus "U7E2" )
				( pin "a(0)"
					( attribute "PN" "1"
						( Origin gPackager )
					)
					( objectStatus "U7E2.1" )
				)
				( pin "b(0)"
					( attribute "PN" "2"
						( Origin gPackager )
					)
					( objectStatus "U7E2.2" )
				)
				( pin "y(0)"
					( attribute "PN" "4"
						( Origin gPackager )
					)
					( objectStatus "U7E2.4" )
				)
			)
			( gate "@baseboard_fab2_lib.baseboard_fab2(sch_1):page95_i118"
				( attribute "BOM_COST" "PROC_SIDEBAND"
					( Origin gFrontEnd )
				)
				( attribute "CDS_LIB" "mstr_ttl"
					( Origin gPackager )
				)
				( attribute "CDS_LOCATION" "U7E3"
					( Origin gPackager )
				)
				( attribute "CDS_SEC" "1"
					( Origin gPackager )
				)
				( attribute "LOCATION" "U7E3"
					( Origin gFrontEnd )
				)
				( attribute "MATERIAL" "IC"
					( Origin gFrontEnd )
				)
				( attribute "PACK_TYPE" "SOTLF"
					( Origin gFrontEnd )
				)
				( attribute "PART_NUMBER" "D10321-001"
					( Origin gFrontEnd )
				)
				( attribute "PHYS_PAGE" "95"
					( Origin gFrontEnd )
				)
				( attribute "ROOM" "CAT_ERR"
					( Origin gFrontEnd )
				)
				( attribute "ROT" "0"
					( Origin gFrontEnd )
				)
				( attribute "SEC" "1"
					( Origin gFrontEnd )
				)
				( attribute "SEC_TYPE" "SOTLF"
					( Origin gFrontEnd )
				)
				( attribute "VALUE" "NC7SZ08"
					( Origin gFrontEnd )
				)
				( attribute "VER" "1"
					( Origin gFrontEnd )
				)
				( attribute "XY" "(1575,2775)"
					( Origin gFrontEnd )
				)
				( attribute "CHIPS_PART_NAME" "TTL1G08"
					( Origin gPackager )
				)
				( attribute "CDS_PART_NAME" "TTL1G08_SOTLF-NC7SZ08,IC,D1032B"
					( Origin gPackager )
				)
				( objectStatus "U7E3" )
				( pin "a(0)"
					( attribute "PN" "1"
						( Origin gPackager )
					)
					( objectStatus "U7E3.1" )
				)
				( pin "b(0)"
					( attribute "PN" "2"
						( Origin gPackager )
					)
					( objectStatus "U7E3.2" )
				)
				( pin "y(0)"
					( attribute "PN" "4"
						( Origin gPackager )
					)
					( objectStatus "U7E3.4" )
				)
			)
			( gate "@baseboard_fab2_lib.baseboard_fab2(sch_1):page95_i119"
				( attribute "CDS_LIB" "mstr_discrete"
					( Origin gPackager )
				)
				( attribute "CDS_LOCATION" "Q7E8"
					( Origin gPackager )
				)
				( attribute "CDS_SEC" "1"
					( Origin gPackager )
				)
				( attribute "LOCATION" "Q7E8"
					( Origin gFrontEnd )
				)
				( attribute "MATERIAL" "FET"
					( Origin gFrontEnd )
				)
				( attribute "PACK_TYPE" "SOT23"
					( Origin gFrontEnd )
				)
				( attribute "PART_NUMBER" "C79254-001"
					( Origin gFrontEnd )
				)
				( attribute "PHYS_PAGE" "95"
					( Origin gFrontEnd )
				)
				( attribute "ROOM" "PROC_SIDEBAND"
					( Origin gFrontEnd )
				)
				( attribute "ROT" "0"
					( Origin gFrontEnd )
				)
				( attribute "SEC" "1"
					( Origin gFrontEnd )
				)
				( attribute "SEC_TYPE" "SOT23"
					( Origin gFrontEnd )
				)
				( attribute "VALUE" "2N7002"
					( Origin gFrontEnd )
				)
				( attribute "VER" "8"
					( Origin gFrontEnd )
				)
				( attribute "XY" "(-3100,4550)"
					( Origin gFrontEnd )
				)
				( attribute "CHIPS_PART_NAME" "FET_N"
					( Origin gPackager )
				)
				( attribute "CDS_PART_NAME" "FET_N_SOT23-2N7002,FET,C79254-A"
					( Origin gPackager )
				)
				( objectStatus "Q7E8" )
				( pin "drn"
					( attribute "PN" "3"
						( Origin gPackager )
					)
					( objectStatus "Q7E8.3" )
				)
				( pin "gate"
					( attribute "PN" "1"
						( Origin gPackager )
					)
					( objectStatus "Q7E8.1" )
				)
				( pin "src"
					( attribute "PN" "2"
						( Origin gPackager )
					)
					( objectStatus "Q7E8.2" )
				)
			)
			( gate "@baseboard_fab2_lib.baseboard_fab2(sch_1):page96_i2"
				( attribute "BOM_COST" "PROC_SIDEBAND"
					( Origin gFrontEnd )
				)
				( attribute "CDS_LIB" "mstr_discrete"
					( Origin gPackager )
				)
				( attribute "CDS_LOCATION" "R6D12"
					( Origin gPackager )
				)
				( attribute "CDS_SEC" "1"
					( Origin gPackager )
				)
				( attribute "LOCATION" "R6D12"
					( Origin gFrontEnd )
				)
				( attribute "MATERIAL" "CHIP"
					( Origin gFrontEnd )
				)
				( attribute "PACK_TYPE" "0402"
					( Origin gFrontEnd )
				)
				( attribute "PART_NUMBER" "G21796-047"
					( Origin gFrontEnd )
				)
				( attribute "PHYS_PAGE" "96"
					( Origin gFrontEnd )
				)
				( attribute "ROOM" "PROC_RSTS_PGOODS"
					( Origin gFrontEnd )
				)
				( attribute "ROT" "0"
					( Origin gFrontEnd )
				)
				( attribute "SEC" "1"
					( Origin gFrontEnd )
				)
				( attribute "SEC_TYPE" "0402"
					( Origin gFrontEnd )
				)
				( attribute "TOLERANCE" "1%"
					( Origin gFrontEnd )
				)
				( attribute "VALUE" "49.9"
					( Origin gFrontEnd )
				)
				( attribute "VER" "2"
					( Origin gFrontEnd )
				)
				( attribute "WATTAGE" "1/16W"
					( Origin gFrontEnd )
				)
				( attribute "XY" "(1900,4450)"
					( Origin gFrontEnd )
				)
				( attribute "CHIPS_PART_NAME" "RES"
					( Origin gPackager )
				)
				( attribute "CDS_PART_NAME" "RES_0402-49.9,1%,1/16W,CHIP,G2A"
					( Origin gPackager )
				)
				( objectStatus "R6D12" )
				( pin "a"
					( attribute "PN" "1"
						( Origin gPackager )
					)
					( objectStatus "R6D12.1" )
				)
				( pin "b"
					( attribute "PN" "2"
						( Origin gPackager )
					)
					( objectStatus "R6D12.2" )
				)
			)
			( gate "@baseboard_fab2_lib.baseboard_fab2(sch_1):page96_i3"
				( attribute "BOM_COST" "PROC_SIDEBAND"
					( Origin gFrontEnd )
				)
				( attribute "CDS_LIB" "mstr_discrete"
					( Origin gPackager )
				)
				( attribute "CDS_LOCATION" "R6D8"
					( Origin gPackager )
				)
				( attribute "CDS_SEC" "1"
					( Origin gPackager )
				)
				( attribute "LOCATION" "R6D8"
					( Origin gFrontEnd )
				)
				( attribute "MATERIAL" "CHIP"
					( Origin gFrontEnd )
				)
				( attribute "PACK_TYPE" "0402"
					( Origin gFrontEnd )
				)
				( attribute "PART_NUMBER" "G21796-047"
					( Origin gFrontEnd )
				)
				( attribute "PHYS_PAGE" "96"
					( Origin gFrontEnd )
				)
				( attribute "ROOM" "PROC_RSTS_PGOODS"
					( Origin gFrontEnd )
				)
				( attribute "ROT" "2"
					( Origin gFrontEnd )
				)
				( attribute "SEC" "1"
					( Origin gFrontEnd )
				)
				( attribute "SEC_TYPE" "0402"
					( Origin gFrontEnd )
				)
				( attribute "TOLERANCE" "1%"
					( Origin gFrontEnd )
				)
				( attribute "VALUE" "49.9"
					( Origin gFrontEnd )
				)
				( attribute "VER" "2"
					( Origin gFrontEnd )
				)
				( attribute "WATTAGE" "1/16W"
					( Origin gFrontEnd )
				)
				( attribute "XY" "(1700,4450)"
					( Origin gFrontEnd )
				)
				( attribute "CHIPS_PART_NAME" "RES"
					( Origin gPackager )
				)
				( attribute "CDS_PART_NAME" "RES_0402-49.9,1%,1/16W,CHIP,G2A"
					( Origin gPackager )
				)
				( objectStatus "R6D8" )
				( pin "a"
					( attribute "PN" "1"
						( Origin gPackager )
					)
					( objectStatus "R6D8.1" )
				)
				( pin "b"
					( attribute "PN" "2"
						( Origin gPackager )
					)
					( objectStatus "R6D8.2" )
				)
			)
			( gate "@baseboard_fab2_lib.baseboard_fab2(sch_1):page96_i5"
				( attribute "BOM_COST" "PROC_SIDEBAND"
					( Origin gFrontEnd )
				)
				( attribute "CDS_LIB" "mstr_discrete"
					( Origin gPackager )
				)
				( attribute "CDS_LOCATION" "R3P29"
					( Origin gPackager )
				)
				( attribute "CDS_SEC" "1"
					( Origin gPackager )
				)
				( attribute "LOCATION" "R3P29"
					( Origin gFrontEnd )
				)
				( attribute "MATERIAL" "CHIP"
					( Origin gFrontEnd )
				)
				( attribute "PACK_TYPE" "0402"
					( Origin gFrontEnd )
				)
				( attribute "PART_NUMBER" "G21796-298"
					( Origin gFrontEnd )
				)
				( attribute "PHYS_PAGE" "96"
					( Origin gFrontEnd )
				)
				( attribute "ROOM" "PROC_RSTS_PGOODS"
					( Origin gFrontEnd )
				)
				( attribute "ROT" "0"
					( Origin gFrontEnd )
				)
				( attribute "SEC" "1"
					( Origin gPackager )
				)
				( attribute "TOLERANCE" "1.0%"
					( Origin gFrontEnd )
				)
				( attribute "VALUE" "64.9"
					( Origin gFrontEnd )
				)
				( attribute "VER" "2"
					( Origin gFrontEnd )
				)
				( attribute "WATTAGE" "1/16W"
					( Origin gFrontEnd )
				)
				( attribute "XY" "(975,4450)"
					( Origin gFrontEnd )
				)
				( attribute "CHIPS_PART_NAME" "RES"
					( Origin gPackager )
				)
				( attribute "CDS_PART_NAME" "RES_0402-64.9,1.0%,1/16W,CHIP,A"
					( Origin gPackager )
				)
				( objectStatus "R3P29" )
				( pin "a"
					( attribute "PN" "1"
						( Origin gPackager )
					)
					( objectStatus "R3P29.1" )
				)
				( pin "b"
					( attribute "PN" "2"
						( Origin gPackager )
					)
					( objectStatus "R3P29.2" )
				)
			)
			( gate "@baseboard_fab2_lib.baseboard_fab2(sch_1):page96_i7"
				( attribute "BOM_COST" "PROC_SIDEBAND"
					( Origin gFrontEnd )
				)
				( attribute "CDS_LIB" "mstr_discrete"
					( Origin gPackager )
				)
				( attribute "CDS_LOCATION" "R3P38"
					( Origin gPackager )
				)
				( attribute "CDS_SEC" "1"
					( Origin gPackager )
				)
				( attribute "LOCATION" "R3P38"
					( Origin gFrontEnd )
				)
				( attribute "MATERIAL" "CHIP"
					( Origin gFrontEnd )
				)
				( attribute "PACK_TYPE" "0402"
					( Origin gFrontEnd )
				)
				( attribute "PART_NUMBER" "G21796-298"
					( Origin gFrontEnd )
				)
				( attribute "PHYS_PAGE" "96"
					( Origin gFrontEnd )
				)
				( attribute "ROOM" "PROC_RSTS_PGOODS"
					( Origin gFrontEnd )
				)
				( attribute "ROT" "0"
					( Origin gFrontEnd )
				)
				( attribute "SEC" "1"
					( Origin gPackager )
				)
				( attribute "TOLERANCE" "1.0%"
					( Origin gFrontEnd )
				)
				( attribute "VALUE" "64.9"
					( Origin gFrontEnd )
				)
				( attribute "VER" "2"
					( Origin gFrontEnd )
				)
				( attribute "WATTAGE" "1/16W"
					( Origin gFrontEnd )
				)
				( attribute "XY" "(575,4450)"
					( Origin gFrontEnd )
				)
				( attribute "CHIPS_PART_NAME" "RES"
					( Origin gPackager )
				)
				( attribute "CDS_PART_NAME" "RES_0402-64.9,1.0%,1/16W,CHIP,A"
					( Origin gPackager )
				)
				( objectStatus "R3P38" )
				( pin "a"
					( attribute "PN" "1"
						( Origin gPackager )
					)
					( objectStatus "R3P38.1" )
				)
				( pin "b"
					( attribute "PN" "2"
						( Origin gPackager )
					)
					( objectStatus "R3P38.2" )
				)
			)
			( gate "@baseboard_fab2_lib.baseboard_fab2(sch_1):page96_i25"
				( attribute "BOM_COST" "PROC_SIDEBAND"
					( Origin gFrontEnd )
				)
				( attribute "CDS_LIB" "mstr_discrete"
					( Origin gPackager )
				)
				( attribute "CDS_LOCATION" "R3D20"
					( Origin gPackager )
				)
				( attribute "CDS_SEC" "1"
					( Origin gPackager )
				)
				( attribute "LOCATION" "R3D20"
					( Origin gFrontEnd )
				)
				( attribute "MATERIAL" "CHIP"
					( Origin gFrontEnd )
				)
				( attribute "PACK_TYPE" "0402"
					( Origin gFrontEnd )
				)
				( attribute "PART_NUMBER" "G21796-047"
					( Origin gFrontEnd )
				)
				( attribute "PHYS_PAGE" "96"
					( Origin gFrontEnd )
				)
				( attribute "ROOM" "PROC_RSTS_PGOODS"
					( Origin gFrontEnd )
				)
				( attribute "ROT" "0"
					( Origin gFrontEnd )
				)
				( attribute "SEC" "1"
					( Origin gFrontEnd )
				)
				( attribute "SEC_TYPE" "0402"
					( Origin gFrontEnd )
				)
				( attribute "TOLERANCE" "1%"
					( Origin gFrontEnd )
				)
				( attribute "VALUE" "49.9"
					( Origin gFrontEnd )
				)
				( attribute "VER" "2"
					( Origin gFrontEnd )
				)
				( attribute "WATTAGE" "1/16W"
					( Origin gFrontEnd )
				)
				( attribute "XY" "(1900,2150)"
					( Origin gFrontEnd )
				)
				( attribute "CHIPS_PART_NAME" "RES"
					( Origin gPackager )
				)
				( attribute "CDS_PART_NAME" "RES_0402-49.9,1%,1/16W,CHIP,G2A"
					( Origin gPackager )
				)
				( objectStatus "R3D20" )
				( pin "a"
					( attribute "PN" "1"
						( Origin gPackager )
					)
					( objectStatus "R3D20.1" )
				)
				( pin "b"
					( attribute "PN" "2"
						( Origin gPackager )
					)
					( objectStatus "R3D20.2" )
				)
			)
			( gate "@baseboard_fab2_lib.baseboard_fab2(sch_1):page96_i26"
				( attribute "BOM_COST" "PROC_SIDEBAND"
					( Origin gFrontEnd )
				)
				( attribute "CDS_LIB" "mstr_discrete"
					( Origin gPackager )
				)
				( attribute "CDS_LOCATION" "R3D15"
					( Origin gPackager )
				)
				( attribute "CDS_SEC" "1"
					( Origin gPackager )
				)
				( attribute "LOCATION" "R3D15"
					( Origin gFrontEnd )
				)
				( attribute "MATERIAL" "CHIP"
					( Origin gFrontEnd )
				)
				( attribute "PACK_TYPE" "0402"
					( Origin gFrontEnd )
				)
				( attribute "PART_NUMBER" "G21796-047"
					( Origin gFrontEnd )
				)
				( attribute "PHYS_PAGE" "96"
					( Origin gFrontEnd )
				)
				( attribute "ROOM" "PROC_RSTS_PGOODS"
					( Origin gFrontEnd )
				)
				( attribute "ROT" "2"
					( Origin gFrontEnd )
				)
				( attribute "SEC" "1"
					( Origin gFrontEnd )
				)
				( attribute "SEC_TYPE" "0402"
					( Origin gFrontEnd )
				)
				( attribute "TOLERANCE" "1%"
					( Origin gFrontEnd )
				)
				( attribute "VALUE" "49.9"
					( Origin gFrontEnd )
				)
				( attribute "VER" "2"
					( Origin gFrontEnd )
				)
				( attribute "WATTAGE" "1/16W"
					( Origin gFrontEnd )
				)
				( attribute "XY" "(1700,2150)"
					( Origin gFrontEnd )
				)
				( attribute "CHIPS_PART_NAME" "RES"
					( Origin gPackager )
				)
				( attribute "CDS_PART_NAME" "RES_0402-49.9,1%,1/16W,CHIP,G2A"
					( Origin gPackager )
				)
				( objectStatus "R3D15" )
				( pin "a"
					( attribute "PN" "1"
						( Origin gPackager )
					)
					( objectStatus "R3D15.1" )
				)
				( pin "b"
					( attribute "PN" "2"
						( Origin gPackager )
					)
					( objectStatus "R3D15.2" )
				)
			)
			( gate "@baseboard_fab2_lib.baseboard_fab2(sch_1):page96_i28"
				( attribute "BOM_COST" "PROC_SIDEBAND"
					( Origin gFrontEnd )
				)
				( attribute "CDS_LIB" "mstr_discrete"
					( Origin gPackager )
				)
				( attribute "CDS_LOCATION" "R7M9"
					( Origin gPackager )
				)
				( attribute "CDS_SEC" "1"
					( Origin gPackager )
				)
				( attribute "LOCATION" "R7M9"
					( Origin gFrontEnd )
				)
				( attribute "MATERIAL" "CHIP"
					( Origin gFrontEnd )
				)
				( attribute "PACK_TYPE" "0402"
					( Origin gFrontEnd )
				)
				( attribute "PART_NUMBER" "G21796-298"
					( Origin gFrontEnd )
				)
				( attribute "PHYS_PAGE" "96"
					( Origin gFrontEnd )
				)
				( attribute "ROOM" "PROC_RSTS_PGOODS"
					( Origin gFrontEnd )
				)
				( attribute "ROT" "0"
					( Origin gFrontEnd )
				)
				( attribute "SEC" "1"
					( Origin gPackager )
				)
				( attribute "TOLERANCE" "1.0%"
					( Origin gFrontEnd )
				)
				( attribute "VALUE" "64.9"
					( Origin gFrontEnd )
				)
				( attribute "VER" "2"
					( Origin gFrontEnd )
				)
				( attribute "WATTAGE" "1/16W"
					( Origin gFrontEnd )
				)
				( attribute "XY" "(975,2150)"
					( Origin gFrontEnd )
				)
				( attribute "CHIPS_PART_NAME" "RES"
					( Origin gPackager )
				)
				( attribute "CDS_PART_NAME" "RES_0402-64.9,1.0%,1/16W,CHIP,A"
					( Origin gPackager )
				)
				( objectStatus "R7M9" )
				( pin "a"
					( attribute "PN" "1"
						( Origin gPackager )
					)
					( objectStatus "R7M9.1" )
				)
				( pin "b"
					( attribute "PN" "2"
						( Origin gPackager )
					)
					( objectStatus "R7M9.2" )
				)
			)
			( gate "@baseboard_fab2_lib.baseboard_fab2(sch_1):page96_i30"
				( attribute "BOM_COST" "PROC_SIDEBAND"
					( Origin gFrontEnd )
				)
				( attribute "CDS_LIB" "mstr_discrete"
					( Origin gPackager )
				)
				( attribute "CDS_LOCATION" "R3D21"
					( Origin gPackager )
				)
				( attribute "CDS_SEC" "1"
					( Origin gPackager )
				)
				( attribute "LOCATION" "R3D21"
					( Origin gFrontEnd )
				)
				( attribute "MATERIAL" "CHIP"
					( Origin gFrontEnd )
				)
				( attribute "PACK_TYPE" "0402"
					( Origin gFrontEnd )
				)
				( attribute "PART_NUMBER" "G21796-298"
					( Origin gFrontEnd )
				)
				( attribute "PHYS_PAGE" "96"
					( Origin gFrontEnd )
				)
				( attribute "ROOM" "PROC_RSTS_PGOODS"
					( Origin gFrontEnd )
				)
				( attribute "ROT" "0"
					( Origin gFrontEnd )
				)
				( attribute "SEC" "1"
					( Origin gPackager )
				)
				( attribute "TOLERANCE" "1.0%"
					( Origin gFrontEnd )
				)
				( attribute "VALUE" "64.9"
					( Origin gFrontEnd )
				)
				( attribute "VER" "2"
					( Origin gFrontEnd )
				)
				( attribute "WATTAGE" "1/16W"
					( Origin gFrontEnd )
				)
				( attribute "XY" "(575,2150)"
					( Origin gFrontEnd )
				)
				( attribute "CHIPS_PART_NAME" "RES"
					( Origin gPackager )
				)
				( attribute "CDS_PART_NAME" "RES_0402-64.9,1.0%,1/16W,CHIP,A"
					( Origin gPackager )
				)
				( objectStatus "R3D21" )
				( pin "a"
					( attribute "PN" "1"
						( Origin gPackager )
					)
					( objectStatus "R3D21.1" )
				)
				( pin "b"
					( attribute "PN" "2"
						( Origin gPackager )
					)
					( objectStatus "R3D21.2" )
				)
			)
			( gate "@baseboard_fab2_lib.baseboard_fab2(sch_1):page96_i36"
				( attribute "BOM_COST" "PROC_SIDEBAND"
					( Origin gFrontEnd )
				)
				( attribute "CDS_LIB" "mstr_discrete"
					( Origin gPackager )
				)
				( attribute "CDS_LOCATION" "R3P36"
					( Origin gPackager )
				)
				( attribute "CDS_SEC" "1"
					( Origin gPackager )
				)
				( attribute "LOCATION" "R3P36"
					( Origin gFrontEnd )
				)
				( attribute "MATERIAL" "CHIP"
					( Origin gFrontEnd )
				)
				( attribute "PACK_TYPE" "0402"
					( Origin gFrontEnd )
				)
				( attribute "PART_NUMBER" "G21796-026"
					( Origin gFrontEnd )
				)
				( attribute "PHYS_PAGE" "96"
					( Origin gFrontEnd )
				)
				( attribute "ROOM" "PROC_RSTS_PGOODS"
					( Origin gFrontEnd )
				)
				( attribute "ROT" "0"
					( Origin gFrontEnd )
				)
				( attribute "SEC" "1"
					( Origin gPackager )
				)
				( attribute "TOLERANCE" "1%"
					( Origin gFrontEnd )
				)
				( attribute "VALUE" "1.00K"
					( Origin gFrontEnd )
				)
				( attribute "VER" "2"
					( Origin gFrontEnd )
				)
				( attribute "WATTAGE" "1/16W"
					( Origin gFrontEnd )
				)
				( attribute "XY" "(-2100,4650)"
					( Origin gFrontEnd )
				)
				( attribute "CHIPS_PART_NAME" "RES"
					( Origin gPackager )
				)
				( attribute "CDS_PART_NAME" "RES_0402-1.00K,1%,1/16W,CHIP,GA"
					( Origin gPackager )
				)
				( objectStatus "R3P36" )
				( pin "a"
					( attribute "PN" "1"
						( Origin gPackager )
					)
					( objectStatus "R3P36.1" )
				)
				( pin "b"
					( attribute "PN" "2"
						( Origin gPackager )
					)
					( objectStatus "R3P36.2" )
				)
			)
			( gate "@baseboard_fab2_lib.baseboard_fab2(sch_1):page96_i42"
				( attribute "BOM_COST" "PROC_SIDEBAND"
					( Origin gFrontEnd )
				)
				( attribute "CDS_LIB" "mstr_digital"
					( Origin gPackager )
				)
				( attribute "CDS_LOCATION" "U3P1"
					( Origin gPackager )
				)
				( attribute "CDS_SEC" "1"
					( Origin gPackager )
				)
				( attribute "LOCATION" "U3P1"
					( Origin gFrontEnd )
				)
				( attribute "MATERIAL" "IC"
					( Origin gFrontEnd )
				)
				( attribute "PACK_TYPE" "SM"
					( Origin gFrontEnd )
				)
				( attribute "PART_NUMBER" "D66151-001"
					( Origin gFrontEnd )
				)
				( attribute "PHYS_PAGE" "96"
					( Origin gFrontEnd )
				)
				( attribute "ROOM" "PROC_RSTS_PGOODS"
					( Origin gFrontEnd )
				)
				( attribute "ROT" "0"
					( Origin gFrontEnd )
				)
				( attribute "SEC" "1"
					( Origin gPackager )
				)
				( attribute "VER" "1"
					( Origin gFrontEnd )
				)
				( attribute "XY" "(-875,4100)"
					( Origin gFrontEnd )
				)
				( attribute "CHIPS_PART_NAME" "GTL2014"
					( Origin gPackager )
				)
				( attribute "CDS_PART_NAME" "GTL2014_SM-IC,D66151-001"
					( Origin gPackager )
				)
				( objectStatus "U3P1" )
				( pin "a0"
					( attribute "PN" "13"
						( Origin gPackager )
					)
					( objectStatus "U3P1.13" )
				)
				( pin "a1"
					( attribute "PN" "12"
						( Origin gPackager )
					)
					( objectStatus "U3P1.12" )
				)
				( pin "a2"
					( attribute "PN" "10"
						( Origin gPackager )
					)
					( objectStatus "U3P1.10" )
				)
				( pin "a3"
					( attribute "PN" "9"
						( Origin gPackager )
					)
					( objectStatus "U3P1.9" )
				)
				( pin "b0"
					( attribute "PN" "2"
						( Origin gPackager )
					)
					( objectStatus "U3P1.2" )
				)
				( pin "b1"
					( attribute "PN" "3"
						( Origin gPackager )
					)
					( objectStatus "U3P1.3" )
				)
				( pin "b2"
					( attribute "PN" "5"
						( Origin gPackager )
					)
					( objectStatus "U3P1.5" )
				)
				( pin "b3"
					( attribute "PN" "6"
						( Origin gPackager )
					)
					( objectStatus "U3P1.6" )
				)
				( pin "dir"
					( attribute "PN" "1"
						( Origin gPackager )
					)
					( objectStatus "U3P1.1" )
				)
				( pin "gnd(0)"
					( attribute "PN" "7"
						( Origin gPackager )
					)
					( objectStatus "U3P1.7" )
				)
				( pin "gnd(1)"
					( attribute "PN" "8"
						( Origin gPackager )
					)
					( objectStatus "U3P1.8" )
				)
				( pin "gnd(2)"
					( attribute "PN" "11"
						( Origin gPackager )
					)
					( objectStatus "U3P1.11" )
				)
				( pin "vcc"
					( attribute "PN" "14"
						( Origin gPackager )
					)
					( objectStatus "U3P1.14" )
				)
				( pin "vref"
					( attribute "PN" "4"
						( Origin gPackager )
					)
					( objectStatus "U3P1.4" )
				)
			)
			( gate "@baseboard_fab2_lib.baseboard_fab2(sch_1):page96_i46"
				( attribute "BOM_COST" "PROC_SIDEBAND"
					( Origin gFrontEnd )
				)
				( attribute "CDS_LIB" "mstr_digital"
					( Origin gPackager )
				)
				( attribute "CDS_LOCATION" "U4C2"
					( Origin gPackager )
				)
				( attribute "CDS_SEC" "1"
					( Origin gPackager )
				)
				( attribute "LOCATION" "U4C2"
					( Origin gFrontEnd )
				)
				( attribute "MATERIAL" "IC"
					( Origin gFrontEnd )
				)
				( attribute "PACK_TYPE" "SM"
					( Origin gFrontEnd )
				)
				( attribute "PART_NUMBER" "D66151-001"
					( Origin gFrontEnd )
				)
				( attribute "PHYS_PAGE" "96"
					( Origin gFrontEnd )
				)
				( attribute "ROOM" "PROC_RSTS_PGOODS"
					( Origin gFrontEnd )
				)
				( attribute "ROT" "0"
					( Origin gFrontEnd )
				)
				( attribute "SEC" "1"
					( Origin gPackager )
				)
				( attribute "VER" "1"
					( Origin gFrontEnd )
				)
				( attribute "XY" "(-875,1800)"
					( Origin gFrontEnd )
				)
				( attribute "CHIPS_PART_NAME" "GTL2014"
					( Origin gPackager )
				)
				( attribute "CDS_PART_NAME" "GTL2014_SM-IC,D66151-001"
					( Origin gPackager )
				)
				( objectStatus "U4C2" )
				( pin "a0"
					( attribute "PN" "13"
						( Origin gPackager )
					)
					( objectStatus "U4C2.13" )
				)
				( pin "a1"
					( attribute "PN" "12"
						( Origin gPackager )
					)
					( objectStatus "U4C2.12" )
				)
				( pin "a2"
					( attribute "PN" "10"
						( Origin gPackager )
					)
					( objectStatus "U4C2.10" )
				)
				( pin "a3"
					( attribute "PN" "9"
						( Origin gPackager )
					)
					( objectStatus "U4C2.9" )
				)
				( pin "b0"
					( attribute "PN" "2"
						( Origin gPackager )
					)
					( objectStatus "U4C2.2" )
				)
				( pin "b1"
					( attribute "PN" "3"
						( Origin gPackager )
					)
					( objectStatus "U4C2.3" )
				)
				( pin "b2"
					( attribute "PN" "5"
						( Origin gPackager )
					)
					( objectStatus "U4C2.5" )
				)
				( pin "b3"
					( attribute "PN" "6"
						( Origin gPackager )
					)
					( objectStatus "U4C2.6" )
				)
				( pin "dir"
					( attribute "PN" "1"
						( Origin gPackager )
					)
					( objectStatus "U4C2.1" )
				)
				( pin "gnd(0)"
					( attribute "PN" "7"
						( Origin gPackager )
					)
					( objectStatus "U4C2.7" )
				)
				( pin "gnd(1)"
					( attribute "PN" "8"
						( Origin gPackager )
					)
					( objectStatus "U4C2.8" )
				)
				( pin "gnd(2)"
					( attribute "PN" "11"
						( Origin gPackager )
					)
					( objectStatus "U4C2.11" )
				)
				( pin "vcc"
					( attribute "PN" "14"
						( Origin gPackager )
					)
					( objectStatus "U4C2.14" )
				)
				( pin "vref"
					( attribute "PN" "4"
						( Origin gPackager )
					)
					( objectStatus "U4C2.4" )
				)
			)
			( gate "@baseboard_fab2_lib.baseboard_fab2(sch_1):page96_i55"
				( attribute "BOM_COST" "PROC_SIDEBAND"
					( Origin gFrontEnd )
				)
				( attribute "CDS_LIB" "mstr_discrete"
					( Origin gPackager )
				)
				( attribute "CDS_LOCATION" "R4C8"
					( Origin gPackager )
				)
				( attribute "CDS_SEC" "1"
					( Origin gPackager )
				)
				( attribute "LOCATION" "R4C8"
					( Origin gFrontEnd )
				)
				( attribute "MATERIAL" "CHIP"
					( Origin gFrontEnd )
				)
				( attribute "PACK_TYPE" "0402"
					( Origin gFrontEnd )
				)
				( attribute "PART_NUMBER" "G21796-026"
					( Origin gFrontEnd )
				)
				( attribute "PHYS_PAGE" "96"
					( Origin gFrontEnd )
				)
				( attribute "ROOM" "PROC_RSTS_PGOODS"
					( Origin gFrontEnd )
				)
				( attribute "ROT" "0"
					( Origin gFrontEnd )
				)
				( attribute "SEC" "1"
					( Origin gPackager )
				)
				( attribute "TOLERANCE" "1%"
					( Origin gFrontEnd )
				)
				( attribute "VALUE" "1.00K"
					( Origin gFrontEnd )
				)
				( attribute "VER" "2"
					( Origin gFrontEnd )
				)
				( attribute "WATTAGE" "1/16W"
					( Origin gFrontEnd )
				)
				( attribute "XY" "(-2100,2350)"
					( Origin gFrontEnd )
				)
				( attribute "CHIPS_PART_NAME" "RES"
					( Origin gPackager )
				)
				( attribute "CDS_PART_NAME" "RES_0402-1.00K,1%,1/16W,CHIP,GA"
					( Origin gPackager )
				)
				( objectStatus "R4C8" )
				( pin "a"
					( attribute "PN" "1"
						( Origin gPackager )
					)
					( objectStatus "R4C8.1" )
				)
				( pin "b"
					( attribute "PN" "2"
						( Origin gPackager )
					)
					( objectStatus "R4C8.2" )
				)
			)
			( gate "@baseboard_fab2_lib.baseboard_fab2(sch_1):page96_i69"
				( attribute "BOM_COST" "PROC_SIDEBAND"
					( Origin gFrontEnd )
				)
				( attribute "CDS_LIB" "mstr_discrete"
					( Origin gPackager )
				)
				( attribute "CDS_LOCATION" "R4C9"
					( Origin gPackager )
				)
				( attribute "CDS_SEC" "1"
					( Origin gPackager )
				)
				( attribute "LOCATION" "R4C9"
					( Origin gFrontEnd )
				)
				( attribute "MATERIAL" "CHIP"
					( Origin gFrontEnd )
				)
				( attribute "PACK_TYPE" "0402"
					( Origin gFrontEnd )
				)
				( attribute "PART_NUMBER" "G21796-026"
					( Origin gFrontEnd )
				)
				( attribute "PHYS_PAGE" "96"
					( Origin gFrontEnd )
				)
				( attribute "ROOM" "PROC_RSTS_PGOODS"
					( Origin gFrontEnd )
				)
				( attribute "ROT" "0"
					( Origin gFrontEnd )
				)
				( attribute "SEC" "1"
					( Origin gFrontEnd )
				)
				( attribute "SEC_TYPE" "0402"
					( Origin gFrontEnd )
				)
				( attribute "TOLERANCE" "1%"
					( Origin gFrontEnd )
				)
				( attribute "VALUE" "1.00K"
					( Origin gFrontEnd )
				)
				( attribute "VER" "1"
					( Origin gFrontEnd )
				)
				( attribute "WATTAGE" "1/16W"
					( Origin gFrontEnd )
				)
				( attribute "XY" "(-2400,2050)"
					( Origin gFrontEnd )
				)
				( attribute "CHIPS_PART_NAME" "RES"
					( Origin gPackager )
				)
				( attribute "CDS_PART_NAME" "RES_0402-1.00K,1%,1/16W,CHIP,GA"
					( Origin gPackager )
				)
				( objectStatus "R4C9" )
				( pin "a"
					( attribute "PN" "1"
						( Origin gPackager )
					)
					( objectStatus "R4C9.1" )
				)
				( pin "b"
					( attribute "PN" "2"
						( Origin gPackager )
					)
					( objectStatus "R4C9.2" )
				)
			)
			( gate "@baseboard_fab2_lib.baseboard_fab2(sch_1):page96_i71"
				( attribute "BOM_COST" "PROC_SIDEBAND"
					( Origin gFrontEnd )
				)
				( attribute "CDS_LIB" "mstr_discrete"
					( Origin gPackager )
				)
				( attribute "CDS_LOCATION" "R3P32"
					( Origin gPackager )
				)
				( attribute "CDS_SEC" "1"
					( Origin gPackager )
				)
				( attribute "LOCATION" "R3P32"
					( Origin gFrontEnd )
				)
				( attribute "MATERIAL" "CHIP"
					( Origin gFrontEnd )
				)
				( attribute "PACK_TYPE" "0402"
					( Origin gFrontEnd )
				)
				( attribute "PART_NUMBER" "G21796-026"
					( Origin gFrontEnd )
				)
				( attribute "PHYS_PAGE" "96"
					( Origin gFrontEnd )
				)
				( attribute "ROOM" "PROC_RSTS_PGOODS"
					( Origin gFrontEnd )
				)
				( attribute "ROT" "0"
					( Origin gFrontEnd )
				)
				( attribute "SEC" "1"
					( Origin gFrontEnd )
				)
				( attribute "SEC_TYPE" "0402"
					( Origin gFrontEnd )
				)
				( attribute "TOLERANCE" "1%"
					( Origin gFrontEnd )
				)
				( attribute "VALUE" "1.00K"
					( Origin gFrontEnd )
				)
				( attribute "VER" "1"
					( Origin gFrontEnd )
				)
				( attribute "WATTAGE" "1/16W"
					( Origin gFrontEnd )
				)
				( attribute "XY" "(-2400,4350)"
					( Origin gFrontEnd )
				)
				( attribute "CHIPS_PART_NAME" "RES"
					( Origin gPackager )
				)
				( attribute "CDS_PART_NAME" "RES_0402-1.00K,1%,1/16W,CHIP,GA"
					( Origin gPackager )
				)
				( objectStatus "R3P32" )
				( pin "a"
					( attribute "PN" "1"
						( Origin gPackager )
					)
					( objectStatus "R3P32.1" )
				)
				( pin "b"
					( attribute "PN" "2"
						( Origin gPackager )
					)
					( objectStatus "R3P32.2" )
				)
			)
			( gate "@baseboard_fab2_lib.baseboard_fab2(sch_1):page96_i73"
				( attribute "BOM_COST" "PROC_SIDEBAND"
					( Origin gFrontEnd )
				)
				( attribute "CDS_LIB" "dev_discrete"
					( Origin gPackager )
				)
				( attribute "CDS_LOCATION" "C3P42"
					( Origin gPackager )
				)
				( attribute "CDS_SEC" "1"
					( Origin gPackager )
				)
				( attribute "LOCATION" "C3P42"
					( Origin gFrontEnd )
				)
				( attribute "MATERIAL" "X6S"
					( Origin gFrontEnd )
				)
				( attribute "PACK_TYPE" "0402V"
					( Origin gFrontEnd )
				)
				( attribute "PART_NUMBER" "D97712-004"
					( Origin gFrontEnd )
				)
				( attribute "PHYS_PAGE" "96"
					( Origin gFrontEnd )
				)
				( attribute "ROOM" "PROC_RSTS_PGOODS"
					( Origin gFrontEnd )
				)
				( attribute "ROT" "0"
					( Origin gFrontEnd )
				)
				( attribute "SEC" "1"
					( Origin gFrontEnd )
				)
				( attribute "SEC_TYPE" "0402V"
					( Origin gFrontEnd )
				)
				( attribute "TOLERANCE" "10%"
					( Origin gFrontEnd )
				)
				( attribute "VALUE" "1.0UF"
					( Origin gFrontEnd )
				)
				( attribute "VER" "1"
					( Origin gFrontEnd )
				)
				( attribute "VOLTAGE" "6.3V"
					( Units "uVoltage" "V" 1.000000)
					( Origin gFrontEnd )
				)
				( attribute "XY" "(-1650,4650)"
					( Origin gFrontEnd )
				)
				( attribute "CHIPS_PART_NAME" "CAP_A"
					( Origin gPackager )
				)
				( attribute "CDS_PART_NAME" "CAP_A_0402V-1.0UF,6.3V,10%,X6SA"
					( Origin gPackager )
				)
				( objectStatus "C3P42" )
				( pin "a"
					( attribute "PN" "1"
						( Origin gPackager )
					)
					( objectStatus "C3P42.1" )
				)
				( pin "b"
					( attribute "PN" "2"
						( Origin gPackager )
					)
					( objectStatus "C3P42.2" )
				)
			)
			( gate "@baseboard_fab2_lib.baseboard_fab2(sch_1):page96_i75"
				( attribute "BOM_COST" "PROC_SIDEBAND"
					( Origin gFrontEnd )
				)
				( attribute "CDS_LIB" "dev_discrete"
					( Origin gPackager )
				)
				( attribute "CDS_LOCATION" "C4C3"
					( Origin gPackager )
				)
				( attribute "CDS_SEC" "1"
					( Origin gPackager )
				)
				( attribute "LOCATION" "C4C3"
					( Origin gFrontEnd )
				)
				( attribute "MATERIAL" "X6S"
					( Origin gFrontEnd )
				)
				( attribute "PACK_TYPE" "0402V"
					( Origin gFrontEnd )
				)
				( attribute "PART_NUMBER" "D97712-004"
					( Origin gFrontEnd )
				)
				( attribute "PHYS_PAGE" "96"
					( Origin gFrontEnd )
				)
				( attribute "ROOM" "PROC_RSTS_PGOODS"
					( Origin gFrontEnd )
				)
				( attribute "ROT" "0"
					( Origin gFrontEnd )
				)
				( attribute "SEC" "1"
					( Origin gFrontEnd )
				)
				( attribute "SEC_TYPE" "0402V"
					( Origin gFrontEnd )
				)
				( attribute "TOLERANCE" "10%"
					( Origin gFrontEnd )
				)
				( attribute "VALUE" "1.0UF"
					( Origin gFrontEnd )
				)
				( attribute "VER" "1"
					( Origin gFrontEnd )
				)
				( attribute "VOLTAGE" "6.3V"
					( Units "uVoltage" "V" 1.000000)
					( Origin gFrontEnd )
				)
				( attribute "XY" "(-1725,2325)"
					( Origin gFrontEnd )
				)
				( attribute "CHIPS_PART_NAME" "CAP_A"
					( Origin gPackager )
				)
				( attribute "CDS_PART_NAME" "CAP_A_0402V-1.0UF,6.3V,10%,X6SA"
					( Origin gPackager )
				)
				( objectStatus "C4C3" )
				( pin "a"
					( attribute "PN" "1"
						( Origin gPackager )
					)
					( objectStatus "C4C3.1" )
				)
				( pin "b"
					( attribute "PN" "2"
						( Origin gPackager )
					)
					( objectStatus "C4C3.2" )
				)
			)
			( gate "@baseboard_fab2_lib.baseboard_fab2(sch_1):page97_i33"
				( attribute "BOM_COST" "PROC_SIDEBAND"
					( Origin gFrontEnd )
				)
				( attribute "CDS_LIB" "mstr_discrete"
					( Origin gPackager )
				)
				( attribute "CDS_LOCATION" "R3D18"
					( Origin gPackager )
				)
				( attribute "CDS_SEC" "1"
					( Origin gPackager )
				)
				( attribute "LOCATION" "R3D18"
					( Origin gFrontEnd )
				)
				( attribute "MATERIAL" "CHIP"
					( Origin gFrontEnd )
				)
				( attribute "PACK_TYPE" "0402"
					( Origin gFrontEnd )
				)
				( attribute "PART_NUMBER" "G21497-005"
					( Origin gFrontEnd )
				)
				( attribute "PHYS_PAGE" "97"
					( Origin gFrontEnd )
				)
				( attribute "ROOM" "PROC_SIDEBAND"
					( Origin gFrontEnd )
				)
				( attribute "ROT" "0"
					( Origin gFrontEnd )
				)
				( attribute "SEC" "1"
					( Origin gPackager )
				)
				( attribute "TOLERANCE" "5%"
					( Origin gFrontEnd )
				)
				( attribute "VALUE" "0.0"
					( Origin gFrontEnd )
				)
				( attribute "VER" "1"
					( Origin gFrontEnd )
				)
				( attribute "WATTAGE" "1/16W"
					( Origin gFrontEnd )
				)
				( attribute "XY" "(-2000,4225)"
					( Origin gFrontEnd )
				)
				( attribute "CHIPS_PART_NAME" "RES"
					( Origin gPackager )
				)
				( attribute "CDS_PART_NAME" "RES_0402-0.0,5%,1/16W,CHIP,G21A"
					( Origin gPackager )
				)
				( objectStatus "R3D18" )
				( pin "a"
					( attribute "PN" "1"
						( Origin gPackager )
					)
					( objectStatus "R3D18.1" )
				)
				( pin "b"
					( attribute "PN" "2"
						( Origin gPackager )
					)
					( objectStatus "R3D18.2" )
				)
			)
			( gate "@baseboard_fab2_lib.baseboard_fab2(sch_1):page97_i42"
				( attribute "CDS_LIB" "mstr_discrete"
					( Origin gPackager )
				)
				( attribute "CDS_LOCATION" "R4R4"
					( Origin gPackager )
				)
				( attribute "CDS_SEC" "1"
					( Origin gPackager )
				)
				( attribute "LOCATION" "R4R4"
					( Origin gFrontEnd )
				)
				( attribute "MATERIAL" "CHIP"
					( Origin gFrontEnd )
				)
				( attribute "PACK_TYPE" "0402"
					( Origin gFrontEnd )
				)
				( attribute "PART_NUMBER" "G21796-009"
					( Origin gFrontEnd )
				)
				( attribute "PHYS_PAGE" "97"
					( Origin gFrontEnd )
				)
				( attribute "ROOM" "PROC_SIDEBAND"
					( Origin gFrontEnd )
				)
				( attribute "ROT" "0"
					( Origin gFrontEnd )
				)
				( attribute "SEC" "1"
					( Origin gPackager )
				)
				( attribute "TOLERANCE" "1%"
					( Origin gFrontEnd )
				)
				( attribute "VALUE" "150.0"
					( Origin gFrontEnd )
				)
				( attribute "VER" "2"
					( Origin gFrontEnd )
				)
				( attribute "WATTAGE" "1/16W"
					( Origin gFrontEnd )
				)
				( attribute "XY" "(-2700,4525)"
					( Origin gFrontEnd )
				)
				( attribute "CHIPS_PART_NAME" "RES"
					( Origin gPackager )
				)
				( attribute "CDS_PART_NAME" "RES_0402-150.0,1%,1/16W,CHIP,GA"
					( Origin gPackager )
				)
				( objectStatus "R4R4" )
				( pin "a"
					( attribute "PN" "1"
						( Origin gPackager )
					)
					( objectStatus "R4R4.1" )
				)
				( pin "b"
					( attribute "PN" "2"
						( Origin gPackager )
					)
					( objectStatus "R4R4.2" )
				)
			)
			( gate "@baseboard_fab2_lib.baseboard_fab2(sch_1):page97_i44"
				( attribute "CDS_LIB" "mstr_discrete"
					( Origin gPackager )
				)
				( attribute "CDS_LOCATION" "R7P20"
					( Origin gPackager )
				)
				( attribute "CDS_SEC" "1"
					( Origin gPackager )
				)
				( attribute "LOCATION" "R7P20"
					( Origin gFrontEnd )
				)
				( attribute "MATERIAL" "CHIP"
					( Origin gFrontEnd )
				)
				( attribute "PACK_TYPE" "0402"
					( Origin gFrontEnd )
				)
				( attribute "PART_NUMBER" "G21796-009"
					( Origin gFrontEnd )
				)
				( attribute "PHYS_PAGE" "97"
					( Origin gFrontEnd )
				)
				( attribute "ROOM" "PROC_SIDEBAND"
					( Origin gFrontEnd )
				)
				( attribute "ROT" "0"
					( Origin gFrontEnd )
				)
				( attribute "SEC" "1"
					( Origin gPackager )
				)
				( attribute "TOLERANCE" "1%"
					( Origin gFrontEnd )
				)
				( attribute "VALUE" "150.0"
					( Origin gFrontEnd )
				)
				( attribute "VER" "2"
					( Origin gFrontEnd )
				)
				( attribute "WATTAGE" "1/16W"
					( Origin gFrontEnd )
				)
				( attribute "XY" "(-1200,4525)"
					( Origin gFrontEnd )
				)
				( attribute "CHIPS_PART_NAME" "RES"
					( Origin gPackager )
				)
				( attribute "CDS_PART_NAME" "RES_0402-150.0,1%,1/16W,CHIP,GA"
					( Origin gPackager )
				)
				( objectStatus "R7P20" )
				( pin "a"
					( attribute "PN" "1"
						( Origin gPackager )
					)
					( objectStatus "R7P20.1" )
				)
				( pin "b"
					( attribute "PN" "2"
						( Origin gPackager )
					)
					( objectStatus "R7P20.2" )
				)
			)
			( gate "@baseboard_fab2_lib.baseboard_fab2(sch_1):page97_i72"
				( attribute "BOM_COST" "PROC_SIDEBAND"
					( Origin gFrontEnd )
				)
				( attribute "CDS_LIB" "mstr_discrete"
					( Origin gPackager )
				)
				( attribute "CDS_LOCATION" "R4P21"
					( Origin gPackager )
				)
				( attribute "CDS_SEC" "1"
					( Origin gPackager )
				)
				( attribute "LOCATION" "R4P21"
					( Origin gFrontEnd )
				)
				( attribute "MATERIAL" "CHIP"
					( Origin gFrontEnd )
				)
				( attribute "PACK_TYPE" "0402"
					( Origin gFrontEnd )
				)
				( attribute "PART_NUMBER" "G21796-294"
					( Origin gFrontEnd )
				)
				( attribute "PHYS_PAGE" "97"
					( Origin gFrontEnd )
				)
				( attribute "ROOM" "PROC_SIDEBAND"
					( Origin gFrontEnd )
				)
				( attribute "ROT" "0"
					( Origin gFrontEnd )
				)
				( attribute "SEC" "1"
					( Origin gFrontEnd )
				)
				( attribute "SEC_TYPE" "0402"
					( Origin gFrontEnd )
				)
				( attribute "TOLERANCE" "1.0%"
					( Origin gFrontEnd )
				)
				( attribute "VALUE" "240"
					( Origin gFrontEnd )
				)
				( attribute "VER" "1"
					( Origin gFrontEnd )
				)
				( attribute "WATTAGE" "1/16W"
					( Origin gFrontEnd )
				)
				( attribute "XY" "(-2625,1425)"
					( Origin gFrontEnd )
				)
				( attribute "CHIPS_PART_NAME" "RES"
					( Origin gPackager )
				)
				( attribute "CDS_PART_NAME" "RES_0402-240,1.0%,1/16W,CHIP,GA"
					( Origin gPackager )
				)
				( objectStatus "R4P21" )
				( pin "a"
					( attribute "PN" "1"
						( Origin gPackager )
					)
					( objectStatus "R4P21.1" )
				)
				( pin "b"
					( attribute "PN" "2"
						( Origin gPackager )
					)
					( objectStatus "R4P21.2" )
				)
			)
			( gate "@baseboard_fab2_lib.baseboard_fab2(sch_1):page97_i76"
				( attribute "BOM_COST" "PROC_SIDEBAND"
					( Origin gFrontEnd )
				)
				( attribute "CDS_LIB" "mstr_discrete"
					( Origin gPackager )
				)
				( attribute "CDS_LOCATION" "R4C10"
					( Origin gPackager )
				)
				( attribute "CDS_SEC" "1"
					( Origin gPackager )
				)
				( attribute "LOCATION" "R4C10"
					( Origin gFrontEnd )
				)
				( attribute "MATERIAL" "CHIP"
					( Origin gFrontEnd )
				)
				( attribute "PACK_TYPE" "0402"
					( Origin gFrontEnd )
				)
				( attribute "PART_NUMBER" "G21796-294"
					( Origin gFrontEnd )
				)
				( attribute "PHYS_PAGE" "97"
					( Origin gFrontEnd )
				)
				( attribute "ROOM" "PROC_SIDEBAND"
					( Origin gFrontEnd )
				)
				( attribute "ROT" "0"
					( Origin gFrontEnd )
				)
				( attribute "SEC" "1"
					( Origin gFrontEnd )
				)
				( attribute "SEC_TYPE" "0402"
					( Origin gFrontEnd )
				)
				( attribute "TOLERANCE" "1.0%"
					( Origin gFrontEnd )
				)
				( attribute "VALUE" "240"
					( Origin gFrontEnd )
				)
				( attribute "VER" "1"
					( Origin gFrontEnd )
				)
				( attribute "WATTAGE" "1/16W"
					( Origin gFrontEnd )
				)
				( attribute "XY" "(-2600,800)"
					( Origin gFrontEnd )
				)
				( attribute "CHIPS_PART_NAME" "RES"
					( Origin gPackager )
				)
				( attribute "CDS_PART_NAME" "RES_0402-240,1.0%,1/16W,CHIP,GA"
					( Origin gPackager )
				)
				( objectStatus "R4C10" )
				( pin "a"
					( attribute "PN" "1"
						( Origin gPackager )
					)
					( objectStatus "R4C10.1" )
				)
				( pin "b"
					( attribute "PN" "2"
						( Origin gPackager )
					)
					( objectStatus "R4C10.2" )
				)
			)
			( gate "@baseboard_fab2_lib.baseboard_fab2(sch_1):page97_i80"
				( attribute "CDS_LIB" "mstr_discrete"
					( Origin gPackager )
				)
				( attribute "CDS_LOCATION" "R4P5"
					( Origin gPackager )
				)
				( attribute "CDS_SEC" "1"
					( Origin gPackager )
				)
				( attribute "LOCATION" "R4P5"
					( Origin gFrontEnd )
				)
				( attribute "MATERIAL" "CHIP"
					( Origin gFrontEnd )
				)
				( attribute "PACK_TYPE" "0402"
					( Origin gFrontEnd )
				)
				( attribute "PART_NUMBER" "G21796-016"
					( Origin gFrontEnd )
				)
				( attribute "PHYS_PAGE" "97"
					( Origin gFrontEnd )
				)
				( attribute "ROOM" "CPU0"
					( Origin gFrontEnd )
				)
				( attribute "ROT" "0"
					( Origin gFrontEnd )
				)
				( attribute "SEC" "1"
					( Origin gFrontEnd )
				)
				( attribute "SEC_TYPE" "0402"
					( Origin gFrontEnd )
				)
				( attribute "TOLERANCE" "1%"
					( Origin gFrontEnd )
				)
				( attribute "VALUE" "10.0K"
					( Origin gFrontEnd )
				)
				( attribute "VER" "1"
					( Origin gFrontEnd )
				)
				( attribute "WATTAGE" "1/16W"
					( Origin gFrontEnd )
				)
				( attribute "XY" "(-2375,3175)"
					( Origin gFrontEnd )
				)
				( attribute "CHIPS_PART_NAME" "RES"
					( Origin gPackager )
				)
				( attribute "CDS_PART_NAME" "RES_0402-10.0K,1%,1/16W,CHIP,GA"
					( Origin gPackager )
				)
				( objectStatus "R4P5" )
				( pin "a"
					( attribute "PN" "1"
						( Origin gPackager )
					)
					( objectStatus "R4P5.1" )
				)
				( pin "b"
					( attribute "PN" "2"
						( Origin gPackager )
					)
					( objectStatus "R4P5.2" )
				)
			)
			( gate "@baseboard_fab2_lib.baseboard_fab2(sch_1):page97_i81"
				( attribute "CDS_LIB" "mstr_discrete"
					( Origin gPackager )
				)
				( attribute "CDS_LOCATION" "R7P13"
					( Origin gPackager )
				)
				( attribute "CDS_SEC" "1"
					( Origin gPackager )
				)
				( attribute "LOCATION" "R7P13"
					( Origin gFrontEnd )
				)
				( attribute "MATERIAL" "CHIP"
					( Origin gFrontEnd )
				)
				( attribute "PACK_TYPE" "0402"
					( Origin gFrontEnd )
				)
				( attribute "PART_NUMBER" "G21796-016"
					( Origin gFrontEnd )
				)
				( attribute "PHYS_PAGE" "97"
					( Origin gFrontEnd )
				)
				( attribute "ROOM" "CPU1"
					( Origin gFrontEnd )
				)
				( attribute "ROT" "0"
					( Origin gFrontEnd )
				)
				( attribute "SEC" "1"
					( Origin gFrontEnd )
				)
				( attribute "SEC_TYPE" "0402"
					( Origin gFrontEnd )
				)
				( attribute "TOLERANCE" "1%"
					( Origin gFrontEnd )
				)
				( attribute "VALUE" "10.0K"
					( Origin gFrontEnd )
				)
				( attribute "VER" "1"
					( Origin gFrontEnd )
				)
				( attribute "WATTAGE" "1/16W"
					( Origin gFrontEnd )
				)
				( attribute "XY" "(-2375,2825)"
					( Origin gFrontEnd )
				)
				( attribute "CHIPS_PART_NAME" "RES"
					( Origin gPackager )
				)
				( attribute "CDS_PART_NAME" "RES_0402-10.0K,1%,1/16W,CHIP,GA"
					( Origin gPackager )
				)
				( objectStatus "R7P13" )
				( pin "a"
					( attribute "PN" "1"
						( Origin gPackager )
					)
					( objectStatus "R7P13.1" )
				)
				( pin "b"
					( attribute "PN" "2"
						( Origin gPackager )
					)
					( objectStatus "R7P13.2" )
				)
			)
			( gate "@baseboard_fab2_lib.baseboard_fab2(sch_1):page98_i4"
				( attribute "BOM_COST" "PROC_SOCKET"
					( Origin gFrontEnd )
				)
				( attribute "CDS_LIB" "mstr_discrete"
					( Origin gPackager )
				)
				( attribute "CDS_LOCATION" "R4F5"
					( Origin gPackager )
				)
				( attribute "CDS_SEC" "1"
					( Origin gPackager )
				)
				( attribute "LOCATION" "R4F5"
					( Origin gFrontEnd )
				)
				( attribute "MATERIAL" "CHIP"
					( Origin gFrontEnd )
				)
				( attribute "PACK_TYPE" "0402"
					( Origin gFrontEnd )
				)
				( attribute "PART_NUMBER" "G21796-026"
					( Origin gFrontEnd )
				)
				( attribute "PHYS_PAGE" "98"
					( Origin gFrontEnd )
				)
				( attribute "ROOM" "PROC"
					( Origin gFrontEnd )
				)
				( attribute "ROT" "2"
					( Origin gFrontEnd )
				)
				( attribute "SEC" "1"
					( Origin gFrontEnd )
				)
				( attribute "SEC_TYPE" "0402"
					( Origin gFrontEnd )
				)
				( attribute "TOLERANCE" "1%"
					( Origin gFrontEnd )
				)
				( attribute "VALUE" "1.00K"
					( Origin gFrontEnd )
				)
				( attribute "VER" "2"
					( Origin gFrontEnd )
				)
				( attribute "WATTAGE" "1/16W"
					( Origin gFrontEnd )
				)
				( attribute "XY" "(-1725,3700)"
					( Origin gFrontEnd )
				)
				( attribute "CHIPS_PART_NAME" "RES"
					( Origin gPackager )
				)
				( attribute "CDS_PART_NAME" "RES_0402-1.00K,1%,1/16W,CHIP,GA"
					( Origin gPackager )
				)
				( objectStatus "R4F5" )
				( pin "a"
					( attribute "PN" "1"
						( Origin gPackager )
					)
					( objectStatus "R4F5.1" )
				)
				( pin "b"
					( attribute "PN" "2"
						( Origin gPackager )
					)
					( objectStatus "R4F5.2" )
				)
			)
			( gate "@baseboard_fab2_lib.baseboard_fab2(sch_1):page98_i5"
				( attribute "BOM_COST" "PROC_SOCKET"
					( Origin gFrontEnd )
				)
				( attribute "CDS_LIB" "mstr_discrete"
					( Origin gPackager )
				)
				( attribute "CDS_LOCATION" "R4F3"
					( Origin gPackager )
				)
				( attribute "CDS_SEC" "1"
					( Origin gPackager )
				)
				( attribute "LOCATION" "R4F3"
					( Origin gFrontEnd )
				)
				( attribute "MATERIAL" "CHIP"
					( Origin gFrontEnd )
				)
				( attribute "PACK_TYPE" "0402"
					( Origin gFrontEnd )
				)
				( attribute "PART_NUMBER" "G21796-274"
					( Origin gFrontEnd )
				)
				( attribute "PHYS_PAGE" "98"
					( Origin gFrontEnd )
				)
				( attribute "ROOM" "PROC"
					( Origin gFrontEnd )
				)
				( attribute "ROT" "0"
					( Origin gFrontEnd )
				)
				( attribute "SEC" "1"
					( Origin gFrontEnd )
				)
				( attribute "SEC_TYPE" "0402"
					( Origin gFrontEnd )
				)
				( attribute "TOLERANCE" "1.0%"
					( Origin gFrontEnd )
				)
				( attribute "VALUE" "2"
					( Origin gFrontEnd )
				)
				( attribute "VER" "1"
					( Origin gFrontEnd )
				)
				( attribute "WATTAGE" "1/16W"
					( Origin gFrontEnd )
				)
				( attribute "XY" "(-2025,4025)"
					( Origin gFrontEnd )
				)
				( attribute "CHIPS_PART_NAME" "RES"
					( Origin gPackager )
				)
				( attribute "CDS_PART_NAME" "RES_0402-2,1.0%,1/16W,CHIP,G21A"
					( Origin gPackager )
				)
				( objectStatus "R4F3" )
				( pin "a"
					( attribute "PN" "1"
						( Origin gPackager )
					)
					( objectStatus "R4F3.1" )
				)
				( pin "b"
					( attribute "PN" "2"
						( Origin gPackager )
					)
					( objectStatus "R4F3.2" )
				)
			)
			( gate "@baseboard_fab2_lib.baseboard_fab2(sch_1):page98_i7"
				( attribute "BOM_COST" "SM_CONTROLLER"
					( Origin gFrontEnd )
				)
				( attribute "CDS_LIB" "dev_discrete"
					( Origin gPackager )
				)
				( attribute "CDS_LOCATION" "C4F9"
					( Origin gPackager )
				)
				( attribute "CDS_SEC" "1"
					( Origin gPackager )
				)
				( attribute "LOCATION" "C4F9"
					( Origin gFrontEnd )
				)
				( attribute "MATERIAL" "X7R"
					( Origin gFrontEnd )
				)
				( attribute "PACK_TYPE" "0402V"
					( Origin gFrontEnd )
				)
				( attribute "PART_NUMBER" "A36096-045"
					( Origin gFrontEnd )
				)
				( attribute "PHYS_PAGE" "98"
					( Origin gFrontEnd )
				)
				( attribute "ROOM" "MEM"
					( Origin gFrontEnd )
				)
				( attribute "ROT" "0"
					( Origin gFrontEnd )
				)
				( attribute "SEC" "1"
					( Origin gFrontEnd )
				)
				( attribute "SEC_TYPE" "0402V"
					( Origin gFrontEnd )
				)
				( attribute "TOLERANCE" "10%"
					( Origin gFrontEnd )
				)
				( attribute "VALUE" "0.01UF"
					( Origin gFrontEnd )
				)
				( attribute "VER" "1"
					( Origin gFrontEnd )
				)
				( attribute "VOLTAGE" "25V"
					( Units "uVoltage" "V" 1.000000)
					( Origin gFrontEnd )
				)
				( attribute "XY" "(-2250,3725)"
					( Origin gFrontEnd )
				)
				( attribute "CHIPS_PART_NAME" "CAP_A"
					( Origin gPackager )
				)
				( attribute "CDS_PART_NAME" "CAP_A_0402V-0.01UF,25V,10%,X7RA"
					( Origin gPackager )
				)
				( objectStatus "C4F9" )
				( pin "a"
					( attribute "PN" "1"
						( Origin gPackager )
					)
					( objectStatus "C4F9.1" )
				)
				( pin "b"
					( attribute "PN" "2"
						( Origin gPackager )
					)
					( objectStatus "C4F9.2" )
				)
			)
			( gate "@baseboard_fab2_lib.baseboard_fab2(sch_1):page98_i9"
				( attribute "BOM_COST" "PROC_SOCKET"
					( Origin gFrontEnd )
				)
				( attribute "CDS_LIB" "mstr_discrete"
					( Origin gPackager )
				)
				( attribute "CDS_LOCATION" "R6M1"
					( Origin gPackager )
				)
				( attribute "CDS_SEC" "1"
					( Origin gPackager )
				)
				( attribute "LOCATION" "R6M1"
					( Origin gFrontEnd )
				)
				( attribute "MATERIAL" "CHIP"
					( Origin gFrontEnd )
				)
				( attribute "PACK_TYPE" "0402"
					( Origin gFrontEnd )
				)
				( attribute "PART_NUMBER" "G21796-026"
					( Origin gFrontEnd )
				)
				( attribute "PHYS_PAGE" "98"
					( Origin gFrontEnd )
				)
				( attribute "ROOM" "MEM"
					( Origin gFrontEnd )
				)
				( attribute "ROT" "2"
					( Origin gFrontEnd )
				)
				( attribute "SEC" "1"
					( Origin gFrontEnd )
				)
				( attribute "SEC_TYPE" "0402"
					( Origin gFrontEnd )
				)
				( attribute "TOLERANCE" "1%"
					( Origin gFrontEnd )
				)
				( attribute "VALUE" "1.00K"
					( Origin gFrontEnd )
				)
				( attribute "VER" "2"
					( Origin gFrontEnd )
				)
				( attribute "WATTAGE" "1/16W"
					( Origin gFrontEnd )
				)
				( attribute "XY" "(-1800,2675)"
					( Origin gFrontEnd )
				)
				( attribute "CHIPS_PART_NAME" "RES"
					( Origin gPackager )
				)
				( attribute "CDS_PART_NAME" "RES_0402-1.00K,1%,1/16W,CHIP,GA"
					( Origin gPackager )
				)
				( objectStatus "R6M1" )
				( pin "a"
					( attribute "PN" "1"
						( Origin gPackager )
					)
					( objectStatus "R6M1.1" )
				)
				( pin "b"
					( attribute "PN" "2"
						( Origin gPackager )
					)
					( objectStatus "R6M1.2" )
				)
			)
			( gate "@baseboard_fab2_lib.baseboard_fab2(sch_1):page98_i12"
				( attribute "BOM_COST" "PROC_SOCKET"
					( Origin gFrontEnd )
				)
				( attribute "CDS_LIB" "mstr_discrete"
					( Origin gPackager )
				)
				( attribute "CDS_LOCATION" "R6L16"
					( Origin gPackager )
				)
				( attribute "CDS_SEC" "1"
					( Origin gPackager )
				)
				( attribute "LOCATION" "R6L16"
					( Origin gFrontEnd )
				)
				( attribute "MATERIAL" "CHIP"
					( Origin gFrontEnd )
				)
				( attribute "PACK_TYPE" "0402"
					( Origin gFrontEnd )
				)
				( attribute "PART_NUMBER" "G21796-026"
					( Origin gFrontEnd )
				)
				( attribute "PHYS_PAGE" "98"
					( Origin gFrontEnd )
				)
				( attribute "ROOM" "PROC"
					( Origin gFrontEnd )
				)
				( attribute "ROT" "2"
					( Origin gFrontEnd )
				)
				( attribute "SEC" "1"
					( Origin gFrontEnd )
				)
				( attribute "SEC_TYPE" "0402"
					( Origin gFrontEnd )
				)
				( attribute "TOLERANCE" "1%"
					( Origin gFrontEnd )
				)
				( attribute "VALUE" "1.00K"
					( Origin gFrontEnd )
				)
				( attribute "VER" "2"
					( Origin gFrontEnd )
				)
				( attribute "WATTAGE" "1/16W"
					( Origin gFrontEnd )
				)
				( attribute "XY" "(-1725,2025)"
					( Origin gFrontEnd )
				)
				( attribute "CHIPS_PART_NAME" "RES"
					( Origin gPackager )
				)
				( attribute "CDS_PART_NAME" "RES_0402-1.00K,1%,1/16W,CHIP,GA"
					( Origin gPackager )
				)
				( objectStatus "R6L16" )
				( pin "a"
					( attribute "PN" "1"
						( Origin gPackager )
					)
					( objectStatus "R6L16.1" )
				)
				( pin "b"
					( attribute "PN" "2"
						( Origin gPackager )
					)
					( objectStatus "R6L16.2" )
				)
			)
			( gate "@baseboard_fab2_lib.baseboard_fab2(sch_1):page98_i14"
				( attribute "BOM_COST" "PROC_SOCKET"
					( Origin gFrontEnd )
				)
				( attribute "CDS_LIB" "mstr_discrete"
					( Origin gPackager )
				)
				( attribute "CDS_LOCATION" "R6M2"
					( Origin gPackager )
				)
				( attribute "CDS_SEC" "1"
					( Origin gPackager )
				)
				( attribute "LOCATION" "R6M2"
					( Origin gFrontEnd )
				)
				( attribute "MATERIAL" "CHIP"
					( Origin gFrontEnd )
				)
				( attribute "PACK_TYPE" "0402"
					( Origin gFrontEnd )
				)
				( attribute "PART_NUMBER" "G21796-274"
					( Origin gFrontEnd )
				)
				( attribute "PHYS_PAGE" "98"
					( Origin gFrontEnd )
				)
				( attribute "ROOM" "PROC"
					( Origin gFrontEnd )
				)
				( attribute "ROT" "0"
					( Origin gFrontEnd )
				)
				( attribute "SEC" "1"
					( Origin gFrontEnd )
				)
				( attribute "SEC_TYPE" "0402"
					( Origin gFrontEnd )
				)
				( attribute "TOLERANCE" "1.0%"
					( Origin gFrontEnd )
				)
				( attribute "VALUE" "2"
					( Origin gFrontEnd )
				)
				( attribute "VER" "1"
					( Origin gFrontEnd )
				)
				( attribute "WATTAGE" "1/16W"
					( Origin gFrontEnd )
				)
				( attribute "XY" "(-2025,2350)"
					( Origin gFrontEnd )
				)
				( attribute "CHIPS_PART_NAME" "RES"
					( Origin gPackager )
				)
				( attribute "CDS_PART_NAME" "RES_0402-2,1.0%,1/16W,CHIP,G21A"
					( Origin gPackager )
				)
				( objectStatus "R6M2" )
				( pin "a"
					( attribute "PN" "1"
						( Origin gPackager )
					)
					( objectStatus "R6M2.1" )
				)
				( pin "b"
					( attribute "PN" "2"
						( Origin gPackager )
					)
					( objectStatus "R6M2.2" )
				)
			)
			( gate "@baseboard_fab2_lib.baseboard_fab2(sch_1):page98_i33"
				( attribute "BOM_COST" "SM_CONTROLLER"
					( Origin gFrontEnd )
				)
				( attribute "CDS_LIB" "dev_discrete"
					( Origin gPackager )
				)
				( attribute "CDS_LOCATION" "C6M2"
					( Origin gPackager )
				)
				( attribute "CDS_SEC" "1"
					( Origin gPackager )
				)
				( attribute "LOCATION" "C6M2"
					( Origin gFrontEnd )
				)
				( attribute "MATERIAL" "X7R"
					( Origin gFrontEnd )
				)
				( attribute "PACK_TYPE" "0402V"
					( Origin gFrontEnd )
				)
				( attribute "PART_NUMBER" "A36096-045"
					( Origin gFrontEnd )
				)
				( attribute "PHYS_PAGE" "98"
					( Origin gFrontEnd )
				)
				( attribute "ROOM" "MEM"
					( Origin gFrontEnd )
				)
				( attribute "ROT" "0"
					( Origin gFrontEnd )
				)
				( attribute "SEC" "1"
					( Origin gFrontEnd )
				)
				( attribute "SEC_TYPE" "0402V"
					( Origin gFrontEnd )
				)
				( attribute "TOLERANCE" "10%"
					( Origin gFrontEnd )
				)
				( attribute "VALUE" "0.01UF"
					( Origin gFrontEnd )
				)
				( attribute "VER" "1"
					( Origin gFrontEnd )
				)
				( attribute "VOLTAGE" "25V"
					( Units "uVoltage" "V" 1.000000)
					( Origin gFrontEnd )
				)
				( attribute "XY" "(-2250,2050)"
					( Origin gFrontEnd )
				)
				( attribute "CHIPS_PART_NAME" "CAP_A"
					( Origin gPackager )
				)
				( attribute "CDS_PART_NAME" "CAP_A_0402V-0.01UF,25V,10%,X7RA"
					( Origin gPackager )
				)
				( objectStatus "C6M2" )
				( pin "a"
					( attribute "PN" "1"
						( Origin gPackager )
					)
					( objectStatus "C6M2.1" )
				)
				( pin "b"
					( attribute "PN" "2"
						( Origin gPackager )
					)
					( objectStatus "C6M2.2" )
				)
			)
			( gate "@baseboard_fab2_lib.baseboard_fab2(sch_1):page98_i36"
				( attribute "BOM_COST" "SM_CONTROLLER"
					( Origin gFrontEnd )
				)
				( attribute "CDS_LIB" "mstr_discrete"
					( Origin gPackager )
				)
				( attribute "CDS_LOCATION" "R4F4"
					( Origin gPackager )
				)
				( attribute "CDS_SEC" "1"
					( Origin gPackager )
				)
				( attribute "LOCATION" "R4F4"
					( Origin gFrontEnd )
				)
				( attribute "MATERIAL" "CHIP"
					( Origin gFrontEnd )
				)
				( attribute "PACK_TYPE" "0402"
					( Origin gFrontEnd )
				)
				( attribute "PART_NUMBER" "G21796-026"
					( Origin gFrontEnd )
				)
				( attribute "PHYS_PAGE" "98"
					( Origin gFrontEnd )
				)
				( attribute "ROOM" "MEM"
					( Origin gFrontEnd )
				)
				( attribute "ROT" "2"
					( Origin gFrontEnd )
				)
				( attribute "SEC" "1"
					( Origin gFrontEnd )
				)
				( attribute "SEC_TYPE" "0402"
					( Origin gFrontEnd )
				)
				( attribute "TOLERANCE" "1%"
					( Origin gFrontEnd )
				)
				( attribute "VALUE" "1.00K"
					( Origin gFrontEnd )
				)
				( attribute "VER" "2"
					( Origin gFrontEnd )
				)
				( attribute "WATTAGE" "1/16W"
					( Origin gFrontEnd )
				)
				( attribute "XY" "(-1800,4350)"
					( Origin gFrontEnd )
				)
				( attribute "CHIPS_PART_NAME" "RES"
					( Origin gPackager )
				)
				( attribute "CDS_PART_NAME" "RES_0402-1.00K,1%,1/16W,CHIP,GA"
					( Origin gPackager )
				)
				( objectStatus "R4F4" )
				( pin "a"
					( attribute "PN" "1"
						( Origin gPackager )
					)
					( objectStatus "R4F4.1" )
				)
				( pin "b"
					( attribute "PN" "2"
						( Origin gPackager )
					)
					( objectStatus "R4F4.2" )
				)
			)
			( gate "@baseboard_fab2_lib.baseboard_fab2(sch_1):page98_i38"
				( attribute "BOM_COST" "SM_CONTROLLER"
					( Origin gFrontEnd )
				)
				( attribute "CDS_LIB" "mstr_discrete"
					( Origin gPackager )
				)
				( attribute "CDS_LOCATION" "R4G2"
					( Origin gPackager )
				)
				( attribute "CDS_SEC" "1"
					( Origin gPackager )
				)
				( attribute "LOCATION" "R4G2"
					( Origin gFrontEnd )
				)
				( attribute "MATERIAL" "CHIP"
					( Origin gFrontEnd )
				)
				( attribute "PACK_TYPE" "0402"
					( Origin gFrontEnd )
				)
				( attribute "PART_NUMBER" "G21796-026"
					( Origin gFrontEnd )
				)
				( attribute "PHYS_PAGE" "98"
					( Origin gFrontEnd )
				)
				( attribute "ROOM" "MEM"
					( Origin gFrontEnd )
				)
				( attribute "ROT" "2"
					( Origin gFrontEnd )
				)
				( attribute "SEC" "1"
					( Origin gFrontEnd )
				)
				( attribute "SEC_TYPE" "0402"
					( Origin gFrontEnd )
				)
				( attribute "TOLERANCE" "1%"
					( Origin gFrontEnd )
				)
				( attribute "VALUE" "1.00K"
					( Origin gFrontEnd )
				)
				( attribute "VER" "2"
					( Origin gFrontEnd )
				)
				( attribute "WATTAGE" "1/16W"
					( Origin gFrontEnd )
				)
				( attribute "XY" "(250,4350)"
					( Origin gFrontEnd )
				)
				( attribute "CHIPS_PART_NAME" "RES"
					( Origin gPackager )
				)
				( attribute "CDS_PART_NAME" "RES_0402-1.00K,1%,1/16W,CHIP,GA"
					( Origin gPackager )
				)
				( objectStatus "R4G2" )
				( pin "a"
					( attribute "PN" "1"
						( Origin gPackager )
					)
					( objectStatus "R4G2.1" )
				)
				( pin "b"
					( attribute "PN" "2"
						( Origin gPackager )
					)
					( objectStatus "R4G2.2" )
				)
			)
			( gate "@baseboard_fab2_lib.baseboard_fab2(sch_1):page98_i40"
				( attribute "BOM_COST" "PROC_SOCKET"
					( Origin gFrontEnd )
				)
				( attribute "CDS_LIB" "mstr_discrete"
					( Origin gPackager )
				)
				( attribute "CDS_LOCATION" "R4G3"
					( Origin gPackager )
				)
				( attribute "CDS_SEC" "1"
					( Origin gPackager )
				)
				( attribute "LOCATION" "R4G3"
					( Origin gFrontEnd )
				)
				( attribute "MATERIAL" "CHIP"
					( Origin gFrontEnd )
				)
				( attribute "PACK_TYPE" "0402"
					( Origin gFrontEnd )
				)
				( attribute "PART_NUMBER" "G21796-026"
					( Origin gFrontEnd )
				)
				( attribute "PHYS_PAGE" "98"
					( Origin gFrontEnd )
				)
				( attribute "ROOM" "PROC"
					( Origin gFrontEnd )
				)
				( attribute "ROT" "2"
					( Origin gFrontEnd )
				)
				( attribute "SEC" "1"
					( Origin gFrontEnd )
				)
				( attribute "SEC_TYPE" "0402"
					( Origin gFrontEnd )
				)
				( attribute "TOLERANCE" "1%"
					( Origin gFrontEnd )
				)
				( attribute "VALUE" "1.00K"
					( Origin gFrontEnd )
				)
				( attribute "VER" "2"
					( Origin gFrontEnd )
				)
				( attribute "WATTAGE" "1/16W"
					( Origin gFrontEnd )
				)
				( attribute "XY" "(325,3700)"
					( Origin gFrontEnd )
				)
				( attribute "CHIPS_PART_NAME" "RES"
					( Origin gPackager )
				)
				( attribute "CDS_PART_NAME" "RES_0402-1.00K,1%,1/16W,CHIP,GA"
					( Origin gPackager )
				)
				( objectStatus "R4G3" )
				( pin "a"
					( attribute "PN" "1"
						( Origin gPackager )
					)
					( objectStatus "R4G3.1" )
				)
				( pin "b"
					( attribute "PN" "2"
						( Origin gPackager )
					)
					( objectStatus "R4G3.2" )
				)
			)
			( gate "@baseboard_fab2_lib.baseboard_fab2(sch_1):page98_i42"
				( attribute "BOM_COST" "PROC_SOCKET"
					( Origin gFrontEnd )
				)
				( attribute "CDS_LIB" "mstr_discrete"
					( Origin gPackager )
				)
				( attribute "CDS_LOCATION" "R4G1"
					( Origin gPackager )
				)
				( attribute "CDS_SEC" "1"
					( Origin gPackager )
				)
				( attribute "LOCATION" "R4G1"
					( Origin gFrontEnd )
				)
				( attribute "MATERIAL" "CHIP"
					( Origin gFrontEnd )
				)
				( attribute "PACK_TYPE" "0402"
					( Origin gFrontEnd )
				)
				( attribute "PART_NUMBER" "G21796-274"
					( Origin gFrontEnd )
				)
				( attribute "PHYS_PAGE" "98"
					( Origin gFrontEnd )
				)
				( attribute "ROOM" "PROC"
					( Origin gFrontEnd )
				)
				( attribute "ROT" "0"
					( Origin gFrontEnd )
				)
				( attribute "SEC" "1"
					( Origin gFrontEnd )
				)
				( attribute "SEC_TYPE" "0402"
					( Origin gFrontEnd )
				)
				( attribute "TOLERANCE" "1.0%"
					( Origin gFrontEnd )
				)
				( attribute "VALUE" "2"
					( Origin gFrontEnd )
				)
				( attribute "VER" "1"
					( Origin gFrontEnd )
				)
				( attribute "WATTAGE" "1/16W"
					( Origin gFrontEnd )
				)
				( attribute "XY" "(25,4025)"
					( Origin gFrontEnd )
				)
				( attribute "CHIPS_PART_NAME" "RES"
					( Origin gPackager )
				)
				( attribute "CDS_PART_NAME" "RES_0402-2,1.0%,1/16W,CHIP,G21A"
					( Origin gPackager )
				)
				( objectStatus "R4G1" )
				( pin "a"
					( attribute "PN" "1"
						( Origin gPackager )
					)
					( objectStatus "R4G1.1" )
				)
				( pin "b"
					( attribute "PN" "2"
						( Origin gPackager )
					)
					( objectStatus "R4G1.2" )
				)
			)
			( gate "@baseboard_fab2_lib.baseboard_fab2(sch_1):page98_i43"
				( attribute "BOM_COST" "SM_CONTROLLER"
					( Origin gFrontEnd )
				)
				( attribute "CDS_LIB" "dev_discrete"
					( Origin gPackager )
				)
				( attribute "CDS_LOCATION" "C4G1"
					( Origin gPackager )
				)
				( attribute "CDS_SEC" "1"
					( Origin gPackager )
				)
				( attribute "LOCATION" "C4G1"
					( Origin gFrontEnd )
				)
				( attribute "MATERIAL" "X7R"
					( Origin gFrontEnd )
				)
				( attribute "PACK_TYPE" "0402V"
					( Origin gFrontEnd )
				)
				( attribute "PART_NUMBER" "A36096-045"
					( Origin gFrontEnd )
				)
				( attribute "PHYS_PAGE" "98"
					( Origin gFrontEnd )
				)
				( attribute "ROOM" "MEM"
					( Origin gFrontEnd )
				)
				( attribute "ROT" "0"
					( Origin gFrontEnd )
				)
				( attribute "SEC" "1"
					( Origin gFrontEnd )
				)
				( attribute "SEC_TYPE" "0402V"
					( Origin gFrontEnd )
				)
				( attribute "TOLERANCE" "10%"
					( Origin gFrontEnd )
				)
				( attribute "VALUE" "0.01UF"
					( Origin gFrontEnd )
				)
				( attribute "VER" "1"
					( Origin gFrontEnd )
				)
				( attribute "VOLTAGE" "25V"
					( Units "uVoltage" "V" 1.000000)
					( Origin gFrontEnd )
				)
				( attribute "XY" "(-200,3725)"
					( Origin gFrontEnd )
				)
				( attribute "CHIPS_PART_NAME" "CAP_A"
					( Origin gPackager )
				)
				( attribute "CDS_PART_NAME" "CAP_A_0402V-0.01UF,25V,10%,X7RA"
					( Origin gPackager )
				)
				( objectStatus "C4G1" )
				( pin "a"
					( attribute "PN" "1"
						( Origin gPackager )
					)
					( objectStatus "C4G1.1" )
				)
				( pin "b"
					( attribute "PN" "2"
						( Origin gPackager )
					)
					( objectStatus "C4G1.2" )
				)
			)
			( gate "@baseboard_fab2_lib.baseboard_fab2(sch_1):page98_i46"
				( attribute "BOM_COST" "SM_CONTROLLER"
					( Origin gFrontEnd )
				)
				( attribute "CDS_LIB" "mstr_discrete"
					( Origin gPackager )
				)
				( attribute "CDS_LOCATION" "R4G21"
					( Origin gPackager )
				)
				( attribute "CDS_SEC" "1"
					( Origin gPackager )
				)
				( attribute "LOCATION" "R4G21"
					( Origin gFrontEnd )
				)
				( attribute "MATERIAL" "CHIP"
					( Origin gFrontEnd )
				)
				( attribute "PACK_TYPE" "0402"
					( Origin gFrontEnd )
				)
				( attribute "PART_NUMBER" "G21796-026"
					( Origin gFrontEnd )
				)
				( attribute "PHYS_PAGE" "98"
					( Origin gFrontEnd )
				)
				( attribute "ROOM" "MEM"
					( Origin gFrontEnd )
				)
				( attribute "ROT" "2"
					( Origin gFrontEnd )
				)
				( attribute "SEC" "1"
					( Origin gFrontEnd )
				)
				( attribute "SEC_TYPE" "0402"
					( Origin gFrontEnd )
				)
				( attribute "TOLERANCE" "1%"
					( Origin gFrontEnd )
				)
				( attribute "VALUE" "1.00K"
					( Origin gFrontEnd )
				)
				( attribute "VER" "2"
					( Origin gFrontEnd )
				)
				( attribute "WATTAGE" "1/16W"
					( Origin gFrontEnd )
				)
				( attribute "XY" "(2400,4350)"
					( Origin gFrontEnd )
				)
				( attribute "CHIPS_PART_NAME" "RES"
					( Origin gPackager )
				)
				( attribute "CDS_PART_NAME" "RES_0402-1.00K,1%,1/16W,CHIP,GA"
					( Origin gPackager )
				)
				( objectStatus "R4G21" )
				( pin "a"
					( attribute "PN" "1"
						( Origin gPackager )
					)
					( objectStatus "R4G21.1" )
				)
				( pin "b"
					( attribute "PN" "2"
						( Origin gPackager )
					)
					( objectStatus "R4G21.2" )
				)
			)
			( gate "@baseboard_fab2_lib.baseboard_fab2(sch_1):page98_i48"
				( attribute "BOM_COST" "PROC_SOCKET"
					( Origin gFrontEnd )
				)
				( attribute "CDS_LIB" "mstr_discrete"
					( Origin gPackager )
				)
				( attribute "CDS_LOCATION" "R4G22"
					( Origin gPackager )
				)
				( attribute "CDS_SEC" "1"
					( Origin gPackager )
				)
				( attribute "LOCATION" "R4G22"
					( Origin gFrontEnd )
				)
				( attribute "MATERIAL" "CHIP"
					( Origin gFrontEnd )
				)
				( attribute "PACK_TYPE" "0402"
					( Origin gFrontEnd )
				)
				( attribute "PART_NUMBER" "G21796-026"
					( Origin gFrontEnd )
				)
				( attribute "PHYS_PAGE" "98"
					( Origin gFrontEnd )
				)
				( attribute "ROOM" "PROC"
					( Origin gFrontEnd )
				)
				( attribute "ROT" "2"
					( Origin gFrontEnd )
				)
				( attribute "SEC" "1"
					( Origin gFrontEnd )
				)
				( attribute "SEC_TYPE" "0402"
					( Origin gFrontEnd )
				)
				( attribute "TOLERANCE" "1%"
					( Origin gFrontEnd )
				)
				( attribute "VALUE" "1.00K"
					( Origin gFrontEnd )
				)
				( attribute "VER" "2"
					( Origin gFrontEnd )
				)
				( attribute "WATTAGE" "1/16W"
					( Origin gFrontEnd )
				)
				( attribute "XY" "(2475,3700)"
					( Origin gFrontEnd )
				)
				( attribute "CHIPS_PART_NAME" "RES"
					( Origin gPackager )
				)
				( attribute "CDS_PART_NAME" "RES_0402-1.00K,1%,1/16W,CHIP,GA"
					( Origin gPackager )
				)
				( objectStatus "R4G22" )
				( pin "a"
					( attribute "PN" "1"
						( Origin gPackager )
					)
					( objectStatus "R4G22.1" )
				)
				( pin "b"
					( attribute "PN" "2"
						( Origin gPackager )
					)
					( objectStatus "R4G22.2" )
				)
			)
			( gate "@baseboard_fab2_lib.baseboard_fab2(sch_1):page98_i50"
				( attribute "BOM_COST" "PROC_SOCKET"
					( Origin gFrontEnd )
				)
				( attribute "CDS_LIB" "mstr_discrete"
					( Origin gPackager )
				)
				( attribute "CDS_LOCATION" "R4G20"
					( Origin gPackager )
				)
				( attribute "CDS_SEC" "1"
					( Origin gPackager )
				)
				( attribute "LOCATION" "R4G20"
					( Origin gFrontEnd )
				)
				( attribute "MATERIAL" "CHIP"
					( Origin gFrontEnd )
				)
				( attribute "PACK_TYPE" "0402"
					( Origin gFrontEnd )
				)
				( attribute "PART_NUMBER" "G21796-274"
					( Origin gFrontEnd )
				)
				( attribute "PHYS_PAGE" "98"
					( Origin gFrontEnd )
				)
				( attribute "ROOM" "PROC"
					( Origin gFrontEnd )
				)
				( attribute "ROT" "0"
					( Origin gFrontEnd )
				)
				( attribute "SEC" "1"
					( Origin gFrontEnd )
				)
				( attribute "SEC_TYPE" "0402"
					( Origin gFrontEnd )
				)
				( attribute "TOLERANCE" "1.0%"
					( Origin gFrontEnd )
				)
				( attribute "VALUE" "2"
					( Origin gFrontEnd )
				)
				( attribute "VER" "1"
					( Origin gFrontEnd )
				)
				( attribute "WATTAGE" "1/16W"
					( Origin gFrontEnd )
				)
				( attribute "XY" "(2175,4025)"
					( Origin gFrontEnd )
				)
				( attribute "CHIPS_PART_NAME" "RES"
					( Origin gPackager )
				)
				( attribute "CDS_PART_NAME" "RES_0402-2,1.0%,1/16W,CHIP,G21A"
					( Origin gPackager )
				)
				( objectStatus "R4G20" )
				( pin "a"
					( attribute "PN" "1"
						( Origin gPackager )
					)
					( objectStatus "R4G20.1" )
				)
				( pin "b"
					( attribute "PN" "2"
						( Origin gPackager )
					)
					( objectStatus "R4G20.2" )
				)
			)
			( gate "@baseboard_fab2_lib.baseboard_fab2(sch_1):page98_i51"
				( attribute "BOM_COST" "SM_CONTROLLER"
					( Origin gFrontEnd )
				)
				( attribute "CDS_LIB" "dev_discrete"
					( Origin gPackager )
				)
				( attribute "CDS_LOCATION" "C4G17"
					( Origin gPackager )
				)
				( attribute "CDS_SEC" "1"
					( Origin gPackager )
				)
				( attribute "LOCATION" "C4G17"
					( Origin gFrontEnd )
				)
				( attribute "MATERIAL" "X7R"
					( Origin gFrontEnd )
				)
				( attribute "PACK_TYPE" "0402V"
					( Origin gFrontEnd )
				)
				( attribute "PART_NUMBER" "A36096-045"
					( Origin gFrontEnd )
				)
				( attribute "PHYS_PAGE" "98"
					( Origin gFrontEnd )
				)
				( attribute "ROOM" "MEM"
					( Origin gFrontEnd )
				)
				( attribute "ROT" "0"
					( Origin gFrontEnd )
				)
				( attribute "SEC" "1"
					( Origin gFrontEnd )
				)
				( attribute "SEC_TYPE" "0402V"
					( Origin gFrontEnd )
				)
				( attribute "TOLERANCE" "10%"
					( Origin gFrontEnd )
				)
				( attribute "VALUE" "0.01UF"
					( Origin gFrontEnd )
				)
				( attribute "VER" "1"
					( Origin gFrontEnd )
				)
				( attribute "VOLTAGE" "25V"
					( Units "uVoltage" "V" 1.000000)
					( Origin gFrontEnd )
				)
				( attribute "XY" "(1950,3725)"
					( Origin gFrontEnd )
				)
				( attribute "CHIPS_PART_NAME" "CAP_A"
					( Origin gPackager )
				)
				( attribute "CDS_PART_NAME" "CAP_A_0402V-0.01UF,25V,10%,X7RA"
					( Origin gPackager )
				)
				( objectStatus "C4G17" )
				( pin "a"
					( attribute "PN" "1"
						( Origin gPackager )
					)
					( objectStatus "C4G17.1" )
				)
				( pin "b"
					( attribute "PN" "2"
						( Origin gPackager )
					)
					( objectStatus "C4G17.2" )
				)
			)
			( gate "@baseboard_fab2_lib.baseboard_fab2(sch_1):page98_i54"
				( attribute "BOM_COST" "SM_CONTROLLER"
					( Origin gFrontEnd )
				)
				( attribute "CDS_LIB" "mstr_discrete"
					( Origin gPackager )
				)
				( attribute "CDS_LOCATION" "R6L13"
					( Origin gPackager )
				)
				( attribute "CDS_SEC" "1"
					( Origin gPackager )
				)
				( attribute "LOCATION" "R6L13"
					( Origin gFrontEnd )
				)
				( attribute "MATERIAL" "CHIP"
					( Origin gFrontEnd )
				)
				( attribute "PACK_TYPE" "0402"
					( Origin gFrontEnd )
				)
				( attribute "PART_NUMBER" "G21796-026"
					( Origin gFrontEnd )
				)
				( attribute "PHYS_PAGE" "98"
					( Origin gFrontEnd )
				)
				( attribute "ROOM" "MEM"
					( Origin gFrontEnd )
				)
				( attribute "ROT" "2"
					( Origin gFrontEnd )
				)
				( attribute "SEC" "1"
					( Origin gFrontEnd )
				)
				( attribute "SEC_TYPE" "0402"
					( Origin gFrontEnd )
				)
				( attribute "TOLERANCE" "1%"
					( Origin gFrontEnd )
				)
				( attribute "VALUE" "1.00K"
					( Origin gFrontEnd )
				)
				( attribute "VER" "2"
					( Origin gFrontEnd )
				)
				( attribute "WATTAGE" "1/16W"
					( Origin gFrontEnd )
				)
				( attribute "XY" "(225,2675)"
					( Origin gFrontEnd )
				)
				( attribute "CHIPS_PART_NAME" "RES"
					( Origin gPackager )
				)
				( attribute "CDS_PART_NAME" "RES_0402-1.00K,1%,1/16W,CHIP,GA"
					( Origin gPackager )
				)
				( objectStatus "R6L13" )
				( pin "a"
					( attribute "PN" "1"
						( Origin gPackager )
					)
					( objectStatus "R6L13.1" )
				)
				( pin "b"
					( attribute "PN" "2"
						( Origin gPackager )
					)
					( objectStatus "R6L13.2" )
				)
			)
			( gate "@baseboard_fab2_lib.baseboard_fab2(sch_1):page98_i56"
				( attribute "BOM_COST" "PROC_SOCKET"
					( Origin gFrontEnd )
				)
				( attribute "CDS_LIB" "mstr_discrete"
					( Origin gPackager )
				)
				( attribute "CDS_LOCATION" "R6L12"
					( Origin gPackager )
				)
				( attribute "CDS_SEC" "1"
					( Origin gPackager )
				)
				( attribute "LOCATION" "R6L12"
					( Origin gFrontEnd )
				)
				( attribute "MATERIAL" "CHIP"
					( Origin gFrontEnd )
				)
				( attribute "PACK_TYPE" "0402"
					( Origin gFrontEnd )
				)
				( attribute "PART_NUMBER" "G21796-026"
					( Origin gFrontEnd )
				)
				( attribute "PHYS_PAGE" "98"
					( Origin gFrontEnd )
				)
				( attribute "ROOM" "PROC"
					( Origin gFrontEnd )
				)
				( attribute "ROT" "2"
					( Origin gFrontEnd )
				)
				( attribute "SEC" "1"
					( Origin gFrontEnd )
				)
				( attribute "SEC_TYPE" "0402"
					( Origin gFrontEnd )
				)
				( attribute "TOLERANCE" "1%"
					( Origin gFrontEnd )
				)
				( attribute "VALUE" "1.00K"
					( Origin gFrontEnd )
				)
				( attribute "VER" "2"
					( Origin gFrontEnd )
				)
				( attribute "WATTAGE" "1/16W"
					( Origin gFrontEnd )
				)
				( attribute "XY" "(300,2025)"
					( Origin gFrontEnd )
				)
				( attribute "CHIPS_PART_NAME" "RES"
					( Origin gPackager )
				)
				( attribute "CDS_PART_NAME" "RES_0402-1.00K,1%,1/16W,CHIP,GA"
					( Origin gPackager )
				)
				( objectStatus "R6L12" )
				( pin "a"
					( attribute "PN" "1"
						( Origin gPackager )
					)
					( objectStatus "R6L12.1" )
				)
				( pin "b"
					( attribute "PN" "2"
						( Origin gPackager )
					)
					( objectStatus "R6L12.2" )
				)
			)
			( gate "@baseboard_fab2_lib.baseboard_fab2(sch_1):page98_i58"
				( attribute "BOM_COST" "PROC_SOCKET"
					( Origin gFrontEnd )
				)
				( attribute "CDS_LIB" "mstr_discrete"
					( Origin gPackager )
				)
				( attribute "CDS_LOCATION" "R6L14"
					( Origin gPackager )
				)
				( attribute "CDS_SEC" "1"
					( Origin gPackager )
				)
				( attribute "LOCATION" "R6L14"
					( Origin gFrontEnd )
				)
				( attribute "MATERIAL" "CHIP"
					( Origin gFrontEnd )
				)
				( attribute "PACK_TYPE" "0402"
					( Origin gFrontEnd )
				)
				( attribute "PART_NUMBER" "G21796-274"
					( Origin gFrontEnd )
				)
				( attribute "PHYS_PAGE" "98"
					( Origin gFrontEnd )
				)
				( attribute "ROOM" "PROC"
					( Origin gFrontEnd )
				)
				( attribute "ROT" "0"
					( Origin gFrontEnd )
				)
				( attribute "SEC" "1"
					( Origin gFrontEnd )
				)
				( attribute "SEC_TYPE" "0402"
					( Origin gFrontEnd )
				)
				( attribute "TOLERANCE" "1.0%"
					( Origin gFrontEnd )
				)
				( attribute "VALUE" "2"
					( Origin gFrontEnd )
				)
				( attribute "VER" "1"
					( Origin gFrontEnd )
				)
				( attribute "WATTAGE" "1/16W"
					( Origin gFrontEnd )
				)
				( attribute "XY" "(0,2350)"
					( Origin gFrontEnd )
				)
				( attribute "CHIPS_PART_NAME" "RES"
					( Origin gPackager )
				)
				( attribute "CDS_PART_NAME" "RES_0402-2,1.0%,1/16W,CHIP,G21A"
					( Origin gPackager )
				)
				( objectStatus "R6L14" )
				( pin "a"
					( attribute "PN" "1"
						( Origin gPackager )
					)
					( objectStatus "R6L14.1" )
				)
				( pin "b"
					( attribute "PN" "2"
						( Origin gPackager )
					)
					( objectStatus "R6L14.2" )
				)
			)
			( gate "@baseboard_fab2_lib.baseboard_fab2(sch_1):page98_i59"
				( attribute "BOM_COST" "SM_CONTROLLER"
					( Origin gFrontEnd )
				)
				( attribute "CDS_LIB" "dev_discrete"
					( Origin gPackager )
				)
				( attribute "CDS_LOCATION" "C6L7"
					( Origin gPackager )
				)
				( attribute "CDS_SEC" "1"
					( Origin gPackager )
				)
				( attribute "LOCATION" "C6L7"
					( Origin gFrontEnd )
				)
				( attribute "MATERIAL" "X7R"
					( Origin gFrontEnd )
				)
				( attribute "PACK_TYPE" "0402V"
					( Origin gFrontEnd )
				)
				( attribute "PART_NUMBER" "A36096-045"
					( Origin gFrontEnd )
				)
				( attribute "PHYS_PAGE" "98"
					( Origin gFrontEnd )
				)
				( attribute "ROOM" "MEM"
					( Origin gFrontEnd )
				)
				( attribute "ROT" "0"
					( Origin gFrontEnd )
				)
				( attribute "SEC" "1"
					( Origin gFrontEnd )
				)
				( attribute "SEC_TYPE" "0402V"
					( Origin gFrontEnd )
				)
				( attribute "TOLERANCE" "10%"
					( Origin gFrontEnd )
				)
				( attribute "VALUE" "0.01UF"
					( Origin gFrontEnd )
				)
				( attribute "VER" "1"
					( Origin gFrontEnd )
				)
				( attribute "VOLTAGE" "25V"
					( Units "uVoltage" "V" 1.000000)
					( Origin gFrontEnd )
				)
				( attribute "XY" "(-225,2050)"
					( Origin gFrontEnd )
				)
				( attribute "CHIPS_PART_NAME" "CAP_A"
					( Origin gPackager )
				)
				( attribute "CDS_PART_NAME" "CAP_A_0402V-0.01UF,25V,10%,X7RA"
					( Origin gPackager )
				)
				( objectStatus "C6L7" )
				( pin "a"
					( attribute "PN" "1"
						( Origin gPackager )
					)
					( objectStatus "C6L7.1" )
				)
				( pin "b"
					( attribute "PN" "2"
						( Origin gPackager )
					)
					( objectStatus "C6L7.2" )
				)
			)
			( gate "@baseboard_fab2_lib.baseboard_fab2(sch_1):page98_i62"
				( attribute "BOM_COST" "SM_CONTROLLER"
					( Origin gFrontEnd )
				)
				( attribute "CDS_LIB" "mstr_discrete"
					( Origin gPackager )
				)
				( attribute "CDS_LOCATION" "R6L2"
					( Origin gPackager )
				)
				( attribute "CDS_SEC" "1"
					( Origin gPackager )
				)
				( attribute "LOCATION" "R6L2"
					( Origin gFrontEnd )
				)
				( attribute "MATERIAL" "CHIP"
					( Origin gFrontEnd )
				)
				( attribute "PACK_TYPE" "0402"
					( Origin gFrontEnd )
				)
				( attribute "PART_NUMBER" "G21796-026"
					( Origin gFrontEnd )
				)
				( attribute "PHYS_PAGE" "98"
					( Origin gFrontEnd )
				)
				( attribute "ROOM" "MEM"
					( Origin gFrontEnd )
				)
				( attribute "ROT" "2"
					( Origin gFrontEnd )
				)
				( attribute "SEC" "1"
					( Origin gFrontEnd )
				)
				( attribute "SEC_TYPE" "0402"
					( Origin gFrontEnd )
				)
				( attribute "TOLERANCE" "1%"
					( Origin gFrontEnd )
				)
				( attribute "VALUE" "1.00K"
					( Origin gFrontEnd )
				)
				( attribute "VER" "2"
					( Origin gFrontEnd )
				)
				( attribute "WATTAGE" "1/16W"
					( Origin gFrontEnd )
				)
				( attribute "XY" "(2400,2650)"
					( Origin gFrontEnd )
				)
				( attribute "CHIPS_PART_NAME" "RES"
					( Origin gPackager )
				)
				( attribute "CDS_PART_NAME" "RES_0402-1.00K,1%,1/16W,CHIP,GA"
					( Origin gPackager )
				)
				( objectStatus "R6L2" )
				( pin "a"
					( attribute "PN" "1"
						( Origin gPackager )
					)
					( objectStatus "R6L2.1" )
				)
				( pin "b"
					( attribute "PN" "2"
						( Origin gPackager )
					)
					( objectStatus "R6L2.2" )
				)
			)
			( gate "@baseboard_fab2_lib.baseboard_fab2(sch_1):page98_i64"
				( attribute "BOM_COST" "PROC_SOCKET"
					( Origin gFrontEnd )
				)
				( attribute "CDS_LIB" "mstr_discrete"
					( Origin gPackager )
				)
				( attribute "CDS_LOCATION" "R6L1"
					( Origin gPackager )
				)
				( attribute "CDS_SEC" "1"
					( Origin gPackager )
				)
				( attribute "LOCATION" "R6L1"
					( Origin gFrontEnd )
				)
				( attribute "MATERIAL" "CHIP"
					( Origin gFrontEnd )
				)
				( attribute "PACK_TYPE" "0402"
					( Origin gFrontEnd )
				)
				( attribute "PART_NUMBER" "G21796-026"
					( Origin gFrontEnd )
				)
				( attribute "PHYS_PAGE" "98"
					( Origin gFrontEnd )
				)
				( attribute "ROOM" "PROC"
					( Origin gFrontEnd )
				)
				( attribute "ROT" "2"
					( Origin gFrontEnd )
				)
				( attribute "SEC" "1"
					( Origin gFrontEnd )
				)
				( attribute "SEC_TYPE" "0402"
					( Origin gFrontEnd )
				)
				( attribute "TOLERANCE" "1%"
					( Origin gFrontEnd )
				)
				( attribute "VALUE" "1.00K"
					( Origin gFrontEnd )
				)
				( attribute "VER" "2"
					( Origin gFrontEnd )
				)
				( attribute "WATTAGE" "1/16W"
					( Origin gFrontEnd )
				)
				( attribute "XY" "(2475,2000)"
					( Origin gFrontEnd )
				)
				( attribute "CHIPS_PART_NAME" "RES"
					( Origin gPackager )
				)
				( attribute "CDS_PART_NAME" "RES_0402-1.00K,1%,1/16W,CHIP,GA"
					( Origin gPackager )
				)
				( objectStatus "R6L1" )
				( pin "a"
					( attribute "PN" "1"
						( Origin gPackager )
					)
					( objectStatus "R6L1.1" )
				)
				( pin "b"
					( attribute "PN" "2"
						( Origin gPackager )
					)
					( objectStatus "R6L1.2" )
				)
			)
			( gate "@baseboard_fab2_lib.baseboard_fab2(sch_1):page98_i66"
				( attribute "BOM_COST" "PROC_SOCKET"
					( Origin gFrontEnd )
				)
				( attribute "CDS_LIB" "mstr_discrete"
					( Origin gPackager )
				)
				( attribute "CDS_LOCATION" "R6L3"
					( Origin gPackager )
				)
				( attribute "CDS_SEC" "1"
					( Origin gPackager )
				)
				( attribute "LOCATION" "R6L3"
					( Origin gFrontEnd )
				)
				( attribute "MATERIAL" "CHIP"
					( Origin gFrontEnd )
				)
				( attribute "PACK_TYPE" "0402"
					( Origin gFrontEnd )
				)
				( attribute "PART_NUMBER" "G21796-274"
					( Origin gFrontEnd )
				)
				( attribute "PHYS_PAGE" "98"
					( Origin gFrontEnd )
				)
				( attribute "ROOM" "PROC"
					( Origin gFrontEnd )
				)
				( attribute "ROT" "0"
					( Origin gFrontEnd )
				)
				( attribute "SEC" "1"
					( Origin gFrontEnd )
				)
				( attribute "SEC_TYPE" "0402"
					( Origin gFrontEnd )
				)
				( attribute "TOLERANCE" "1.0%"
					( Origin gFrontEnd )
				)
				( attribute "VALUE" "2"
					( Origin gFrontEnd )
				)
				( attribute "VER" "1"
					( Origin gFrontEnd )
				)
				( attribute "WATTAGE" "1/16W"
					( Origin gFrontEnd )
				)
				( attribute "XY" "(2175,2325)"
					( Origin gFrontEnd )
				)
				( attribute "CHIPS_PART_NAME" "RES"
					( Origin gPackager )
				)
				( attribute "CDS_PART_NAME" "RES_0402-2,1.0%,1/16W,CHIP,G21A"
					( Origin gPackager )
				)
				( objectStatus "R6L3" )
				( pin "a"
					( attribute "PN" "1"
						( Origin gPackager )
					)
					( objectStatus "R6L3.1" )
				)
				( pin "b"
					( attribute "PN" "2"
						( Origin gPackager )
					)
					( objectStatus "R6L3.2" )
				)
			)
			( gate "@baseboard_fab2_lib.baseboard_fab2(sch_1):page98_i67"
				( attribute "BOM_COST" "SM_CONTROLLER"
					( Origin gFrontEnd )
				)
				( attribute "CDS_LIB" "dev_discrete"
					( Origin gPackager )
				)
				( attribute "CDS_LOCATION" "C6L2"
					( Origin gPackager )
				)
				( attribute "CDS_SEC" "1"
					( Origin gPackager )
				)
				( attribute "LOCATION" "C6L2"
					( Origin gFrontEnd )
				)
				( attribute "MATERIAL" "X7R"
					( Origin gFrontEnd )
				)
				( attribute "PACK_TYPE" "0402V"
					( Origin gFrontEnd )
				)
				( attribute "PART_NUMBER" "A36096-045"
					( Origin gFrontEnd )
				)
				( attribute "PHYS_PAGE" "98"
					( Origin gFrontEnd )
				)
				( attribute "ROOM" "MEM"
					( Origin gFrontEnd )
				)
				( attribute "ROT" "0"
					( Origin gFrontEnd )
				)
				( attribute "SEC" "1"
					( Origin gFrontEnd )
				)
				( attribute "SEC_TYPE" "0402V"
					( Origin gFrontEnd )
				)
				( attribute "TOLERANCE" "10%"
					( Origin gFrontEnd )
				)
				( attribute "VALUE" "0.01UF"
					( Origin gFrontEnd )
				)
				( attribute "VER" "1"
					( Origin gFrontEnd )
				)
				( attribute "VOLTAGE" "25V"
					( Units "uVoltage" "V" 1.000000)
					( Origin gFrontEnd )
				)
				( attribute "XY" "(1950,2025)"
					( Origin gFrontEnd )
				)
				( attribute "CHIPS_PART_NAME" "CAP_A"
					( Origin gPackager )
				)
				( attribute "CDS_PART_NAME" "CAP_A_0402V-0.01UF,25V,10%,X7RA"
					( Origin gPackager )
				)
				( objectStatus "C6L2" )
				( pin "a"
					( attribute "PN" "1"
						( Origin gPackager )
					)
					( objectStatus "C6L2.1" )
				)
				( pin "b"
					( attribute "PN" "2"
						( Origin gPackager )
					)
					( objectStatus "C6L2.2" )
				)
			)
			( gate "@baseboard_fab2_lib.baseboard_fab2(sch_1):page99_i2"
				( attribute "BOM_COST" "SM_CONTROLLER"
					( Origin gFrontEnd )
				)
				( attribute "CDS_LIB" "dev_discrete"
					( Origin gPackager )
				)
				( attribute "CDS_LOCATION" "C6F2"
					( Origin gPackager )
				)
				( attribute "CDS_SEC" "1"
					( Origin gPackager )
				)
				( attribute "CD_SEC" "1"
					( Origin gFrontEnd )
				)
				( attribute "LOCATION" "C6F2"
					( Origin gFrontEnd )
				)
				( attribute "MATERIAL" "X7R"
					( Origin gFrontEnd )
				)
				( attribute "PACK_TYPE" "0402V"
					( Origin gFrontEnd )
				)
				( attribute "PART_NUMBER" "A36096-030"
					( Origin gFrontEnd )
				)
				( attribute "PHYS_PAGE" "99"
					( Origin gFrontEnd )
				)
				( attribute "ROOM" "MEM"
					( Origin gFrontEnd )
				)
				( attribute "ROT" "0"
					( Origin gFrontEnd )
				)
				( attribute "SEC" "1"
					( Origin gPackager )
				)
				( attribute "SIGNAL_MODEL" "DEFAULT_CAPACITOR_100000pF_2_1"
					( Origin gFrontEnd )
				)
				( attribute "TOLERANCE" "10%"
					( Origin gFrontEnd )
				)
				( attribute "VALUE" "0.1UF"
					( Origin gFrontEnd )
				)
				( attribute "VER" "1"
					( Origin gFrontEnd )
				)
				( attribute "VOLTAGE" "16V"
					( Units "uVoltage" "V" 1.000000)
					( Origin gFrontEnd )
				)
				( attribute "XY" "(1900,4925)"
					( Origin gFrontEnd )
				)
				( attribute "CHIPS_PART_NAME" "CAP_A"
					( Origin gPackager )
				)
				( attribute "CDS_PART_NAME" "CAP_A_0402V-0.1UF,16V,10%,X7R,A"
					( Origin gPackager )
				)
				( objectStatus "C6F2" )
				( pin "a"
					( attribute "PN" "1"
						( Origin gPackager )
					)
					( objectStatus "C6F2.1" )
				)
				( pin "b"
					( attribute "PN" "2"
						( Origin gPackager )
					)
					( objectStatus "C6F2.2" )
				)
			)
			( gate "@baseboard_fab2_lib.baseboard_fab2(sch_1):page99_i7"
				( attribute "BOM_COST" "SM_CONTROLLER"
					( Origin gFrontEnd )
				)
				( attribute "CDS_LIB" "dev_discrete"
					( Origin gPackager )
				)
				( attribute "CDS_LOCATION" "C6F3"
					( Origin gPackager )
				)
				( attribute "CDS_SEC" "1"
					( Origin gPackager )
				)
				( attribute "CD_SEC" "1"
					( Origin gFrontEnd )
				)
				( attribute "LOCATION" "C6F3"
					( Origin gFrontEnd )
				)
				( attribute "MATERIAL" "X7R"
					( Origin gFrontEnd )
				)
				( attribute "PACK_TYPE" "0402V"
					( Origin gFrontEnd )
				)
				( attribute "PART_NUMBER" "A36096-030"
					( Origin gFrontEnd )
				)
				( attribute "PHYS_PAGE" "99"
					( Origin gFrontEnd )
				)
				( attribute "ROOM" "MEM"
					( Origin gFrontEnd )
				)
				( attribute "ROT" "0"
					( Origin gFrontEnd )
				)
				( attribute "SEC" "1"
					( Origin gPackager )
				)
				( attribute "SIGNAL_MODEL" "DEFAULT_CAPACITOR_100000pF_2_1"
					( Origin gFrontEnd )
				)
				( attribute "TOLERANCE" "10%"
					( Origin gFrontEnd )
				)
				( attribute "VALUE" "0.1UF"
					( Origin gFrontEnd )
				)
				( attribute "VER" "1"
					( Origin gFrontEnd )
				)
				( attribute "VOLTAGE" "16V"
					( Units "uVoltage" "V" 1.000000)
					( Origin gFrontEnd )
				)
				( attribute "XY" "(1475,4900)"
					( Origin gFrontEnd )
				)
				( attribute "CHIPS_PART_NAME" "CAP_A"
					( Origin gPackager )
				)
				( attribute "CDS_PART_NAME" "CAP_A_0402V-0.1UF,16V,10%,X7R,A"
					( Origin gPackager )
				)
				( objectStatus "C6F3" )
				( pin "a"
					( attribute "PN" "1"
						( Origin gPackager )
					)
					( objectStatus "C6F3.1" )
				)
				( pin "b"
					( attribute "PN" "2"
						( Origin gPackager )
					)
					( objectStatus "C6F3.2" )
				)
			)
			( gate "@baseboard_fab2_lib.baseboard_fab2(sch_1):page99_i9"
				( attribute "CDS_LIB" "mstr_discrete"
					( Origin gPackager )
				)
				( attribute "CDS_LOCATION" "R4T9"
					( Origin gPackager )
				)
				( attribute "CDS_SEC" "1"
					( Origin gPackager )
				)
				( attribute "LOCATION" "R4T9"
					( Origin gFrontEnd )
				)
				( attribute "MATERIAL" "CHIP"
					( Origin gFrontEnd )
				)
				( attribute "PACK_TYPE" "0402"
					( Origin gFrontEnd )
				)
				( attribute "PART_NUMBER" "G21796-173"
					( Origin gFrontEnd )
				)
				( attribute "PHYS_PAGE" "99"
					( Origin gFrontEnd )
				)
				( attribute "ROOM" "MEM"
					( Origin gFrontEnd )
				)
				( attribute "ROT" "0"
					( Origin gFrontEnd )
				)
				( attribute "SEC" "1"
					( Origin gPackager )
				)
				( attribute "TOLERANCE" "1%"
					( Origin gFrontEnd )
				)
				( attribute "VALUE" "20.0"
					( Origin gFrontEnd )
				)
				( attribute "VER" "1"
					( Origin gFrontEnd )
				)
				( attribute "WATTAGE" "1/16W"
					( Origin gFrontEnd )
				)
				( attribute "XY" "(1600,4350)"
					( Origin gFrontEnd )
				)
				( attribute "CHIPS_PART_NAME" "RES"
					( Origin gPackager )
				)
				( attribute "CDS_PART_NAME" "RES_0402-20.0,1%,1/16W,CHIP,G2A"
					( Origin gPackager )
				)
				( objectStatus "R4T9" )
				( pin "a"
					( attribute "PN" "1"
						( Origin gPackager )
					)
					( objectStatus "R4T9.1" )
				)
				( pin "b"
					( attribute "PN" "2"
						( Origin gPackager )
					)
					( objectStatus "R4T9.2" )
				)
			)
			( gate "@baseboard_fab2_lib.baseboard_fab2(sch_1):page99_i10"
				( attribute "CDS_LIB" "mstr_discrete"
					( Origin gPackager )
				)
				( attribute "CDS_LOCATION" "R4T10"
					( Origin gPackager )
				)
				( attribute "CDS_SEC" "1"
					( Origin gPackager )
				)
				( attribute "LOCATION" "R4T10"
					( Origin gFrontEnd )
				)
				( attribute "MATERIAL" "CHIP"
					( Origin gFrontEnd )
				)
				( attribute "PACK_TYPE" "0402"
					( Origin gFrontEnd )
				)
				( attribute "PART_NUMBER" "G21796-173"
					( Origin gFrontEnd )
				)
				( attribute "PHYS_PAGE" "99"
					( Origin gFrontEnd )
				)
				( attribute "ROOM" "MEM"
					( Origin gFrontEnd )
				)
				( attribute "ROT" "0"
					( Origin gFrontEnd )
				)
				( attribute "SEC" "1"
					( Origin gPackager )
				)
				( attribute "TOLERANCE" "1%"
					( Origin gFrontEnd )
				)
				( attribute "VALUE" "20.0"
					( Origin gFrontEnd )
				)
				( attribute "VER" "1"
					( Origin gFrontEnd )
				)
				( attribute "WATTAGE" "1/16W"
					( Origin gFrontEnd )
				)
				( attribute "XY" "(1600,4300)"
					( Origin gFrontEnd )
				)
				( attribute "CHIPS_PART_NAME" "RES"
					( Origin gPackager )
				)
				( attribute "CDS_PART_NAME" "RES_0402-20.0,1%,1/16W,CHIP,G2A"
					( Origin gPackager )
				)
				( objectStatus "R4T10" )
				( pin "a"
					( attribute "PN" "1"
						( Origin gPackager )
					)
					( objectStatus "R4T10.1" )
				)
				( pin "b"
					( attribute "PN" "2"
						( Origin gPackager )
					)
					( objectStatus "R4T10.2" )
				)
			)
			( gate "@baseboard_fab2_lib.baseboard_fab2(sch_1):page99_i11"
				( attribute "BOM_COST" "SM_CONTROLLER"
					( Origin gFrontEnd )
				)
				( attribute "CDS_LIB" "mstr_discrete"
					( Origin gPackager )
				)
				( attribute "CDS_LOCATION" "R4T8"
					( Origin gPackager )
				)
				( attribute "CDS_SEC" "1"
					( Origin gPackager )
				)
				( attribute "LOCATION" "R4T8"
					( Origin gFrontEnd )
				)
				( attribute "MATERIAL" "CHIP"
					( Origin gFrontEnd )
				)
				( attribute "PACK_TYPE" "0402"
					( Origin gFrontEnd )
				)
				( attribute "PART_NUMBER" "G21796-235"
					( Origin gFrontEnd )
				)
				( attribute "PHYS_PAGE" "99"
					( Origin gFrontEnd )
				)
				( attribute "ROOM" "MEM"
					( Origin gFrontEnd )
				)
				( attribute "ROT" "0"
					( Origin gFrontEnd )
				)
				( attribute "SEC" "1"
					( Origin gFrontEnd )
				)
				( attribute "SEC_TYPE" "0402"
					( Origin gFrontEnd )
				)
				( attribute "TOLERANCE" "1.0%"
					( Origin gFrontEnd )
				)
				( attribute "VALUE" "665"
					( Origin gFrontEnd )
				)
				( attribute "VER" "2"
					( Origin gFrontEnd )
				)
				( attribute "WATTAGE" "1/16W"
					( Origin gFrontEnd )
				)
				( attribute "XY" "(1225,4650)"
					( Origin gFrontEnd )
				)
				( attribute "CHIPS_PART_NAME" "RES"
					( Origin gPackager )
				)
				( attribute "CDS_PART_NAME" "RES_0402-665,1.0%,1/16W,CHIP,GA"
					( Origin gPackager )
				)
				( objectStatus "R4T8" )
				( pin "a"
					( attribute "PN" "1"
						( Origin gPackager )
					)
					( objectStatus "R4T8.1" )
				)
				( pin "b"
					( attribute "PN" "2"
						( Origin gPackager )
					)
					( objectStatus "R4T8.2" )
				)
			)
			( gate "@baseboard_fab2_lib.baseboard_fab2(sch_1):page99_i13"
				( attribute "BOM_COST" "SM_CONTROLLER"
					( Origin gFrontEnd )
				)
				( attribute "CDS_LIB" "mstr_discrete"
					( Origin gPackager )
				)
				( attribute "CDS_LOCATION" "R4T7"
					( Origin gPackager )
				)
				( attribute "CDS_SEC" "1"
					( Origin gPackager )
				)
				( attribute "LOCATION" "R4T7"
					( Origin gFrontEnd )
				)
				( attribute "MATERIAL" "CHIP"
					( Origin gFrontEnd )
				)
				( attribute "PACK_TYPE" "0402"
					( Origin gFrontEnd )
				)
				( attribute "PART_NUMBER" "G21796-235"
					( Origin gFrontEnd )
				)
				( attribute "PHYS_PAGE" "99"
					( Origin gFrontEnd )
				)
				( attribute "ROOM" "MEM"
					( Origin gFrontEnd )
				)
				( attribute "ROT" "0"
					( Origin gFrontEnd )
				)
				( attribute "SEC" "1"
					( Origin gFrontEnd )
				)
				( attribute "SEC_TYPE" "0402"
					( Origin gFrontEnd )
				)
				( attribute "TOLERANCE" "1.0%"
					( Origin gFrontEnd )
				)
				( attribute "VALUE" "665"
					( Origin gFrontEnd )
				)
				( attribute "VER" "2"
					( Origin gFrontEnd )
				)
				( attribute "WATTAGE" "1/16W"
					( Origin gFrontEnd )
				)
				( attribute "XY" "(875,4650)"
					( Origin gFrontEnd )
				)
				( attribute "CHIPS_PART_NAME" "RES"
					( Origin gPackager )
				)
				( attribute "CDS_PART_NAME" "RES_0402-665,1.0%,1/16W,CHIP,GA"
					( Origin gPackager )
				)
				( objectStatus "R4T7" )
				( pin "a"
					( attribute "PN" "1"
						( Origin gPackager )
					)
					( objectStatus "R4T7.1" )
				)
				( pin "b"
					( attribute "PN" "2"
						( Origin gPackager )
					)
					( objectStatus "R4T7.2" )
				)
			)
			( gate "@baseboard_fab2_lib.baseboard_fab2(sch_1):page99_i15"
				( attribute "BOM_COST" "SM_CONTROLLER"
					( Origin gFrontEnd )
				)
				( attribute "CDS_LIB" "mstr_digital"
					( Origin gPackager )
				)
				( attribute "CDS_LOCATION" "U6F1"
					( Origin gPackager )
				)
				( attribute "CDS_SEC" "1"
					( Origin gPackager )
				)
				( attribute "LOCATION" "U6F1"
					( Origin gFrontEnd )
				)
				( attribute "MATERIAL" "IC"
					( Origin gFrontEnd )
				)
				( attribute "PACK_TYPE" "SSOP"
					( Origin gFrontEnd )
				)
				( attribute "PART_NUMBER" "G81764-001"
					( Origin gFrontEnd )
				)
				( attribute "PHYS_PAGE" "99"
					( Origin gFrontEnd )
				)
				( attribute "ROOM" "MEM"
					( Origin gFrontEnd )
				)
				( attribute "ROT" "0"
					( Origin gFrontEnd )
				)
				( attribute "SEC" "1"
					( Origin gPackager )
				)
				( attribute "VER" "1"
					( Origin gFrontEnd )
				)
				( attribute "XY" "(150,4300)"
					( Origin gFrontEnd )
				)
				( attribute "CHIPS_PART_NAME" "PCA9617"
					( Origin gPackager )
				)
				( attribute "CDS_PART_NAME" "PCA9617_SSOP-IC,G81764-001"
					( Origin gPackager )
				)
				( objectStatus "U6F1" )
				( pin "en"
					( attribute "PN" "5"
						( Origin gPackager )
					)
					( objectStatus "U6F1.5" )
				)
				( pin "scla"
					( attribute "PN" "2"
						( Origin gPackager )
					)
					( objectStatus "U6F1.2" )
				)
				( pin "sclb"
					( attribute "PN" "7"
						( Origin gPackager )
					)
					( objectStatus "U6F1.7" )
				)
				( pin "sdaa"
					( attribute "PN" "3"
						( Origin gPackager )
					)
					( objectStatus "U6F1.3" )
				)
				( pin "sdab"
					( attribute "PN" "6"
						( Origin gPackager )
					)
					( objectStatus "U6F1.6" )
				)
				( pin "vcca"
					( attribute "PN" "1"
						( Origin gPackager )
					)
					( objectStatus "U6F1.1" )
				)
				( pin "vccb"
					( attribute "PN" "8"
						( Origin gPackager )
					)
					( objectStatus "U6F1.8" )
				)
			)
			( gate "@baseboard_fab2_lib.baseboard_fab2(sch_1):page99_i17"
				( attribute "BOM_COST" "SM_CONTROLLER"
					( Origin gFrontEnd )
				)
				( attribute "CDS_LIB" "mstr_discrete"
					( Origin gPackager )
				)
				( attribute "CDS_LOCATION" "R4T6"
					( Origin gPackager )
				)
				( attribute "CDS_SEC" "1"
					( Origin gPackager )
				)
				( attribute "CD_SEC" "1"
					( Origin gFrontEnd )
				)
				( attribute "LOCATION" "R4T6"
					( Origin gFrontEnd )
				)
				( attribute "MATERIAL" "CHIP"
					( Origin gFrontEnd )
				)
				( attribute "PACK_TYPE" "0402"
					( Origin gFrontEnd )
				)
				( attribute "PART_NUMBER" "G21796-294"
					( Origin gFrontEnd )
				)
				( attribute "PHYS_PAGE" "99"
					( Origin gFrontEnd )
				)
				( attribute "ROOM" "MEM"
					( Origin gFrontEnd )
				)
				( attribute "ROT" "2"
					( Origin gFrontEnd )
				)
				( attribute "SEC" "1"
					( Origin gPackager )
				)
				( attribute "SIGNAL_MODEL" "DEFAULT_RESISTOR_750OHM_2_1"
					( Origin gFrontEnd )
				)
				( attribute "TOLERANCE" "1.0%"
					( Origin gFrontEnd )
				)
				( attribute "VALUE" "240"
					( Origin gFrontEnd )
				)
				( attribute "VER" "2"
					( Origin gFrontEnd )
				)
				( attribute "WATTAGE" "1/16W"
					( Origin gFrontEnd )
				)
				( attribute "XY" "(-650,4650)"
					( Origin gFrontEnd )
				)
				( attribute "CHIPS_PART_NAME" "RES"
					( Origin gPackager )
				)
				( attribute "CDS_PART_NAME" "RES_0402-240,1.0%,1/16W,CHIP,GA"
					( Origin gPackager )
				)
				( objectStatus "R4T6" )
				( pin "a"
					( attribute "PN" "1"
						( Origin gPackager )
					)
					( objectStatus "R4T6.1" )
				)
				( pin "b"
					( attribute "PN" "2"
						( Origin gPackager )
					)
					( objectStatus "R4T6.2" )
				)
			)
			( gate "@baseboard_fab2_lib.baseboard_fab2(sch_1):page99_i19"
				( attribute "BOM_COST" "SM_CONTROLLER"
					( Origin gFrontEnd )
				)
				( attribute "CDS_LIB" "mstr_discrete"
					( Origin gPackager )
				)
				( attribute "CDS_LOCATION" "R4T5"
					( Origin gPackager )
				)
				( attribute "CDS_SEC" "1"
					( Origin gPackager )
				)
				( attribute "CD_SEC" "1"
					( Origin gFrontEnd )
				)
				( attribute "LOCATION" "R4T5"
					( Origin gFrontEnd )
				)
				( attribute "MATERIAL" "CHIP"
					( Origin gFrontEnd )
				)
				( attribute "PACK_TYPE" "0402"
					( Origin gFrontEnd )
				)
				( attribute "PART_NUMBER" "G21796-294"
					( Origin gFrontEnd )
				)
				( attribute "PHYS_PAGE" "99"
					( Origin gFrontEnd )
				)
				( attribute "ROOM" "MEM"
					( Origin gFrontEnd )
				)
				( attribute "ROT" "2"
					( Origin gFrontEnd )
				)
				( attribute "SEC" "1"
					( Origin gPackager )
				)
				( attribute "SIGNAL_MODEL" "DEFAULT_RESISTOR_750OHM_2_1"
					( Origin gFrontEnd )
				)
				( attribute "TOLERANCE" "1.0%"
					( Origin gFrontEnd )
				)
				( attribute "VALUE" "240"
					( Origin gFrontEnd )
				)
				( attribute "VER" "2"
					( Origin gFrontEnd )
				)
				( attribute "WATTAGE" "1/16W"
					( Origin gFrontEnd )
				)
				( attribute "XY" "(-1025,4650)"
					( Origin gFrontEnd )
				)
				( attribute "CHIPS_PART_NAME" "RES"
					( Origin gPackager )
				)
				( attribute "CDS_PART_NAME" "RES_0402-240,1.0%,1/16W,CHIP,GA"
					( Origin gPackager )
				)
				( objectStatus "R4T5" )
				( pin "a"
					( attribute "PN" "1"
						( Origin gPackager )
					)
					( objectStatus "R4T5.1" )
				)
				( pin "b"
					( attribute "PN" "2"
						( Origin gPackager )
					)
					( objectStatus "R4T5.2" )
				)
			)
			( gate "@baseboard_fab2_lib.baseboard_fab2(sch_1):page99_i20"
				( attribute "BOM_COST" "SM_CONTROLLER"
					( Origin gFrontEnd )
				)
				( attribute "CDS_LIB" "mstr_discrete"
					( Origin gPackager )
				)
				( attribute "CDS_LOCATION" "R4T4"
					( Origin gPackager )
				)
				( attribute "CDS_SEC" "1"
					( Origin gPackager )
				)
				( attribute "LOCATION" "R4T4"
					( Origin gFrontEnd )
				)
				( attribute "MATERIAL" "CHIP"
					( Origin gFrontEnd )
				)
				( attribute "PACK_TYPE" "0402"
					( Origin gFrontEnd )
				)
				( attribute "PART_NUMBER" "G21796-066"
					( Origin gFrontEnd )
				)
				( attribute "PHYS_PAGE" "99"
					( Origin gFrontEnd )
				)
				( attribute "ROOM" "MEM"
					( Origin gFrontEnd )
				)
				( attribute "ROT" "0"
					( Origin gFrontEnd )
				)
				( attribute "SEC" "1"
					( Origin gPackager )
				)
				( attribute "TOLERANCE" "1%"
					( Origin gFrontEnd )
				)
				( attribute "VALUE" "10.0"
					( Origin gFrontEnd )
				)
				( attribute "VER" "1"
					( Origin gFrontEnd )
				)
				( attribute "WATTAGE" "1/16W"
					( Origin gFrontEnd )
				)
				( attribute "XY" "(-1075,4300)"
					( Origin gFrontEnd )
				)
				( attribute "CHIPS_PART_NAME" "RES"
					( Origin gPackager )
				)
				( attribute "CDS_PART_NAME" "RES_0402-10.0,1%,1/16W,CHIP,G2A"
					( Origin gPackager )
				)
				( objectStatus "R4T4" )
				( pin "a"
					( attribute "PN" "1"
						( Origin gPackager )
					)
					( objectStatus "R4T4.1" )
				)
				( pin "b"
					( attribute "PN" "2"
						( Origin gPackager )
					)
					( objectStatus "R4T4.2" )
				)
			)
			( gate "@baseboard_fab2_lib.baseboard_fab2(sch_1):page99_i23"
				( attribute "BOM_COST" "SM_CONTROLLER"
					( Origin gFrontEnd )
				)
				( attribute "CDS_LIB" "dev_discrete"
					( Origin gPackager )
				)
				( attribute "CDS_LOCATION" "C7E1"
					( Origin gPackager )
				)
				( attribute "CDS_SEC" "1"
					( Origin gPackager )
				)
				( attribute "CD_SEC" "1"
					( Origin gFrontEnd )
				)
				( attribute "LOCATION" "C7E1"
					( Origin gFrontEnd )
				)
				( attribute "MATERIAL" "X7R"
					( Origin gFrontEnd )
				)
				( attribute "PACK_TYPE" "0402V"
					( Origin gFrontEnd )
				)
				( attribute "PART_NUMBER" "A36096-030"
					( Origin gFrontEnd )
				)
				( attribute "PHYS_PAGE" "99"
					( Origin gFrontEnd )
				)
				( attribute "ROOM" "MEM"
					( Origin gFrontEnd )
				)
				( attribute "ROT" "0"
					( Origin gFrontEnd )
				)
				( attribute "SEC" "1"
					( Origin gPackager )
				)
				( attribute "SIGNAL_MODEL" "DEFAULT_CAPACITOR_100000pF_2_1"
					( Origin gFrontEnd )
				)
				( attribute "TOLERANCE" "10%"
					( Origin gFrontEnd )
				)
				( attribute "VALUE" "0.1UF"
					( Origin gFrontEnd )
				)
				( attribute "VER" "1"
					( Origin gFrontEnd )
				)
				( attribute "VOLTAGE" "16V"
					( Units "uVoltage" "V" 1.000000)
					( Origin gFrontEnd )
				)
				( attribute "XY" "(2125,3775)"
					( Origin gFrontEnd )
				)
				( attribute "CHIPS_PART_NAME" "CAP_A"
					( Origin gPackager )
				)
				( attribute "CDS_PART_NAME" "CAP_A_0402V-0.1UF,16V,10%,X7R,A"
					( Origin gPackager )
				)
				( objectStatus "C7E1" )
				( pin "a"
					( attribute "PN" "1"
						( Origin gPackager )
					)
					( objectStatus "C7E1.1" )
				)
				( pin "b"
					( attribute "PN" "2"
						( Origin gPackager )
					)
					( objectStatus "C7E1.2" )
				)
			)
			( gate "@baseboard_fab2_lib.baseboard_fab2(sch_1):page99_i27"
				( attribute "BOM_COST" "SM_CONTROLLER"
					( Origin gFrontEnd )
				)
				( attribute "CDS_LIB" "dev_discrete"
					( Origin gPackager )
				)
				( attribute "CDS_LOCATION" "C4G22"
					( Origin gPackager )
				)
				( attribute "CDS_SEC" "1"
					( Origin gPackager )
				)
				( attribute "CD_SEC" "1"
					( Origin gFrontEnd )
				)
				( attribute "LOCATION" "C4G22"
					( Origin gFrontEnd )
				)
				( attribute "MATERIAL" "X7R"
					( Origin gFrontEnd )
				)
				( attribute "PACK_TYPE" "0402V"
					( Origin gFrontEnd )
				)
				( attribute "PART_NUMBER" "A36096-030"
					( Origin gFrontEnd )
				)
				( attribute "PHYS_PAGE" "99"
					( Origin gFrontEnd )
				)
				( attribute "ROOM" "MEM"
					( Origin gFrontEnd )
				)
				( attribute "ROT" "0"
					( Origin gFrontEnd )
				)
				( attribute "SEC" "1"
					( Origin gPackager )
				)
				( attribute "SIGNAL_MODEL" "DEFAULT_CAPACITOR_100000pF_2_1"
					( Origin gFrontEnd )
				)
				( attribute "TOLERANCE" "10%"
					( Origin gFrontEnd )
				)
				( attribute "VALUE" "0.1UF"
					( Origin gFrontEnd )
				)
				( attribute "VER" "1"
					( Origin gFrontEnd )
				)
				( attribute "VOLTAGE" "16V"
					( Units "uVoltage" "V" 1.000000)
					( Origin gFrontEnd )
				)
				( attribute "XY" "(2225,2700)"
					( Origin gFrontEnd )
				)
				( attribute "CHIPS_PART_NAME" "CAP_A"
					( Origin gPackager )
				)
				( attribute "CDS_PART_NAME" "CAP_A_0402V-0.1UF,16V,10%,X7R,A"
					( Origin gPackager )
				)
				( objectStatus "C4G22" )
				( pin "a"
					( attribute "PN" "1"
						( Origin gPackager )
					)
					( objectStatus "C4G22.1" )
				)
				( pin "b"
					( attribute "PN" "2"
						( Origin gPackager )
					)
					( objectStatus "C4G22.2" )
				)
			)
			( gate "@baseboard_fab2_lib.baseboard_fab2(sch_1):page99_i32"
				( attribute "BOM_COST" "SM_CONTROLLER"
					( Origin gFrontEnd )
				)
				( attribute "CDS_LIB" "dev_discrete"
					( Origin gPackager )
				)
				( attribute "CDS_LOCATION" "C7E2"
					( Origin gPackager )
				)
				( attribute "CDS_SEC" "1"
					( Origin gPackager )
				)
				( attribute "CD_SEC" "1"
					( Origin gFrontEnd )
				)
				( attribute "LOCATION" "C7E2"
					( Origin gFrontEnd )
				)
				( attribute "MATERIAL" "X7R"
					( Origin gFrontEnd )
				)
				( attribute "PACK_TYPE" "0402V"
					( Origin gFrontEnd )
				)
				( attribute "PART_NUMBER" "A36096-030"
					( Origin gFrontEnd )
				)
				( attribute "PHYS_PAGE" "99"
					( Origin gFrontEnd )
				)
				( attribute "ROOM" "MEM"
					( Origin gFrontEnd )
				)
				( attribute "ROT" "0"
					( Origin gFrontEnd )
				)
				( attribute "SEC" "1"
					( Origin gPackager )
				)
				( attribute "SIGNAL_MODEL" "DEFAULT_CAPACITOR_100000pF_2_1"
					( Origin gFrontEnd )
				)
				( attribute "TOLERANCE" "10%"
					( Origin gFrontEnd )
				)
				( attribute "VALUE" "0.1UF"
					( Origin gFrontEnd )
				)
				( attribute "VER" "1"
					( Origin gFrontEnd )
				)
				( attribute "VOLTAGE" "16V"
					( Units "uVoltage" "V" 1.000000)
					( Origin gFrontEnd )
				)
				( attribute "XY" "(1625,3750)"
					( Origin gFrontEnd )
				)
				( attribute "CHIPS_PART_NAME" "CAP_A"
					( Origin gPackager )
				)
				( attribute "CDS_PART_NAME" "CAP_A_0402V-0.1UF,16V,10%,X7R,A"
					( Origin gPackager )
				)
				( objectStatus "C7E2" )
				( pin "a"
					( attribute "PN" "1"
						( Origin gPackager )
					)
					( objectStatus "C7E2.1" )
				)
				( pin "b"
					( attribute "PN" "2"
						( Origin gPackager )
					)
					( objectStatus "C7E2.2" )
				)
			)
			( gate "@baseboard_fab2_lib.baseboard_fab2(sch_1):page99_i34"
				( attribute "CDS_LIB" "mstr_discrete"
					( Origin gPackager )
				)
				( attribute "CDS_LOCATION" "R3R9"
					( Origin gPackager )
				)
				( attribute "CDS_SEC" "1"
					( Origin gPackager )
				)
				( attribute "LOCATION" "R3R9"
					( Origin gFrontEnd )
				)
				( attribute "MATERIAL" "CHIP"
					( Origin gFrontEnd )
				)
				( attribute "PACK_TYPE" "0402"
					( Origin gFrontEnd )
				)
				( attribute "PART_NUMBER" "G21796-173"
					( Origin gFrontEnd )
				)
				( attribute "PHYS_PAGE" "99"
					( Origin gFrontEnd )
				)
				( attribute "ROOM" "MEM"
					( Origin gFrontEnd )
				)
				( attribute "ROT" "0"
					( Origin gFrontEnd )
				)
				( attribute "SEC" "1"
					( Origin gPackager )
				)
				( attribute "TOLERANCE" "1%"
					( Origin gFrontEnd )
				)
				( attribute "VALUE" "20.0"
					( Origin gFrontEnd )
				)
				( attribute "VER" "1"
					( Origin gFrontEnd )
				)
				( attribute "WATTAGE" "1/16W"
					( Origin gFrontEnd )
				)
				( attribute "XY" "(1600,3250)"
					( Origin gFrontEnd )
				)
				( attribute "CHIPS_PART_NAME" "RES"
					( Origin gPackager )
				)
				( attribute "CDS_PART_NAME" "RES_0402-20.0,1%,1/16W,CHIP,G2A"
					( Origin gPackager )
				)
				( objectStatus "R3R9" )
				( pin "a"
					( attribute "PN" "1"
						( Origin gPackager )
					)
					( objectStatus "R3R9.1" )
				)
				( pin "b"
					( attribute "PN" "2"
						( Origin gPackager )
					)
					( objectStatus "R3R9.2" )
				)
			)
			( gate "@baseboard_fab2_lib.baseboard_fab2(sch_1):page99_i35"
				( attribute "CDS_LIB" "mstr_discrete"
					( Origin gPackager )
				)
				( attribute "CDS_LOCATION" "R3R8"
					( Origin gPackager )
				)
				( attribute "CDS_SEC" "1"
					( Origin gPackager )
				)
				( attribute "LOCATION" "R3R8"
					( Origin gFrontEnd )
				)
				( attribute "MATERIAL" "CHIP"
					( Origin gFrontEnd )
				)
				( attribute "PACK_TYPE" "0402"
					( Origin gFrontEnd )
				)
				( attribute "PART_NUMBER" "G21796-173"
					( Origin gFrontEnd )
				)
				( attribute "PHYS_PAGE" "99"
					( Origin gFrontEnd )
				)
				( attribute "ROOM" "MEM"
					( Origin gFrontEnd )
				)
				( attribute "ROT" "0"
					( Origin gFrontEnd )
				)
				( attribute "SEC" "1"
					( Origin gPackager )
				)
				( attribute "TOLERANCE" "1%"
					( Origin gFrontEnd )
				)
				( attribute "VALUE" "20.0"
					( Origin gFrontEnd )
				)
				( attribute "VER" "1"
					( Origin gFrontEnd )
				)
				( attribute "WATTAGE" "1/16W"
					( Origin gFrontEnd )
				)
				( attribute "XY" "(1600,3300)"
					( Origin gFrontEnd )
				)
				( attribute "CHIPS_PART_NAME" "RES"
					( Origin gPackager )
				)
				( attribute "CDS_PART_NAME" "RES_0402-20.0,1%,1/16W,CHIP,G2A"
					( Origin gPackager )
				)
				( objectStatus "R3R8" )
				( pin "a"
					( attribute "PN" "1"
						( Origin gPackager )
					)
					( objectStatus "R3R8.1" )
				)
				( pin "b"
					( attribute "PN" "2"
						( Origin gPackager )
					)
					( objectStatus "R3R8.2" )
				)
			)
			( gate "@baseboard_fab2_lib.baseboard_fab2(sch_1):page99_i41"
				( attribute "BOM_COST" "SM_CONTROLLER"
					( Origin gFrontEnd )
				)
				( attribute "CDS_LIB" "dev_discrete"
					( Origin gPackager )
				)
				( attribute "CDS_LOCATION" "C4G25"
					( Origin gPackager )
				)
				( attribute "CDS_SEC" "1"
					( Origin gPackager )
				)
				( attribute "CD_SEC" "1"
					( Origin gFrontEnd )
				)
				( attribute "LOCATION" "C4G25"
					( Origin gFrontEnd )
				)
				( attribute "MATERIAL" "X7R"
					( Origin gFrontEnd )
				)
				( attribute "PACK_TYPE" "0402V"
					( Origin gFrontEnd )
				)
				( attribute "PART_NUMBER" "A36096-030"
					( Origin gFrontEnd )
				)
				( attribute "PHYS_PAGE" "99"
					( Origin gFrontEnd )
				)
				( attribute "ROOM" "MEM"
					( Origin gFrontEnd )
				)
				( attribute "ROT" "0"
					( Origin gFrontEnd )
				)
				( attribute "SEC" "1"
					( Origin gPackager )
				)
				( attribute "SIGNAL_MODEL" "DEFAULT_CAPACITOR_100000pF_2_1"
					( Origin gFrontEnd )
				)
				( attribute "TOLERANCE" "10%"
					( Origin gFrontEnd )
				)
				( attribute "VALUE" "0.1UF"
					( Origin gFrontEnd )
				)
				( attribute "VER" "1"
					( Origin gFrontEnd )
				)
				( attribute "VOLTAGE" "16V"
					( Units "uVoltage" "V" 1.000000)
					( Origin gFrontEnd )
				)
				( attribute "XY" "(1650,2675)"
					( Origin gFrontEnd )
				)
				( attribute "CHIPS_PART_NAME" "CAP_A"
					( Origin gPackager )
				)
				( attribute "CDS_PART_NAME" "CAP_A_0402V-0.1UF,16V,10%,X7R,A"
					( Origin gPackager )
				)
				( objectStatus "C4G25" )
				( pin "a"
					( attribute "PN" "1"
						( Origin gPackager )
					)
					( objectStatus "C4G25.1" )
				)
				( pin "b"
					( attribute "PN" "2"
						( Origin gPackager )
					)
					( objectStatus "C4G25.2" )
				)
			)
			( gate "@baseboard_fab2_lib.baseboard_fab2(sch_1):page99_i42"
				( attribute "CDS_LIB" "mstr_discrete"
					( Origin gPackager )
				)
				( attribute "CDS_LOCATION" "R6U13"
					( Origin gPackager )
				)
				( attribute "CDS_SEC" "1"
					( Origin gPackager )
				)
				( attribute "LOCATION" "R6U13"
					( Origin gFrontEnd )
				)
				( attribute "MATERIAL" "CHIP"
					( Origin gFrontEnd )
				)
				( attribute "PACK_TYPE" "0402"
					( Origin gFrontEnd )
				)
				( attribute "PART_NUMBER" "G21796-173"
					( Origin gFrontEnd )
				)
				( attribute "PHYS_PAGE" "99"
					( Origin gFrontEnd )
				)
				( attribute "ROOM" "MEM"
					( Origin gFrontEnd )
				)
				( attribute "ROT" "0"
					( Origin gFrontEnd )
				)
				( attribute "SEC" "1"
					( Origin gPackager )
				)
				( attribute "TOLERANCE" "1%"
					( Origin gFrontEnd )
				)
				( attribute "VALUE" "20.0"
					( Origin gFrontEnd )
				)
				( attribute "VER" "1"
					( Origin gFrontEnd )
				)
				( attribute "WATTAGE" "1/16W"
					( Origin gFrontEnd )
				)
				( attribute "XY" "(1600,2150)"
					( Origin gFrontEnd )
				)
				( attribute "CHIPS_PART_NAME" "RES"
					( Origin gPackager )
				)
				( attribute "CDS_PART_NAME" "RES_0402-20.0,1%,1/16W,CHIP,G2A"
					( Origin gPackager )
				)
				( objectStatus "R6U13" )
				( pin "a"
					( attribute "PN" "1"
						( Origin gPackager )
					)
					( objectStatus "R6U13.1" )
				)
				( pin "b"
					( attribute "PN" "2"
						( Origin gPackager )
					)
					( objectStatus "R6U13.2" )
				)
			)
			( gate "@baseboard_fab2_lib.baseboard_fab2(sch_1):page99_i43"
				( attribute "CDS_LIB" "mstr_discrete"
					( Origin gPackager )
				)
				( attribute "CDS_LOCATION" "R6U14"
					( Origin gPackager )
				)
				( attribute "CDS_SEC" "1"
					( Origin gPackager )
				)
				( attribute "LOCATION" "R6U14"
					( Origin gFrontEnd )
				)
				( attribute "MATERIAL" "CHIP"
					( Origin gFrontEnd )
				)
				( attribute "PACK_TYPE" "0402"
					( Origin gFrontEnd )
				)
				( attribute "PART_NUMBER" "G21796-173"
					( Origin gFrontEnd )
				)
				( attribute "PHYS_PAGE" "99"
					( Origin gFrontEnd )
				)
				( attribute "ROOM" "MEM"
					( Origin gFrontEnd )
				)
				( attribute "ROT" "0"
					( Origin gFrontEnd )
				)
				( attribute "SEC" "1"
					( Origin gPackager )
				)
				( attribute "TOLERANCE" "1%"
					( Origin gFrontEnd )
				)
				( attribute "VALUE" "20.0"
					( Origin gFrontEnd )
				)
				( attribute "VER" "1"
					( Origin gFrontEnd )
				)
				( attribute "WATTAGE" "1/16W"
					( Origin gFrontEnd )
				)
				( attribute "XY" "(1600,2100)"
					( Origin gFrontEnd )
				)
				( attribute "CHIPS_PART_NAME" "RES"
					( Origin gPackager )
				)
				( attribute "CDS_PART_NAME" "RES_0402-20.0,1%,1/16W,CHIP,G2A"
					( Origin gPackager )
				)
				( objectStatus "R6U14" )
				( pin "a"
					( attribute "PN" "1"
						( Origin gPackager )
					)
					( objectStatus "R6U14.1" )
				)
				( pin "b"
					( attribute "PN" "2"
						( Origin gPackager )
					)
					( objectStatus "R6U14.2" )
				)
			)
			( gate "@baseboard_fab2_lib.baseboard_fab2(sch_1):page99_i47"
				( attribute "BOM_COST" "SM_CONTROLLER"
					( Origin gFrontEnd )
				)
				( attribute "CDS_LIB" "dev_discrete"
					( Origin gPackager )
				)
				( attribute "CDS_LOCATION" "C3B4"
					( Origin gPackager )
				)
				( attribute "CDS_SEC" "1"
					( Origin gPackager )
				)
				( attribute "CD_SEC" "1"
					( Origin gFrontEnd )
				)
				( attribute "LOCATION" "C3B4"
					( Origin gFrontEnd )
				)
				( attribute "MATERIAL" "X7R"
					( Origin gFrontEnd )
				)
				( attribute "PACK_TYPE" "0402V"
					( Origin gFrontEnd )
				)
				( attribute "PART_NUMBER" "A36096-030"
					( Origin gFrontEnd )
				)
				( attribute "PHYS_PAGE" "99"
					( Origin gFrontEnd )
				)
				( attribute "ROOM" "MEM"
					( Origin gFrontEnd )
				)
				( attribute "ROT" "0"
					( Origin gFrontEnd )
				)
				( attribute "SEC" "1"
					( Origin gPackager )
				)
				( attribute "SIGNAL_MODEL" "DEFAULT_CAPACITOR_100000pF_2_1"
					( Origin gFrontEnd )
				)
				( attribute "TOLERANCE" "10%"
					( Origin gFrontEnd )
				)
				( attribute "VALUE" "0.1UF"
					( Origin gFrontEnd )
				)
				( attribute "VER" "1"
					( Origin gFrontEnd )
				)
				( attribute "VOLTAGE" "16V"
					( Units "uVoltage" "V" 1.000000)
					( Origin gFrontEnd )
				)
				( attribute "XY" "(2250,1525)"
					( Origin gFrontEnd )
				)
				( attribute "CHIPS_PART_NAME" "CAP_A"
					( Origin gPackager )
				)
				( attribute "CDS_PART_NAME" "CAP_A_0402V-0.1UF,16V,10%,X7R,A"
					( Origin gPackager )
				)
				( objectStatus "C3B4" )
				( pin "a"
					( attribute "PN" "1"
						( Origin gPackager )
					)
					( objectStatus "C3B4.1" )
				)
				( pin "b"
					( attribute "PN" "2"
						( Origin gPackager )
					)
					( objectStatus "C3B4.2" )
				)
			)
			( gate "@baseboard_fab2_lib.baseboard_fab2(sch_1):page99_i53"
				( attribute "BOM_COST" "SM_CONTROLLER"
					( Origin gFrontEnd )
				)
				( attribute "CDS_LIB" "dev_discrete"
					( Origin gPackager )
				)
				( attribute "CDS_LOCATION" "C3B5"
					( Origin gPackager )
				)
				( attribute "CDS_SEC" "1"
					( Origin gPackager )
				)
				( attribute "CD_SEC" "1"
					( Origin gFrontEnd )
				)
				( attribute "LOCATION" "C3B5"
					( Origin gFrontEnd )
				)
				( attribute "MATERIAL" "X7R"
					( Origin gFrontEnd )
				)
				( attribute "PACK_TYPE" "0402V"
					( Origin gFrontEnd )
				)
				( attribute "PART_NUMBER" "A36096-030"
					( Origin gFrontEnd )
				)
				( attribute "PHYS_PAGE" "99"
					( Origin gFrontEnd )
				)
				( attribute "ROOM" "MEM"
					( Origin gFrontEnd )
				)
				( attribute "ROT" "0"
					( Origin gFrontEnd )
				)
				( attribute "SEC" "1"
					( Origin gPackager )
				)
				( attribute "SIGNAL_MODEL" "DEFAULT_CAPACITOR_100000pF_2_1"
					( Origin gFrontEnd )
				)
				( attribute "TOLERANCE" "10%"
					( Origin gFrontEnd )
				)
				( attribute "VALUE" "0.1UF"
					( Origin gFrontEnd )
				)
				( attribute "VER" "1"
					( Origin gFrontEnd )
				)
				( attribute "VOLTAGE" "16V"
					( Units "uVoltage" "V" 1.000000)
					( Origin gFrontEnd )
				)
				( attribute "XY" "(1675,1500)"
					( Origin gFrontEnd )
				)
				( attribute "CHIPS_PART_NAME" "CAP_A"
					( Origin gPackager )
				)
				( attribute "CDS_PART_NAME" "CAP_A_0402V-0.1UF,16V,10%,X7R,A"
					( Origin gPackager )
				)
				( objectStatus "C3B5" )
				( pin "a"
					( attribute "PN" "1"
						( Origin gPackager )
					)
					( objectStatus "C3B5.1" )
				)
				( pin "b"
					( attribute "PN" "2"
						( Origin gPackager )
					)
					( objectStatus "C3B5.2" )
				)
			)
			( gate "@baseboard_fab2_lib.baseboard_fab2(sch_1):page99_i55"
				( attribute "CDS_LIB" "mstr_discrete"
					( Origin gPackager )
				)
				( attribute "CDS_LOCATION" "R7M5"
					( Origin gPackager )
				)
				( attribute "CDS_SEC" "1"
					( Origin gPackager )
				)
				( attribute "LOCATION" "R7M5"
					( Origin gFrontEnd )
				)
				( attribute "MATERIAL" "CHIP"
					( Origin gFrontEnd )
				)
				( attribute "PACK_TYPE" "0402"
					( Origin gFrontEnd )
				)
				( attribute "PART_NUMBER" "G21796-173"
					( Origin gFrontEnd )
				)
				( attribute "PHYS_PAGE" "99"
					( Origin gFrontEnd )
				)
				( attribute "ROOM" "MEM"
					( Origin gFrontEnd )
				)
				( attribute "ROT" "0"
					( Origin gFrontEnd )
				)
				( attribute "SEC" "1"
					( Origin gPackager )
				)
				( attribute "TOLERANCE" "1%"
					( Origin gFrontEnd )
				)
				( attribute "VALUE" "20.0"
					( Origin gFrontEnd )
				)
				( attribute "VER" "1"
					( Origin gFrontEnd )
				)
				( attribute "WATTAGE" "1/16W"
					( Origin gFrontEnd )
				)
				( attribute "XY" "(1600,900)"
					( Origin gFrontEnd )
				)
				( attribute "CHIPS_PART_NAME" "RES"
					( Origin gPackager )
				)
				( attribute "CDS_PART_NAME" "RES_0402-20.0,1%,1/16W,CHIP,G2A"
					( Origin gPackager )
				)
				( objectStatus "R7M5" )
				( pin "a"
					( attribute "PN" "1"
						( Origin gPackager )
					)
					( objectStatus "R7M5.1" )
				)
				( pin "b"
					( attribute "PN" "2"
						( Origin gPackager )
					)
					( objectStatus "R7M5.2" )
				)
			)
			( gate "@baseboard_fab2_lib.baseboard_fab2(sch_1):page99_i56"
				( attribute "CDS_LIB" "mstr_discrete"
					( Origin gPackager )
				)
				( attribute "CDS_LOCATION" "R7M4"
					( Origin gPackager )
				)
				( attribute "CDS_SEC" "1"
					( Origin gPackager )
				)
				( attribute "LOCATION" "R7M4"
					( Origin gFrontEnd )
				)
				( attribute "MATERIAL" "CHIP"
					( Origin gFrontEnd )
				)
				( attribute "PACK_TYPE" "0402"
					( Origin gFrontEnd )
				)
				( attribute "PART_NUMBER" "G21796-173"
					( Origin gFrontEnd )
				)
				( attribute "PHYS_PAGE" "99"
					( Origin gFrontEnd )
				)
				( attribute "ROOM" "MEM"
					( Origin gFrontEnd )
				)
				( attribute "ROT" "0"
					( Origin gFrontEnd )
				)
				( attribute "SEC" "1"
					( Origin gPackager )
				)
				( attribute "TOLERANCE" "1%"
					( Origin gFrontEnd )
				)
				( attribute "VALUE" "20.0"
					( Origin gFrontEnd )
				)
				( attribute "VER" "1"
					( Origin gFrontEnd )
				)
				( attribute "WATTAGE" "1/16W"
					( Origin gFrontEnd )
				)
				( attribute "XY" "(1600,950)"
					( Origin gFrontEnd )
				)
				( attribute "CHIPS_PART_NAME" "RES"
					( Origin gPackager )
				)
				( attribute "CDS_PART_NAME" "RES_0402-20.0,1%,1/16W,CHIP,G2A"
					( Origin gPackager )
				)
				( objectStatus "R7M4" )
				( pin "a"
					( attribute "PN" "1"
						( Origin gPackager )
					)
					( objectStatus "R7M4.1" )
				)
				( pin "b"
					( attribute "PN" "2"
						( Origin gPackager )
					)
					( objectStatus "R7M4.2" )
				)
			)
			( gate "@baseboard_fab2_lib.baseboard_fab2(sch_1):page99_i61"
				( attribute "BOM_COST" "SM_CONTROLLER"
					( Origin gFrontEnd )
				)
				( attribute "CDS_LIB" "mstr_digital"
					( Origin gPackager )
				)
				( attribute "CDS_LOCATION" "U7E1"
					( Origin gPackager )
				)
				( attribute "CDS_SEC" "1"
					( Origin gPackager )
				)
				( attribute "LOCATION" "U7E1"
					( Origin gFrontEnd )
				)
				( attribute "MATERIAL" "IC"
					( Origin gFrontEnd )
				)
				( attribute "PACK_TYPE" "SSOP"
					( Origin gFrontEnd )
				)
				( attribute "PART_NUMBER" "G81764-001"
					( Origin gFrontEnd )
				)
				( attribute "PHYS_PAGE" "99"
					( Origin gFrontEnd )
				)
				( attribute "ROOM" "MEM"
					( Origin gFrontEnd )
				)
				( attribute "ROT" "0"
					( Origin gFrontEnd )
				)
				( attribute "SEC" "1"
					( Origin gPackager )
				)
				( attribute "VER" "1"
					( Origin gFrontEnd )
				)
				( attribute "XY" "(150,3250)"
					( Origin gFrontEnd )
				)
				( attribute "CHIPS_PART_NAME" "PCA9617"
					( Origin gPackager )
				)
				( attribute "CDS_PART_NAME" "PCA9617_SSOP-IC,G81764-001"
					( Origin gPackager )
				)
				( objectStatus "U7E1" )
				( pin "en"
					( attribute "PN" "5"
						( Origin gPackager )
					)
					( objectStatus "U7E1.5" )
				)
				( pin "scla"
					( attribute "PN" "2"
						( Origin gPackager )
					)
					( objectStatus "U7E1.2" )
				)
				( pin "sclb"
					( attribute "PN" "7"
						( Origin gPackager )
					)
					( objectStatus "U7E1.7" )
				)
				( pin "sdaa"
					( attribute "PN" "3"
						( Origin gPackager )
					)
					( objectStatus "U7E1.3" )
				)
				( pin "sdab"
					( attribute "PN" "6"
						( Origin gPackager )
					)
					( objectStatus "U7E1.6" )
				)
				( pin "vcca"
					( attribute "PN" "1"
						( Origin gPackager )
					)
					( objectStatus "U7E1.1" )
				)
				( pin "vccb"
					( attribute "PN" "8"
						( Origin gPackager )
					)
					( objectStatus "U7E1.8" )
				)
			)
			( gate "@baseboard_fab2_lib.baseboard_fab2(sch_1):page99_i63"
				( attribute "BOM_COST" "SM_CONTROLLER"
					( Origin gFrontEnd )
				)
				( attribute "CDS_LIB" "mstr_digital"
					( Origin gPackager )
				)
				( attribute "CDS_LOCATION" "U4G1"
					( Origin gPackager )
				)
				( attribute "CDS_SEC" "1"
					( Origin gPackager )
				)
				( attribute "LOCATION" "U4G1"
					( Origin gFrontEnd )
				)
				( attribute "MATERIAL" "IC"
					( Origin gFrontEnd )
				)
				( attribute "PACK_TYPE" "SSOP"
					( Origin gFrontEnd )
				)
				( attribute "PART_NUMBER" "G81764-001"
					( Origin gFrontEnd )
				)
				( attribute "PHYS_PAGE" "99"
					( Origin gFrontEnd )
				)
				( attribute "ROOM" "MEM"
					( Origin gFrontEnd )
				)
				( attribute "ROT" "0"
					( Origin gFrontEnd )
				)
				( attribute "SEC" "1"
					( Origin gPackager )
				)
				( attribute "VER" "1"
					( Origin gFrontEnd )
				)
				( attribute "XY" "(150,2100)"
					( Origin gFrontEnd )
				)
				( attribute "CHIPS_PART_NAME" "PCA9617"
					( Origin gPackager )
				)
				( attribute "CDS_PART_NAME" "PCA9617_SSOP-IC,G81764-001"
					( Origin gPackager )
				)
				( objectStatus "U4G1" )
				( pin "en"
					( attribute "PN" "5"
						( Origin gPackager )
					)
					( objectStatus "U4G1.5" )
				)
				( pin "scla"
					( attribute "PN" "2"
						( Origin gPackager )
					)
					( objectStatus "U4G1.2" )
				)
				( pin "sclb"
					( attribute "PN" "7"
						( Origin gPackager )
					)
					( objectStatus "U4G1.7" )
				)
				( pin "sdaa"
					( attribute "PN" "3"
						( Origin gPackager )
					)
					( objectStatus "U4G1.3" )
				)
				( pin "sdab"
					( attribute "PN" "6"
						( Origin gPackager )
					)
					( objectStatus "U4G1.6" )
				)
				( pin "vcca"
					( attribute "PN" "1"
						( Origin gPackager )
					)
					( objectStatus "U4G1.1" )
				)
				( pin "vccb"
					( attribute "PN" "8"
						( Origin gPackager )
					)
					( objectStatus "U4G1.8" )
				)
			)
			( gate "@baseboard_fab2_lib.baseboard_fab2(sch_1):page99_i65"
				( attribute "BOM_COST" "SM_CONTROLLER"
					( Origin gFrontEnd )
				)
				( attribute "CDS_LIB" "mstr_discrete"
					( Origin gPackager )
				)
				( attribute "CDS_LOCATION" "R3R13"
					( Origin gPackager )
				)
				( attribute "CDS_SEC" "1"
					( Origin gPackager )
				)
				( attribute "CD_SEC" "1"
					( Origin gFrontEnd )
				)
				( attribute "LOCATION" "R3R13"
					( Origin gFrontEnd )
				)
				( attribute "MATERIAL" "CHIP"
					( Origin gFrontEnd )
				)
				( attribute "PACK_TYPE" "0402"
					( Origin gFrontEnd )
				)
				( attribute "PART_NUMBER" "G21796-294"
					( Origin gFrontEnd )
				)
				( attribute "PHYS_PAGE" "99"
					( Origin gFrontEnd )
				)
				( attribute "ROOM" "MEM"
					( Origin gFrontEnd )
				)
				( attribute "ROT" "2"
					( Origin gFrontEnd )
				)
				( attribute "SEC" "1"
					( Origin gPackager )
				)
				( attribute "SIGNAL_MODEL" "DEFAULT_RESISTOR_750OHM_2_1"
					( Origin gFrontEnd )
				)
				( attribute "TOLERANCE" "1.0%"
					( Origin gFrontEnd )
				)
				( attribute "VALUE" "240"
					( Origin gFrontEnd )
				)
				( attribute "VER" "2"
					( Origin gFrontEnd )
				)
				( attribute "WATTAGE" "1/16W"
					( Origin gFrontEnd )
				)
				( attribute "XY" "(-675,3600)"
					( Origin gFrontEnd )
				)
				( attribute "CHIPS_PART_NAME" "RES"
					( Origin gPackager )
				)
				( attribute "CDS_PART_NAME" "RES_0402-240,1.0%,1/16W,CHIP,GA"
					( Origin gPackager )
				)
				( objectStatus "R3R13" )
				( pin "a"
					( attribute "PN" "1"
						( Origin gPackager )
					)
					( objectStatus "R3R13.1" )
				)
				( pin "b"
					( attribute "PN" "2"
						( Origin gPackager )
					)
					( objectStatus "R3R13.2" )
				)
			)
			( gate "@baseboard_fab2_lib.baseboard_fab2(sch_1):page99_i67"
				( attribute "BOM_COST" "SM_CONTROLLER"
					( Origin gFrontEnd )
				)
				( attribute "CDS_LIB" "mstr_discrete"
					( Origin gPackager )
				)
				( attribute "CDS_LOCATION" "R3P60"
					( Origin gPackager )
				)
				( attribute "CDS_SEC" "1"
					( Origin gPackager )
				)
				( attribute "CD_SEC" "1"
					( Origin gFrontEnd )
				)
				( attribute "LOCATION" "R3P60"
					( Origin gFrontEnd )
				)
				( attribute "MATERIAL" "CHIP"
					( Origin gFrontEnd )
				)
				( attribute "PACK_TYPE" "0402"
					( Origin gFrontEnd )
				)
				( attribute "PART_NUMBER" "G21796-294"
					( Origin gFrontEnd )
				)
				( attribute "PHYS_PAGE" "99"
					( Origin gFrontEnd )
				)
				( attribute "ROOM" "MEM"
					( Origin gFrontEnd )
				)
				( attribute "ROT" "2"
					( Origin gFrontEnd )
				)
				( attribute "SEC" "1"
					( Origin gPackager )
				)
				( attribute "SIGNAL_MODEL" "DEFAULT_RESISTOR_750OHM_2_1"
					( Origin gFrontEnd )
				)
				( attribute "TOLERANCE" "1.0%"
					( Origin gFrontEnd )
				)
				( attribute "VALUE" "240"
					( Origin gFrontEnd )
				)
				( attribute "VER" "2"
					( Origin gFrontEnd )
				)
				( attribute "WATTAGE" "1/16W"
					( Origin gFrontEnd )
				)
				( attribute "XY" "(-1050,3600)"
					( Origin gFrontEnd )
				)
				( attribute "CHIPS_PART_NAME" "RES"
					( Origin gPackager )
				)
				( attribute "CDS_PART_NAME" "RES_0402-240,1.0%,1/16W,CHIP,GA"
					( Origin gPackager )
				)
				( objectStatus "R3P60" )
				( pin "a"
					( attribute "PN" "1"
						( Origin gPackager )
					)
					( objectStatus "R3P60.1" )
				)
				( pin "b"
					( attribute "PN" "2"
						( Origin gPackager )
					)
					( objectStatus "R3P60.2" )
				)
			)
			( gate "@baseboard_fab2_lib.baseboard_fab2(sch_1):page99_i70"
				( attribute "BOM_COST" "SM_CONTROLLER"
					( Origin gFrontEnd )
				)
				( attribute "CDS_LIB" "mstr_discrete"
					( Origin gPackager )
				)
				( attribute "CDS_LOCATION" "R6T1"
					( Origin gPackager )
				)
				( attribute "CDS_SEC" "1"
					( Origin gPackager )
				)
				( attribute "CD_SEC" "1"
					( Origin gFrontEnd )
				)
				( attribute "LOCATION" "R6T1"
					( Origin gFrontEnd )
				)
				( attribute "MATERIAL" "CHIP"
					( Origin gFrontEnd )
				)
				( attribute "PACK_TYPE" "0402"
					( Origin gFrontEnd )
				)
				( attribute "PART_NUMBER" "G21796-294"
					( Origin gFrontEnd )
				)
				( attribute "PHYS_PAGE" "99"
					( Origin gFrontEnd )
				)
				( attribute "ROOM" "MEM"
					( Origin gFrontEnd )
				)
				( attribute "ROT" "2"
					( Origin gFrontEnd )
				)
				( attribute "SEC" "1"
					( Origin gPackager )
				)
				( attribute "SIGNAL_MODEL" "DEFAULT_RESISTOR_750OHM_2_1"
					( Origin gFrontEnd )
				)
				( attribute "TOLERANCE" "1.0%"
					( Origin gFrontEnd )
				)
				( attribute "VALUE" "240"
					( Origin gFrontEnd )
				)
				( attribute "VER" "2"
					( Origin gFrontEnd )
				)
				( attribute "WATTAGE" "1/16W"
					( Origin gFrontEnd )
				)
				( attribute "XY" "(-700,2450)"
					( Origin gFrontEnd )
				)
				( attribute "CHIPS_PART_NAME" "RES"
					( Origin gPackager )
				)
				( attribute "CDS_PART_NAME" "RES_0402-240,1.0%,1/16W,CHIP,GA"
					( Origin gPackager )
				)
				( objectStatus "R6T1" )
				( pin "a"
					( attribute "PN" "1"
						( Origin gPackager )
					)
					( objectStatus "R6T1.1" )
				)
				( pin "b"
					( attribute "PN" "2"
						( Origin gPackager )
					)
					( objectStatus "R6T1.2" )
				)
			)
			( gate "@baseboard_fab2_lib.baseboard_fab2(sch_1):page99_i72"
				( attribute "BOM_COST" "SM_CONTROLLER"
					( Origin gFrontEnd )
				)
				( attribute "CDS_LIB" "mstr_discrete"
					( Origin gPackager )
				)
				( attribute "CDS_LOCATION" "R6T2"
					( Origin gPackager )
				)
				( attribute "CDS_SEC" "1"
					( Origin gPackager )
				)
				( attribute "CD_SEC" "1"
					( Origin gFrontEnd )
				)
				( attribute "LOCATION" "R6T2"
					( Origin gFrontEnd )
				)
				( attribute "MATERIAL" "CHIP"
					( Origin gFrontEnd )
				)
				( attribute "PACK_TYPE" "0402"
					( Origin gFrontEnd )
				)
				( attribute "PART_NUMBER" "G21796-294"
					( Origin gFrontEnd )
				)
				( attribute "PHYS_PAGE" "99"
					( Origin gFrontEnd )
				)
				( attribute "ROOM" "MEM"
					( Origin gFrontEnd )
				)
				( attribute "ROT" "2"
					( Origin gFrontEnd )
				)
				( attribute "SEC" "1"
					( Origin gPackager )
				)
				( attribute "SIGNAL_MODEL" "DEFAULT_RESISTOR_750OHM_2_1"
					( Origin gFrontEnd )
				)
				( attribute "TOLERANCE" "1.0%"
					( Origin gFrontEnd )
				)
				( attribute "VALUE" "240"
					( Origin gFrontEnd )
				)
				( attribute "VER" "2"
					( Origin gFrontEnd )
				)
				( attribute "WATTAGE" "1/16W"
					( Origin gFrontEnd )
				)
				( attribute "XY" "(-1075,2450)"
					( Origin gFrontEnd )
				)
				( attribute "CHIPS_PART_NAME" "RES"
					( Origin gPackager )
				)
				( attribute "CDS_PART_NAME" "RES_0402-240,1.0%,1/16W,CHIP,GA"
					( Origin gPackager )
				)
				( objectStatus "R6T2" )
				( pin "a"
					( attribute "PN" "1"
						( Origin gPackager )
					)
					( objectStatus "R6T2.1" )
				)
				( pin "b"
					( attribute "PN" "2"
						( Origin gPackager )
					)
					( objectStatus "R6T2.2" )
				)
			)
			( gate "@baseboard_fab2_lib.baseboard_fab2(sch_1):page99_i75"
				( attribute "BOM_COST" "SM_CONTROLLER"
					( Origin gFrontEnd )
				)
				( attribute "CDS_LIB" "mstr_digital"
					( Origin gPackager )
				)
				( attribute "CDS_LOCATION" "U3B1"
					( Origin gPackager )
				)
				( attribute "CDS_SEC" "1"
					( Origin gPackager )
				)
				( attribute "LOCATION" "U3B1"
					( Origin gFrontEnd )
				)
				( attribute "MATERIAL" "IC"
					( Origin gFrontEnd )
				)
				( attribute "PACK_TYPE" "SSOP"
					( Origin gFrontEnd )
				)
				( attribute "PART_NUMBER" "G81764-001"
					( Origin gFrontEnd )
				)
				( attribute "PHYS_PAGE" "99"
					( Origin gFrontEnd )
				)
				( attribute "ROOM" "MEM"
					( Origin gFrontEnd )
				)
				( attribute "ROT" "0"
					( Origin gFrontEnd )
				)
				( attribute "SEC" "1"
					( Origin gPackager )
				)
				( attribute "VER" "1"
					( Origin gFrontEnd )
				)
				( attribute "XY" "(150,900)"
					( Origin gFrontEnd )
				)
				( attribute "CHIPS_PART_NAME" "PCA9617"
					( Origin gPackager )
				)
				( attribute "CDS_PART_NAME" "PCA9617_SSOP-IC,G81764-001"
					( Origin gPackager )
				)
				( objectStatus "U3B1" )
				( pin "en"
					( attribute "PN" "5"
						( Origin gPackager )
					)
					( objectStatus "U3B1.5" )
				)
				( pin "scla"
					( attribute "PN" "2"
						( Origin gPackager )
					)
					( objectStatus "U3B1.2" )
				)
				( pin "sclb"
					( attribute "PN" "7"
						( Origin gPackager )
					)
					( objectStatus "U3B1.7" )
				)
				( pin "sdaa"
					( attribute "PN" "3"
						( Origin gPackager )
					)
					( objectStatus "U3B1.3" )
				)
				( pin "sdab"
					( attribute "PN" "6"
						( Origin gPackager )
					)
					( objectStatus "U3B1.6" )
				)
				( pin "vcca"
					( attribute "PN" "1"
						( Origin gPackager )
					)
					( objectStatus "U3B1.1" )
				)
				( pin "vccb"
					( attribute "PN" "8"
						( Origin gPackager )
					)
					( objectStatus "U3B1.8" )
				)
			)
			( gate "@baseboard_fab2_lib.baseboard_fab2(sch_1):page99_i77"
				( attribute "BOM_COST" "SM_CONTROLLER"
					( Origin gFrontEnd )
				)
				( attribute "CDS_LIB" "mstr_discrete"
					( Origin gPackager )
				)
				( attribute "CDS_LOCATION" "R7M7"
					( Origin gPackager )
				)
				( attribute "CDS_SEC" "1"
					( Origin gPackager )
				)
				( attribute "CD_SEC" "1"
					( Origin gFrontEnd )
				)
				( attribute "LOCATION" "R7M7"
					( Origin gFrontEnd )
				)
				( attribute "MATERIAL" "CHIP"
					( Origin gFrontEnd )
				)
				( attribute "PACK_TYPE" "0402"
					( Origin gFrontEnd )
				)
				( attribute "PART_NUMBER" "G21796-294"
					( Origin gFrontEnd )
				)
				( attribute "PHYS_PAGE" "99"
					( Origin gFrontEnd )
				)
				( attribute "ROOM" "MEM"
					( Origin gFrontEnd )
				)
				( attribute "ROT" "2"
					( Origin gFrontEnd )
				)
				( attribute "SEC" "1"
					( Origin gPackager )
				)
				( attribute "SIGNAL_MODEL" "DEFAULT_RESISTOR_750OHM_2_1"
					( Origin gFrontEnd )
				)
				( attribute "TOLERANCE" "1.0%"
					( Origin gFrontEnd )
				)
				( attribute "VALUE" "240"
					( Origin gFrontEnd )
				)
				( attribute "VER" "2"
					( Origin gFrontEnd )
				)
				( attribute "WATTAGE" "1/16W"
					( Origin gFrontEnd )
				)
				( attribute "XY" "(-725,1250)"
					( Origin gFrontEnd )
				)
				( attribute "CHIPS_PART_NAME" "RES"
					( Origin gPackager )
				)
				( attribute "CDS_PART_NAME" "RES_0402-240,1.0%,1/16W,CHIP,GA"
					( Origin gPackager )
				)
				( objectStatus "R7M7" )
				( pin "a"
					( attribute "PN" "1"
						( Origin gPackager )
					)
					( objectStatus "R7M7.1" )
				)
				( pin "b"
					( attribute "PN" "2"
						( Origin gPackager )
					)
					( objectStatus "R7M7.2" )
				)
			)
			( gate "@baseboard_fab2_lib.baseboard_fab2(sch_1):page99_i79"
				( attribute "BOM_COST" "SM_CONTROLLER"
					( Origin gFrontEnd )
				)
				( attribute "CDS_LIB" "mstr_discrete"
					( Origin gPackager )
				)
				( attribute "CDS_LOCATION" "R7M2"
					( Origin gPackager )
				)
				( attribute "CDS_SEC" "1"
					( Origin gPackager )
				)
				( attribute "CD_SEC" "1"
					( Origin gFrontEnd )
				)
				( attribute "LOCATION" "R7M2"
					( Origin gFrontEnd )
				)
				( attribute "MATERIAL" "CHIP"
					( Origin gFrontEnd )
				)
				( attribute "PACK_TYPE" "0402"
					( Origin gFrontEnd )
				)
				( attribute "PART_NUMBER" "G21796-294"
					( Origin gFrontEnd )
				)
				( attribute "PHYS_PAGE" "99"
					( Origin gFrontEnd )
				)
				( attribute "ROOM" "MEM"
					( Origin gFrontEnd )
				)
				( attribute "ROT" "2"
					( Origin gFrontEnd )
				)
				( attribute "SEC" "1"
					( Origin gPackager )
				)
				( attribute "SIGNAL_MODEL" "DEFAULT_RESISTOR_750OHM_2_1"
					( Origin gFrontEnd )
				)
				( attribute "TOLERANCE" "1.0%"
					( Origin gFrontEnd )
				)
				( attribute "VALUE" "240"
					( Origin gFrontEnd )
				)
				( attribute "VER" "2"
					( Origin gFrontEnd )
				)
				( attribute "WATTAGE" "1/16W"
					( Origin gFrontEnd )
				)
				( attribute "XY" "(-1100,1250)"
					( Origin gFrontEnd )
				)
				( attribute "CHIPS_PART_NAME" "RES"
					( Origin gPackager )
				)
				( attribute "CDS_PART_NAME" "RES_0402-240,1.0%,1/16W,CHIP,GA"
					( Origin gPackager )
				)
				( objectStatus "R7M2" )
				( pin "a"
					( attribute "PN" "1"
						( Origin gPackager )
					)
					( objectStatus "R7M2.1" )
				)
				( pin "b"
					( attribute "PN" "2"
						( Origin gPackager )
					)
					( objectStatus "R7M2.2" )
				)
			)
			( gate "@baseboard_fab2_lib.baseboard_fab2(sch_1):page99_i83"
				( attribute "BOM_COST" "SM_CONTROLLER"
					( Origin gFrontEnd )
				)
				( attribute "CDS_LIB" "mstr_discrete"
					( Origin gPackager )
				)
				( attribute "CDS_LOCATION" "R4T3"
					( Origin gPackager )
				)
				( attribute "CDS_SEC" "1"
					( Origin gPackager )
				)
				( attribute "LOCATION" "R4T3"
					( Origin gFrontEnd )
				)
				( attribute "MATERIAL" "CHIP"
					( Origin gFrontEnd )
				)
				( attribute "PACK_TYPE" "0402"
					( Origin gFrontEnd )
				)
				( attribute "PART_NUMBER" "G21796-066"
					( Origin gFrontEnd )
				)
				( attribute "PHYS_PAGE" "99"
					( Origin gFrontEnd )
				)
				( attribute "ROOM" "MEM"
					( Origin gFrontEnd )
				)
				( attribute "ROT" "0"
					( Origin gFrontEnd )
				)
				( attribute "SEC" "1"
					( Origin gPackager )
				)
				( attribute "TOLERANCE" "1%"
					( Origin gFrontEnd )
				)
				( attribute "VALUE" "10.0"
					( Origin gFrontEnd )
				)
				( attribute "VER" "1"
					( Origin gFrontEnd )
				)
				( attribute "WATTAGE" "1/16W"
					( Origin gFrontEnd )
				)
				( attribute "XY" "(-1500,4350)"
					( Origin gFrontEnd )
				)
				( attribute "CHIPS_PART_NAME" "RES"
					( Origin gPackager )
				)
				( attribute "CDS_PART_NAME" "RES_0402-10.0,1%,1/16W,CHIP,G2A"
					( Origin gPackager )
				)
				( objectStatus "R4T3" )
				( pin "a"
					( attribute "PN" "1"
						( Origin gPackager )
					)
					( objectStatus "R4T3.1" )
				)
				( pin "b"
					( attribute "PN" "2"
						( Origin gPackager )
					)
					( objectStatus "R4T3.2" )
				)
			)
			( gate "@baseboard_fab2_lib.baseboard_fab2(sch_1):page99_i88"
				( attribute "BOM_COST" "SM_CONTROLLER"
					( Origin gFrontEnd )
				)
				( attribute "CDS_LIB" "mstr_discrete"
					( Origin gPackager )
				)
				( attribute "CDS_LOCATION" "R3R7"
					( Origin gPackager )
				)
				( attribute "CDS_SEC" "1"
					( Origin gPackager )
				)
				( attribute "LOCATION" "R3R7"
					( Origin gFrontEnd )
				)
				( attribute "MATERIAL" "CHIP"
					( Origin gFrontEnd )
				)
				( attribute "PACK_TYPE" "0402"
					( Origin gFrontEnd )
				)
				( attribute "PART_NUMBER" "G21796-066"
					( Origin gFrontEnd )
				)
				( attribute "PHYS_PAGE" "99"
					( Origin gFrontEnd )
				)
				( attribute "ROOM" "MEM"
					( Origin gFrontEnd )
				)
				( attribute "ROT" "0"
					( Origin gFrontEnd )
				)
				( attribute "SEC" "1"
					( Origin gPackager )
				)
				( attribute "TOLERANCE" "1%"
					( Origin gFrontEnd )
				)
				( attribute "VALUE" "10.0"
					( Origin gFrontEnd )
				)
				( attribute "VER" "1"
					( Origin gFrontEnd )
				)
				( attribute "WATTAGE" "1/16W"
					( Origin gFrontEnd )
				)
				( attribute "XY" "(-1575,3300)"
					( Origin gFrontEnd )
				)
				( attribute "CHIPS_PART_NAME" "RES"
					( Origin gPackager )
				)
				( attribute "CDS_PART_NAME" "RES_0402-10.0,1%,1/16W,CHIP,G2A"
					( Origin gPackager )
				)
				( objectStatus "R3R7" )
				( pin "a"
					( attribute "PN" "1"
						( Origin gPackager )
					)
					( objectStatus "R3R7.1" )
				)
				( pin "b"
					( attribute "PN" "2"
						( Origin gPackager )
					)
					( objectStatus "R3R7.2" )
				)
			)
			( gate "@baseboard_fab2_lib.baseboard_fab2(sch_1):page99_i92"
				( attribute "BOM_COST" "SM_CONTROLLER"
					( Origin gFrontEnd )
				)
				( attribute "CDS_LIB" "mstr_discrete"
					( Origin gPackager )
				)
				( attribute "CDS_LOCATION" "R6T3"
					( Origin gPackager )
				)
				( attribute "CDS_SEC" "1"
					( Origin gPackager )
				)
				( attribute "LOCATION" "R6T3"
					( Origin gFrontEnd )
				)
				( attribute "MATERIAL" "CHIP"
					( Origin gFrontEnd )
				)
				( attribute "PACK_TYPE" "0402"
					( Origin gFrontEnd )
				)
				( attribute "PART_NUMBER" "G21796-066"
					( Origin gFrontEnd )
				)
				( attribute "PHYS_PAGE" "99"
					( Origin gFrontEnd )
				)
				( attribute "ROOM" "MEM"
					( Origin gFrontEnd )
				)
				( attribute "ROT" "0"
					( Origin gFrontEnd )
				)
				( attribute "SEC" "1"
					( Origin gPackager )
				)
				( attribute "TOLERANCE" "1%"
					( Origin gFrontEnd )
				)
				( attribute "VALUE" "10.0"
					( Origin gFrontEnd )
				)
				( attribute "VER" "1"
					( Origin gFrontEnd )
				)
				( attribute "WATTAGE" "1/16W"
					( Origin gFrontEnd )
				)
				( attribute "XY" "(-1475,2150)"
					( Origin gFrontEnd )
				)
				( attribute "CHIPS_PART_NAME" "RES"
					( Origin gPackager )
				)
				( attribute "CDS_PART_NAME" "RES_0402-10.0,1%,1/16W,CHIP,G2A"
					( Origin gPackager )
				)
				( objectStatus "R6T3" )
				( pin "a"
					( attribute "PN" "1"
						( Origin gPackager )
					)
					( objectStatus "R6T3.1" )
				)
				( pin "b"
					( attribute "PN" "2"
						( Origin gPackager )
					)
					( objectStatus "R6T3.2" )
				)
			)
			( gate "@baseboard_fab2_lib.baseboard_fab2(sch_1):page99_i98"
				( attribute "BOM_COST" "SM_CONTROLLER"
					( Origin gFrontEnd )
				)
				( attribute "CDS_LIB" "mstr_discrete"
					( Origin gPackager )
				)
				( attribute "CDS_LOCATION" "R7M3"
					( Origin gPackager )
				)
				( attribute "CDS_SEC" "1"
					( Origin gPackager )
				)
				( attribute "LOCATION" "R7M3"
					( Origin gFrontEnd )
				)
				( attribute "MATERIAL" "CHIP"
					( Origin gFrontEnd )
				)
				( attribute "PACK_TYPE" "0402"
					( Origin gFrontEnd )
				)
				( attribute "PART_NUMBER" "G21796-066"
					( Origin gFrontEnd )
				)
				( attribute "PHYS_PAGE" "99"
					( Origin gFrontEnd )
				)
				( attribute "ROOM" "MEM"
					( Origin gFrontEnd )
				)
				( attribute "ROT" "0"
					( Origin gFrontEnd )
				)
				( attribute "SEC" "1"
					( Origin gPackager )
				)
				( attribute "TOLERANCE" "1%"
					( Origin gFrontEnd )
				)
				( attribute "VALUE" "10.0"
					( Origin gFrontEnd )
				)
				( attribute "VER" "1"
					( Origin gFrontEnd )
				)
				( attribute "WATTAGE" "1/16W"
					( Origin gFrontEnd )
				)
				( attribute "XY" "(-1575,950)"
					( Origin gFrontEnd )
				)
				( attribute "CHIPS_PART_NAME" "RES"
					( Origin gPackager )
				)
				( attribute "CDS_PART_NAME" "RES_0402-10.0,1%,1/16W,CHIP,G2A"
					( Origin gPackager )
				)
				( objectStatus "R7M3" )
				( pin "a"
					( attribute "PN" "1"
						( Origin gPackager )
					)
					( objectStatus "R7M3.1" )
				)
				( pin "b"
					( attribute "PN" "2"
						( Origin gPackager )
					)
					( objectStatus "R7M3.2" )
				)
			)
			( gate "@baseboard_fab2_lib.baseboard_fab2(sch_1):page99_i101"
				( attribute "BOM_COST" "SM_CONTROLLER"
					( Origin gFrontEnd )
				)
				( attribute "CDS_LIB" "mstr_discrete"
					( Origin gPackager )
				)
				( attribute "CDS_LOCATION" "R3R12"
					( Origin gPackager )
				)
				( attribute "CDS_SEC" "1"
					( Origin gPackager )
				)
				( attribute "LOCATION" "R3R12"
					( Origin gFrontEnd )
				)
				( attribute "MATERIAL" "CHIP"
					( Origin gFrontEnd )
				)
				( attribute "PACK_TYPE" "0402"
					( Origin gFrontEnd )
				)
				( attribute "PART_NUMBER" "G21796-235"
					( Origin gFrontEnd )
				)
				( attribute "PHYS_PAGE" "99"
					( Origin gFrontEnd )
				)
				( attribute "ROOM" "MEM"
					( Origin gFrontEnd )
				)
				( attribute "ROT" "0"
					( Origin gFrontEnd )
				)
				( attribute "SEC" "1"
					( Origin gFrontEnd )
				)
				( attribute "SEC_TYPE" "0402"
					( Origin gFrontEnd )
				)
				( attribute "TOLERANCE" "1.0%"
					( Origin gFrontEnd )
				)
				( attribute "VALUE" "665"
					( Origin gFrontEnd )
				)
				( attribute "VER" "2"
					( Origin gFrontEnd )
				)
				( attribute "WATTAGE" "1/16W"
					( Origin gFrontEnd )
				)
				( attribute "XY" "(1275,3600)"
					( Origin gFrontEnd )
				)
				( attribute "CHIPS_PART_NAME" "RES"
					( Origin gPackager )
				)
				( attribute "CDS_PART_NAME" "RES_0402-665,1.0%,1/16W,CHIP,GA"
					( Origin gPackager )
				)
				( objectStatus "R3R12" )
				( pin "a"
					( attribute "PN" "1"
						( Origin gPackager )
					)
					( objectStatus "R3R12.1" )
				)
				( pin "b"
					( attribute "PN" "2"
						( Origin gPackager )
					)
					( objectStatus "R3R12.2" )
				)
			)
			( gate "@baseboard_fab2_lib.baseboard_fab2(sch_1):page99_i103"
				( attribute "BOM_COST" "SM_CONTROLLER"
					( Origin gFrontEnd )
				)
				( attribute "CDS_LIB" "mstr_discrete"
					( Origin gPackager )
				)
				( attribute "CDS_LOCATION" "R3R5"
					( Origin gPackager )
				)
				( attribute "CDS_SEC" "1"
					( Origin gPackager )
				)
				( attribute "LOCATION" "R3R5"
					( Origin gFrontEnd )
				)
				( attribute "MATERIAL" "CHIP"
					( Origin gFrontEnd )
				)
				( attribute "PACK_TYPE" "0402"
					( Origin gFrontEnd )
				)
				( attribute "PART_NUMBER" "G21796-235"
					( Origin gFrontEnd )
				)
				( attribute "PHYS_PAGE" "99"
					( Origin gFrontEnd )
				)
				( attribute "ROOM" "MEM"
					( Origin gFrontEnd )
				)
				( attribute "ROT" "0"
					( Origin gFrontEnd )
				)
				( attribute "SEC" "1"
					( Origin gFrontEnd )
				)
				( attribute "SEC_TYPE" "0402"
					( Origin gFrontEnd )
				)
				( attribute "TOLERANCE" "1.0%"
					( Origin gFrontEnd )
				)
				( attribute "VALUE" "665"
					( Origin gFrontEnd )
				)
				( attribute "VER" "2"
					( Origin gFrontEnd )
				)
				( attribute "WATTAGE" "1/16W"
					( Origin gFrontEnd )
				)
				( attribute "XY" "(925,3600)"
					( Origin gFrontEnd )
				)
				( attribute "CHIPS_PART_NAME" "RES"
					( Origin gPackager )
				)
				( attribute "CDS_PART_NAME" "RES_0402-665,1.0%,1/16W,CHIP,GA"
					( Origin gPackager )
				)
				( objectStatus "R3R5" )
				( pin "a"
					( attribute "PN" "1"
						( Origin gPackager )
					)
					( objectStatus "R3R5.1" )
				)
				( pin "b"
					( attribute "PN" "2"
						( Origin gPackager )
					)
					( objectStatus "R3R5.2" )
				)
			)
			( gate "@baseboard_fab2_lib.baseboard_fab2(sch_1):page99_i104"
				( attribute "BOM_COST" "SM_CONTROLLER"
					( Origin gFrontEnd )
				)
				( attribute "CDS_LIB" "mstr_discrete"
					( Origin gPackager )
				)
				( attribute "CDS_LOCATION" "R6U18"
					( Origin gPackager )
				)
				( attribute "CDS_SEC" "1"
					( Origin gPackager )
				)
				( attribute "LOCATION" "R6U18"
					( Origin gFrontEnd )
				)
				( attribute "MATERIAL" "CHIP"
					( Origin gFrontEnd )
				)
				( attribute "PACK_TYPE" "0402"
					( Origin gFrontEnd )
				)
				( attribute "PART_NUMBER" "G21796-235"
					( Origin gFrontEnd )
				)
				( attribute "PHYS_PAGE" "99"
					( Origin gFrontEnd )
				)
				( attribute "ROOM" "MEM"
					( Origin gFrontEnd )
				)
				( attribute "ROT" "0"
					( Origin gFrontEnd )
				)
				( attribute "SEC" "1"
					( Origin gFrontEnd )
				)
				( attribute "SEC_TYPE" "0402"
					( Origin gFrontEnd )
				)
				( attribute "TOLERANCE" "1.0%"
					( Origin gFrontEnd )
				)
				( attribute "VALUE" "665"
					( Origin gFrontEnd )
				)
				( attribute "VER" "2"
					( Origin gFrontEnd )
				)
				( attribute "WATTAGE" "1/16W"
					( Origin gFrontEnd )
				)
				( attribute "XY" "(1225,2450)"
					( Origin gFrontEnd )
				)
				( attribute "CHIPS_PART_NAME" "RES"
					( Origin gPackager )
				)
				( attribute "CDS_PART_NAME" "RES_0402-665,1.0%,1/16W,CHIP,GA"
					( Origin gPackager )
				)
				( objectStatus "R6U18" )
				( pin "a"
					( attribute "PN" "1"
						( Origin gPackager )
					)
					( objectStatus "R6U18.1" )
				)
				( pin "b"
					( attribute "PN" "2"
						( Origin gPackager )
					)
					( objectStatus "R6U18.2" )
				)
			)
			( gate "@baseboard_fab2_lib.baseboard_fab2(sch_1):page99_i106"
				( attribute "BOM_COST" "SM_CONTROLLER"
					( Origin gFrontEnd )
				)
				( attribute "CDS_LIB" "mstr_discrete"
					( Origin gPackager )
				)
				( attribute "CDS_LOCATION" "R6U17"
					( Origin gPackager )
				)
				( attribute "CDS_SEC" "1"
					( Origin gPackager )
				)
				( attribute "LOCATION" "R6U17"
					( Origin gFrontEnd )
				)
				( attribute "MATERIAL" "CHIP"
					( Origin gFrontEnd )
				)
				( attribute "PACK_TYPE" "0402"
					( Origin gFrontEnd )
				)
				( attribute "PART_NUMBER" "G21796-235"
					( Origin gFrontEnd )
				)
				( attribute "PHYS_PAGE" "99"
					( Origin gFrontEnd )
				)
				( attribute "ROOM" "MEM"
					( Origin gFrontEnd )
				)
				( attribute "ROT" "0"
					( Origin gFrontEnd )
				)
				( attribute "SEC" "1"
					( Origin gFrontEnd )
				)
				( attribute "SEC_TYPE" "0402"
					( Origin gFrontEnd )
				)
				( attribute "TOLERANCE" "1.0%"
					( Origin gFrontEnd )
				)
				( attribute "VALUE" "665"
					( Origin gFrontEnd )
				)
				( attribute "VER" "2"
					( Origin gFrontEnd )
				)
				( attribute "WATTAGE" "1/16W"
					( Origin gFrontEnd )
				)
				( attribute "XY" "(875,2450)"
					( Origin gFrontEnd )
				)
				( attribute "CHIPS_PART_NAME" "RES"
					( Origin gPackager )
				)
				( attribute "CDS_PART_NAME" "RES_0402-665,1.0%,1/16W,CHIP,GA"
					( Origin gPackager )
				)
				( objectStatus "R6U17" )
				( pin "a"
					( attribute "PN" "1"
						( Origin gPackager )
					)
					( objectStatus "R6U17.1" )
				)
				( pin "b"
					( attribute "PN" "2"
						( Origin gPackager )
					)
					( objectStatus "R6U17.2" )
				)
			)
			( gate "@baseboard_fab2_lib.baseboard_fab2(sch_1):page99_i107"
				( attribute "BOM_COST" "SM_CONTROLLER"
					( Origin gFrontEnd )
				)
				( attribute "CDS_LIB" "mstr_discrete"
					( Origin gPackager )
				)
				( attribute "CDS_LOCATION" "R7M6"
					( Origin gPackager )
				)
				( attribute "CDS_SEC" "1"
					( Origin gPackager )
				)
				( attribute "LOCATION" "R7M6"
					( Origin gFrontEnd )
				)
				( attribute "MATERIAL" "CHIP"
					( Origin gFrontEnd )
				)
				( attribute "PACK_TYPE" "0402"
					( Origin gFrontEnd )
				)
				( attribute "PART_NUMBER" "G21796-235"
					( Origin gFrontEnd )
				)
				( attribute "PHYS_PAGE" "99"
					( Origin gFrontEnd )
				)
				( attribute "ROOM" "MEM"
					( Origin gFrontEnd )
				)
				( attribute "ROT" "0"
					( Origin gFrontEnd )
				)
				( attribute "SEC" "1"
					( Origin gFrontEnd )
				)
				( attribute "SEC_TYPE" "0402"
					( Origin gFrontEnd )
				)
				( attribute "TOLERANCE" "1.0%"
					( Origin gFrontEnd )
				)
				( attribute "VALUE" "665"
					( Origin gFrontEnd )
				)
				( attribute "VER" "2"
					( Origin gFrontEnd )
				)
				( attribute "WATTAGE" "1/16W"
					( Origin gFrontEnd )
				)
				( attribute "XY" "(1225,1250)"
					( Origin gFrontEnd )
				)
				( attribute "CHIPS_PART_NAME" "RES"
					( Origin gPackager )
				)
				( attribute "CDS_PART_NAME" "RES_0402-665,1.0%,1/16W,CHIP,GA"
					( Origin gPackager )
				)
				( objectStatus "R7M6" )
				( pin "a"
					( attribute "PN" "1"
						( Origin gPackager )
					)
					( objectStatus "R7M6.1" )
				)
				( pin "b"
					( attribute "PN" "2"
						( Origin gPackager )
					)
					( objectStatus "R7M6.2" )
				)
			)
			( gate "@baseboard_fab2_lib.baseboard_fab2(sch_1):page99_i109"
				( attribute "BOM_COST" "SM_CONTROLLER"
					( Origin gFrontEnd )
				)
				( attribute "CDS_LIB" "mstr_discrete"
					( Origin gPackager )
				)
				( attribute "CDS_LOCATION" "R7M1"
					( Origin gPackager )
				)
				( attribute "CDS_SEC" "1"
					( Origin gPackager )
				)
				( attribute "LOCATION" "R7M1"
					( Origin gFrontEnd )
				)
				( attribute "MATERIAL" "CHIP"
					( Origin gFrontEnd )
				)
				( attribute "PACK_TYPE" "0402"
					( Origin gFrontEnd )
				)
				( attribute "PART_NUMBER" "G21796-235"
					( Origin gFrontEnd )
				)
				( attribute "PHYS_PAGE" "99"
					( Origin gFrontEnd )
				)
				( attribute "ROOM" "MEM"
					( Origin gFrontEnd )
				)
				( attribute "ROT" "0"
					( Origin gFrontEnd )
				)
				( attribute "SEC" "1"
					( Origin gFrontEnd )
				)
				( attribute "SEC_TYPE" "0402"
					( Origin gFrontEnd )
				)
				( attribute "TOLERANCE" "1.0%"
					( Origin gFrontEnd )
				)
				( attribute "VALUE" "665"
					( Origin gFrontEnd )
				)
				( attribute "VER" "2"
					( Origin gFrontEnd )
				)
				( attribute "WATTAGE" "1/16W"
					( Origin gFrontEnd )
				)
				( attribute "XY" "(875,1250)"
					( Origin gFrontEnd )
				)
				( attribute "CHIPS_PART_NAME" "RES"
					( Origin gPackager )
				)
				( attribute "CDS_PART_NAME" "RES_0402-665,1.0%,1/16W,CHIP,GA"
					( Origin gPackager )
				)
				( objectStatus "R7M1" )
				( pin "a"
					( attribute "PN" "1"
						( Origin gPackager )
					)
					( objectStatus "R7M1.1" )
				)
				( pin "b"
					( attribute "PN" "2"
						( Origin gPackager )
					)
					( objectStatus "R7M1.2" )
				)
			)
			( gate "@baseboard_fab2_lib.baseboard_fab2(sch_1):page99_i110"
				( attribute "BOM_COST" "SM_CONTROLLER"
					( Origin gFrontEnd )
				)
				( attribute "CDS_LIB" "mstr_discrete"
					( Origin gPackager )
				)
				( attribute "CDS_LOCATION" "R3R14"
					( Origin gPackager )
				)
				( attribute "CDS_SEC" "1"
					( Origin gPackager )
				)
				( attribute "LOCATION" "R3R14"
					( Origin gFrontEnd )
				)
				( attribute "MATERIAL" "CHIP"
					( Origin gFrontEnd )
				)
				( attribute "PACK_TYPE" "0402"
					( Origin gFrontEnd )
				)
				( attribute "PART_NUMBER" "G21796-066"
					( Origin gFrontEnd )
				)
				( attribute "PHYS_PAGE" "99"
					( Origin gFrontEnd )
				)
				( attribute "ROOM" "MEM"
					( Origin gFrontEnd )
				)
				( attribute "ROT" "0"
					( Origin gFrontEnd )
				)
				( attribute "SEC" "1"
					( Origin gPackager )
				)
				( attribute "TOLERANCE" "1%"
					( Origin gFrontEnd )
				)
				( attribute "VALUE" "10.0"
					( Origin gFrontEnd )
				)
				( attribute "VER" "1"
					( Origin gFrontEnd )
				)
				( attribute "WATTAGE" "1/16W"
					( Origin gFrontEnd )
				)
				( attribute "XY" "(-1175,3250)"
					( Origin gFrontEnd )
				)
				( attribute "CHIPS_PART_NAME" "RES"
					( Origin gPackager )
				)
				( attribute "CDS_PART_NAME" "RES_0402-10.0,1%,1/16W,CHIP,G2A"
					( Origin gPackager )
				)
				( objectStatus "R3R14" )
				( pin "a"
					( attribute "PN" "1"
						( Origin gPackager )
					)
					( objectStatus "R3R14.1" )
				)
				( pin "b"
					( attribute "PN" "2"
						( Origin gPackager )
					)
					( objectStatus "R3R14.2" )
				)
			)
			( gate "@baseboard_fab2_lib.baseboard_fab2(sch_1):page99_i111"
				( attribute "BOM_COST" "SM_CONTROLLER"
					( Origin gFrontEnd )
				)
				( attribute "CDS_LIB" "mstr_discrete"
					( Origin gPackager )
				)
				( attribute "CDS_LOCATION" "R6T4"
					( Origin gPackager )
				)
				( attribute "CDS_SEC" "1"
					( Origin gPackager )
				)
				( attribute "LOCATION" "R6T4"
					( Origin gFrontEnd )
				)
				( attribute "MATERIAL" "CHIP"
					( Origin gFrontEnd )
				)
				( attribute "PACK_TYPE" "0402"
					( Origin gFrontEnd )
				)
				( attribute "PART_NUMBER" "G21796-066"
					( Origin gFrontEnd )
				)
				( attribute "PHYS_PAGE" "99"
					( Origin gFrontEnd )
				)
				( attribute "ROOM" "MEM"
					( Origin gFrontEnd )
				)
				( attribute "ROT" "0"
					( Origin gFrontEnd )
				)
				( attribute "SEC" "1"
					( Origin gPackager )
				)
				( attribute "TOLERANCE" "1%"
					( Origin gFrontEnd )
				)
				( attribute "VALUE" "10.0"
					( Origin gFrontEnd )
				)
				( attribute "VER" "1"
					( Origin gFrontEnd )
				)
				( attribute "WATTAGE" "1/16W"
					( Origin gFrontEnd )
				)
				( attribute "XY" "(-1100,2100)"
					( Origin gFrontEnd )
				)
				( attribute "CHIPS_PART_NAME" "RES"
					( Origin gPackager )
				)
				( attribute "CDS_PART_NAME" "RES_0402-10.0,1%,1/16W,CHIP,G2A"
					( Origin gPackager )
				)
				( objectStatus "R6T4" )
				( pin "a"
					( attribute "PN" "1"
						( Origin gPackager )
					)
					( objectStatus "R6T4.1" )
				)
				( pin "b"
					( attribute "PN" "2"
						( Origin gPackager )
					)
					( objectStatus "R6T4.2" )
				)
			)
			( gate "@baseboard_fab2_lib.baseboard_fab2(sch_1):page99_i112"
				( attribute "BOM_COST" "SM_CONTROLLER"
					( Origin gFrontEnd )
				)
				( attribute "CDS_LIB" "mstr_discrete"
					( Origin gPackager )
				)
				( attribute "CDS_LOCATION" "R7M8"
					( Origin gPackager )
				)
				( attribute "CDS_SEC" "1"
					( Origin gPackager )
				)
				( attribute "LOCATION" "R7M8"
					( Origin gFrontEnd )
				)
				( attribute "MATERIAL" "CHIP"
					( Origin gFrontEnd )
				)
				( attribute "PACK_TYPE" "0402"
					( Origin gFrontEnd )
				)
				( attribute "PART_NUMBER" "G21796-066"
					( Origin gFrontEnd )
				)
				( attribute "PHYS_PAGE" "99"
					( Origin gFrontEnd )
				)
				( attribute "ROOM" "MEM"
					( Origin gFrontEnd )
				)
				( attribute "ROT" "0"
					( Origin gFrontEnd )
				)
				( attribute "SEC" "1"
					( Origin gPackager )
				)
				( attribute "TOLERANCE" "1%"
					( Origin gFrontEnd )
				)
				( attribute "VALUE" "10.0"
					( Origin gFrontEnd )
				)
				( attribute "VER" "1"
					( Origin gFrontEnd )
				)
				( attribute "WATTAGE" "1/16W"
					( Origin gFrontEnd )
				)
				( attribute "XY" "(-1200,900)"
					( Origin gFrontEnd )
				)
				( attribute "CHIPS_PART_NAME" "RES"
					( Origin gPackager )
				)
				( attribute "CDS_PART_NAME" "RES_0402-10.0,1%,1/16W,CHIP,G2A"
					( Origin gPackager )
				)
				( objectStatus "R7M8" )
				( pin "a"
					( attribute "PN" "1"
						( Origin gPackager )
					)
					( objectStatus "R7M8.1" )
				)
				( pin "b"
					( attribute "PN" "2"
						( Origin gPackager )
					)
					( objectStatus "R7M8.2" )
				)
			)
			( gate "@baseboard_fab2_lib.baseboard_fab2(sch_1):page100_i2"
				( attribute "BOM_COST" "SM_CONTROLLER"
					( Origin gFrontEnd )
				)
				( attribute "CDS_LIB" "mstr_discrete"
					( Origin gPackager )
				)
				( attribute "CDS_LOCATION" "R1F6"
					( Origin gPackager )
				)
				( attribute "CDS_SEC" "1"
					( Origin gPackager )
				)
				( attribute "LOCATION" "R1F6"
					( Origin gFrontEnd )
				)
				( attribute "MATERIAL" "CHIP"
					( Origin gFrontEnd )
				)
				( attribute "PACK_TYPE" "0402"
					( Origin gFrontEnd )
				)
				( attribute "PART_NUMBER" "G21796-026"
					( Origin gFrontEnd )
				)
				( attribute "PHYS_PAGE" "100"
					( Origin gFrontEnd )
				)
				( attribute "ROOM" "MEM"
					( Origin gFrontEnd )
				)
				( attribute "ROT" "2"
					( Origin gFrontEnd )
				)
				( attribute "SEC" "1"
					( Origin gFrontEnd )
				)
				( attribute "SEC_TYPE" "0402"
					( Origin gFrontEnd )
				)
				( attribute "TOLERANCE" "1%"
					( Origin gFrontEnd )
				)
				( attribute "VALUE" "1.00K"
					( Origin gFrontEnd )
				)
				( attribute "VER" "2"
					( Origin gFrontEnd )
				)
				( attribute "WATTAGE" "1/16W"
					( Origin gFrontEnd )
				)
				( attribute "XY" "(-1825,3300)"
					( Origin gFrontEnd )
				)
				( attribute "CHIPS_PART_NAME" "RES"
					( Origin gPackager )
				)
				( attribute "CDS_PART_NAME" "RES_0402-1.00K,1%,1/16W,CHIP,GA"
					( Origin gPackager )
				)
				( objectStatus "R1F6" )
				( pin "a"
					( attribute "PN" "1"
						( Origin gPackager )
					)
					( objectStatus "R1F6.1" )
				)
				( pin "b"
					( attribute "PN" "2"
						( Origin gPackager )
					)
					( objectStatus "R1F6.2" )
				)
			)
			( gate "@baseboard_fab2_lib.baseboard_fab2(sch_1):page100_i4"
				( attribute "BOM_COST" "PROC_SOCKET"
					( Origin gFrontEnd )
				)
				( attribute "CDS_LIB" "mstr_discrete"
					( Origin gPackager )
				)
				( attribute "CDS_LOCATION" "R9L11"
					( Origin gPackager )
				)
				( attribute "CDS_SEC" "1"
					( Origin gPackager )
				)
				( attribute "LOCATION" "R9L11"
					( Origin gFrontEnd )
				)
				( attribute "MATERIAL" "CHIP"
					( Origin gFrontEnd )
				)
				( attribute "PACK_TYPE" "0402"
					( Origin gFrontEnd )
				)
				( attribute "PART_NUMBER" "G21796-026"
					( Origin gFrontEnd )
				)
				( attribute "PHYS_PAGE" "100"
					( Origin gFrontEnd )
				)
				( attribute "ROOM" "PROC"
					( Origin gFrontEnd )
				)
				( attribute "ROT" "2"
					( Origin gFrontEnd )
				)
				( attribute "SEC" "1"
					( Origin gFrontEnd )
				)
				( attribute "SEC_TYPE" "0402"
					( Origin gFrontEnd )
				)
				( attribute "TOLERANCE" "1%"
					( Origin gFrontEnd )
				)
				( attribute "VALUE" "1.00K"
					( Origin gFrontEnd )
				)
				( attribute "VER" "2"
					( Origin gFrontEnd )
				)
				( attribute "WATTAGE" "1/16W"
					( Origin gFrontEnd )
				)
				( attribute "XY" "(-1825,1625)"
					( Origin gFrontEnd )
				)
				( attribute "CHIPS_PART_NAME" "RES"
					( Origin gPackager )
				)
				( attribute "CDS_PART_NAME" "RES_0402-1.00K,1%,1/16W,CHIP,GA"
					( Origin gPackager )
				)
				( objectStatus "R9L11" )
				( pin "a"
					( attribute "PN" "1"
						( Origin gPackager )
					)
					( objectStatus "R9L11.1" )
				)
				( pin "b"
					( attribute "PN" "2"
						( Origin gPackager )
					)
					( objectStatus "R9L11.2" )
				)
			)
			( gate "@baseboard_fab2_lib.baseboard_fab2(sch_1):page100_i6"
				( attribute "BOM_COST" "SM_CONTROLLER"
					( Origin gFrontEnd )
				)
				( attribute "CDS_LIB" "mstr_discrete"
					( Origin gPackager )
				)
				( attribute "CDS_LOCATION" "R1F5"
					( Origin gPackager )
				)
				( attribute "CDS_SEC" "1"
					( Origin gPackager )
				)
				( attribute "LOCATION" "R1F5"
					( Origin gFrontEnd )
				)
				( attribute "MATERIAL" "CHIP"
					( Origin gFrontEnd )
				)
				( attribute "PACK_TYPE" "0402"
					( Origin gFrontEnd )
				)
				( attribute "PART_NUMBER" "G21796-026"
					( Origin gFrontEnd )
				)
				( attribute "PHYS_PAGE" "100"
					( Origin gFrontEnd )
				)
				( attribute "ROOM" "MEM"
					( Origin gFrontEnd )
				)
				( attribute "ROT" "2"
					( Origin gFrontEnd )
				)
				( attribute "SEC" "1"
					( Origin gFrontEnd )
				)
				( attribute "SEC_TYPE" "0402"
					( Origin gFrontEnd )
				)
				( attribute "TOLERANCE" "1%"
					( Origin gFrontEnd )
				)
				( attribute "VALUE" "1.00K"
					( Origin gFrontEnd )
				)
				( attribute "VER" "2"
					( Origin gFrontEnd )
				)
				( attribute "WATTAGE" "1/16W"
					( Origin gFrontEnd )
				)
				( attribute "XY" "(-1900,3950)"
					( Origin gFrontEnd )
				)
				( attribute "CHIPS_PART_NAME" "RES"
					( Origin gPackager )
				)
				( attribute "CDS_PART_NAME" "RES_0402-1.00K,1%,1/16W,CHIP,GA"
					( Origin gPackager )
				)
				( objectStatus "R1F5" )
				( pin "a"
					( attribute "PN" "1"
						( Origin gPackager )
					)
					( objectStatus "R1F5.1" )
				)
				( pin "b"
					( attribute "PN" "2"
						( Origin gPackager )
					)
					( objectStatus "R1F5.2" )
				)
			)
			( gate "@baseboard_fab2_lib.baseboard_fab2(sch_1):page100_i7"
				( attribute "BOM_COST" "PROC_SOCKET"
					( Origin gFrontEnd )
				)
				( attribute "CDS_LIB" "mstr_discrete"
					( Origin gPackager )
				)
				( attribute "CDS_LOCATION" "R1F4"
					( Origin gPackager )
				)
				( attribute "CDS_SEC" "1"
					( Origin gPackager )
				)
				( attribute "LOCATION" "R1F4"
					( Origin gFrontEnd )
				)
				( attribute "MATERIAL" "CHIP"
					( Origin gFrontEnd )
				)
				( attribute "PACK_TYPE" "0402"
					( Origin gFrontEnd )
				)
				( attribute "PART_NUMBER" "G21796-274"
					( Origin gFrontEnd )
				)
				( attribute "PHYS_PAGE" "100"
					( Origin gFrontEnd )
				)
				( attribute "ROOM" "PROC"
					( Origin gFrontEnd )
				)
				( attribute "ROT" "0"
					( Origin gFrontEnd )
				)
				( attribute "SEC" "1"
					( Origin gFrontEnd )
				)
				( attribute "SEC_TYPE" "0402"
					( Origin gFrontEnd )
				)
				( attribute "TOLERANCE" "1.0%"
					( Origin gFrontEnd )
				)
				( attribute "VALUE" "2"
					( Origin gFrontEnd )
				)
				( attribute "VER" "1"
					( Origin gFrontEnd )
				)
				( attribute "WATTAGE" "1/16W"
					( Origin gFrontEnd )
				)
				( attribute "XY" "(-2125,3625)"
					( Origin gFrontEnd )
				)
				( attribute "CHIPS_PART_NAME" "RES"
					( Origin gPackager )
				)
				( attribute "CDS_PART_NAME" "RES_0402-2,1.0%,1/16W,CHIP,G21A"
					( Origin gPackager )
				)
				( objectStatus "R1F4" )
				( pin "a"
					( attribute "PN" "1"
						( Origin gPackager )
					)
					( objectStatus "R1F4.1" )
				)
				( pin "b"
					( attribute "PN" "2"
						( Origin gPackager )
					)
					( objectStatus "R1F4.2" )
				)
			)
			( gate "@baseboard_fab2_lib.baseboard_fab2(sch_1):page100_i8"
				( attribute "BOM_COST" "PROC_SOCKET"
					( Origin gFrontEnd )
				)
				( attribute "CDS_LIB" "dev_discrete"
					( Origin gPackager )
				)
				( attribute "CDS_LOCATION" "C1F19"
					( Origin gPackager )
				)
				( attribute "CDS_SEC" "1"
					( Origin gPackager )
				)
				( attribute "LOCATION" "C1F19"
					( Origin gFrontEnd )
				)
				( attribute "MATERIAL" "X7R"
					( Origin gFrontEnd )
				)
				( attribute "PACK_TYPE" "0402V"
					( Origin gFrontEnd )
				)
				( attribute "PART_NUMBER" "A36096-045"
					( Origin gFrontEnd )
				)
				( attribute "PHYS_PAGE" "100"
					( Origin gFrontEnd )
				)
				( attribute "ROOM" "PROC"
					( Origin gFrontEnd )
				)
				( attribute "ROT" "0"
					( Origin gFrontEnd )
				)
				( attribute "SEC" "1"
					( Origin gFrontEnd )
				)
				( attribute "SEC_TYPE" "0402V"
					( Origin gFrontEnd )
				)
				( attribute "TOLERANCE" "10%"
					( Origin gFrontEnd )
				)
				( attribute "VALUE" "0.01UF"
					( Origin gFrontEnd )
				)
				( attribute "VER" "1"
					( Origin gFrontEnd )
				)
				( attribute "VOLTAGE" "25V"
					( Units "uVoltage" "V" 1.000000)
					( Origin gFrontEnd )
				)
				( attribute "XY" "(-2350,3325)"
					( Origin gFrontEnd )
				)
				( attribute "CHIPS_PART_NAME" "CAP_A"
					( Origin gPackager )
				)
				( attribute "CDS_PART_NAME" "CAP_A_0402V-0.01UF,25V,10%,X7RA"
					( Origin gPackager )
				)
				( objectStatus "C1F19" )
				( pin "a"
					( attribute "PN" "1"
						( Origin gPackager )
					)
					( objectStatus "C1F19.1" )
				)
				( pin "b"
					( attribute "PN" "2"
						( Origin gPackager )
					)
					( objectStatus "C1F19.2" )
				)
			)
			( gate "@baseboard_fab2_lib.baseboard_fab2(sch_1):page100_i11"
				( attribute "BOM_COST" "SM_CONTROLLER"
					( Origin gFrontEnd )
				)
				( attribute "CDS_LIB" "mstr_discrete"
					( Origin gPackager )
				)
				( attribute "CDS_LOCATION" "R9M1"
					( Origin gPackager )
				)
				( attribute "CDS_SEC" "1"
					( Origin gPackager )
				)
				( attribute "LOCATION" "R9M1"
					( Origin gFrontEnd )
				)
				( attribute "MATERIAL" "CHIP"
					( Origin gFrontEnd )
				)
				( attribute "PACK_TYPE" "0402"
					( Origin gFrontEnd )
				)
				( attribute "PART_NUMBER" "G21796-026"
					( Origin gFrontEnd )
				)
				( attribute "PHYS_PAGE" "100"
					( Origin gFrontEnd )
				)
				( attribute "ROOM" "MEM"
					( Origin gFrontEnd )
				)
				( attribute "ROT" "2"
					( Origin gFrontEnd )
				)
				( attribute "SEC" "1"
					( Origin gFrontEnd )
				)
				( attribute "SEC_TYPE" "0402"
					( Origin gFrontEnd )
				)
				( attribute "TOLERANCE" "1%"
					( Origin gFrontEnd )
				)
				( attribute "VALUE" "1.00K"
					( Origin gFrontEnd )
				)
				( attribute "VER" "2"
					( Origin gFrontEnd )
				)
				( attribute "WATTAGE" "1/16W"
					( Origin gFrontEnd )
				)
				( attribute "XY" "(-1900,2275)"
					( Origin gFrontEnd )
				)
				( attribute "CHIPS_PART_NAME" "RES"
					( Origin gPackager )
				)
				( attribute "CDS_PART_NAME" "RES_0402-1.00K,1%,1/16W,CHIP,GA"
					( Origin gPackager )
				)
				( objectStatus "R9M1" )
				( pin "a"
					( attribute "PN" "1"
						( Origin gPackager )
					)
					( objectStatus "R9M1.1" )
				)
				( pin "b"
					( attribute "PN" "2"
						( Origin gPackager )
					)
					( objectStatus "R9M1.2" )
				)
			)
			( gate "@baseboard_fab2_lib.baseboard_fab2(sch_1):page100_i13"
				( attribute "BOM_COST" "PROC_SOCKET"
					( Origin gFrontEnd )
				)
				( attribute "CDS_LIB" "mstr_discrete"
					( Origin gPackager )
				)
				( attribute "CDS_LOCATION" "R9M2"
					( Origin gPackager )
				)
				( attribute "CDS_SEC" "1"
					( Origin gPackager )
				)
				( attribute "LOCATION" "R9M2"
					( Origin gFrontEnd )
				)
				( attribute "MATERIAL" "CHIP"
					( Origin gFrontEnd )
				)
				( attribute "PACK_TYPE" "0402"
					( Origin gFrontEnd )
				)
				( attribute "PART_NUMBER" "G21796-274"
					( Origin gFrontEnd )
				)
				( attribute "PHYS_PAGE" "100"
					( Origin gFrontEnd )
				)
				( attribute "ROOM" "PROC"
					( Origin gFrontEnd )
				)
				( attribute "ROT" "0"
					( Origin gFrontEnd )
				)
				( attribute "SEC" "1"
					( Origin gFrontEnd )
				)
				( attribute "SEC_TYPE" "0402"
					( Origin gFrontEnd )
				)
				( attribute "TOLERANCE" "1.0%"
					( Origin gFrontEnd )
				)
				( attribute "VALUE" "2"
					( Origin gFrontEnd )
				)
				( attribute "VER" "1"
					( Origin gFrontEnd )
				)
				( attribute "WATTAGE" "1/16W"
					( Origin gFrontEnd )
				)
				( attribute "XY" "(-2125,1950)"
					( Origin gFrontEnd )
				)
				( attribute "CHIPS_PART_NAME" "RES"
					( Origin gPackager )
				)
				( attribute "CDS_PART_NAME" "RES_0402-2,1.0%,1/16W,CHIP,G21A"
					( Origin gPackager )
				)
				( objectStatus "R9M2" )
				( pin "a"
					( attribute "PN" "1"
						( Origin gPackager )
					)
					( objectStatus "R9M2.1" )
				)
				( pin "b"
					( attribute "PN" "2"
						( Origin gPackager )
					)
					( objectStatus "R9M2.2" )
				)
			)
			( gate "@baseboard_fab2_lib.baseboard_fab2(sch_1):page100_i15"
				( attribute "BOM_COST" "SM_CONTROLLER"
					( Origin gFrontEnd )
				)
				( attribute "CDS_LIB" "dev_discrete"
					( Origin gPackager )
				)
				( attribute "CDS_LOCATION" "C9M2"
					( Origin gPackager )
				)
				( attribute "CDS_SEC" "1"
					( Origin gPackager )
				)
				( attribute "LOCATION" "C9M2"
					( Origin gFrontEnd )
				)
				( attribute "MATERIAL" "X7R"
					( Origin gFrontEnd )
				)
				( attribute "PACK_TYPE" "0402V"
					( Origin gFrontEnd )
				)
				( attribute "PART_NUMBER" "A36096-045"
					( Origin gFrontEnd )
				)
				( attribute "PHYS_PAGE" "100"
					( Origin gFrontEnd )
				)
				( attribute "ROOM" "MEM"
					( Origin gFrontEnd )
				)
				( attribute "ROT" "0"
					( Origin gFrontEnd )
				)
				( attribute "SEC" "1"
					( Origin gFrontEnd )
				)
				( attribute "SEC_TYPE" "0402V"
					( Origin gFrontEnd )
				)
				( attribute "TOLERANCE" "10%"
					( Origin gFrontEnd )
				)
				( attribute "VALUE" "0.01UF"
					( Origin gFrontEnd )
				)
				( attribute "VER" "1"
					( Origin gFrontEnd )
				)
				( attribute "VOLTAGE" "25V"
					( Units "uVoltage" "V" 1.000000)
					( Origin gFrontEnd )
				)
				( attribute "XY" "(-2350,1650)"
					( Origin gFrontEnd )
				)
				( attribute "CHIPS_PART_NAME" "CAP_A"
					( Origin gPackager )
				)
				( attribute "CDS_PART_NAME" "CAP_A_0402V-0.01UF,25V,10%,X7RA"
					( Origin gPackager )
				)
				( objectStatus "C9M2" )
				( pin "a"
					( attribute "PN" "1"
						( Origin gPackager )
					)
					( objectStatus "C9M2.1" )
				)
				( pin "b"
					( attribute "PN" "2"
						( Origin gPackager )
					)
					( objectStatus "C9M2.2" )
				)
			)
			( gate "@baseboard_fab2_lib.baseboard_fab2(sch_1):page100_i19"
				( attribute "BOM_COST" "SM_CONTROLLER"
					( Origin gFrontEnd )
				)
				( attribute "CDS_LIB" "mstr_discrete"
					( Origin gPackager )
				)
				( attribute "CDS_LOCATION" "R1G2"
					( Origin gPackager )
				)
				( attribute "CDS_SEC" "1"
					( Origin gPackager )
				)
				( attribute "LOCATION" "R1G2"
					( Origin gFrontEnd )
				)
				( attribute "MATERIAL" "CHIP"
					( Origin gFrontEnd )
				)
				( attribute "PACK_TYPE" "0402"
					( Origin gFrontEnd )
				)
				( attribute "PART_NUMBER" "G21796-026"
					( Origin gFrontEnd )
				)
				( attribute "PHYS_PAGE" "100"
					( Origin gFrontEnd )
				)
				( attribute "ROOM" "MEM"
					( Origin gFrontEnd )
				)
				( attribute "ROT" "2"
					( Origin gFrontEnd )
				)
				( attribute "SEC" "1"
					( Origin gFrontEnd )
				)
				( attribute "SEC_TYPE" "0402"
					( Origin gFrontEnd )
				)
				( attribute "TOLERANCE" "1%"
					( Origin gFrontEnd )
				)
				( attribute "VALUE" "1.00K"
					( Origin gFrontEnd )
				)
				( attribute "VER" "2"
					( Origin gFrontEnd )
				)
				( attribute "WATTAGE" "1/16W"
					( Origin gFrontEnd )
				)
				( attribute "XY" "(450,3950)"
					( Origin gFrontEnd )
				)
				( attribute "CHIPS_PART_NAME" "RES"
					( Origin gPackager )
				)
				( attribute "CDS_PART_NAME" "RES_0402-1.00K,1%,1/16W,CHIP,GA"
					( Origin gPackager )
				)
				( objectStatus "R1G2" )
				( pin "a"
					( attribute "PN" "1"
						( Origin gPackager )
					)
					( objectStatus "R1G2.1" )
				)
				( pin "b"
					( attribute "PN" "2"
						( Origin gPackager )
					)
					( objectStatus "R1G2.2" )
				)
			)
			( gate "@baseboard_fab2_lib.baseboard_fab2(sch_1):page100_i20"
				( attribute "BOM_COST" "SM_CONTROLLER"
					( Origin gFrontEnd )
				)
				( attribute "CDS_LIB" "mstr_discrete"
					( Origin gPackager )
				)
				( attribute "CDS_LOCATION" "R1G3"
					( Origin gPackager )
				)
				( attribute "CDS_SEC" "1"
					( Origin gPackager )
				)
				( attribute "LOCATION" "R1G3"
					( Origin gFrontEnd )
				)
				( attribute "MATERIAL" "CHIP"
					( Origin gFrontEnd )
				)
				( attribute "PACK_TYPE" "0402"
					( Origin gFrontEnd )
				)
				( attribute "PART_NUMBER" "G21796-026"
					( Origin gFrontEnd )
				)
				( attribute "PHYS_PAGE" "100"
					( Origin gFrontEnd )
				)
				( attribute "ROOM" "MEM"
					( Origin gFrontEnd )
				)
				( attribute "ROT" "2"
					( Origin gFrontEnd )
				)
				( attribute "SEC" "1"
					( Origin gFrontEnd )
				)
				( attribute "SEC_TYPE" "0402"
					( Origin gFrontEnd )
				)
				( attribute "TOLERANCE" "1%"
					( Origin gFrontEnd )
				)
				( attribute "VALUE" "1.00K"
					( Origin gFrontEnd )
				)
				( attribute "VER" "2"
					( Origin gFrontEnd )
				)
				( attribute "WATTAGE" "1/16W"
					( Origin gFrontEnd )
				)
				( attribute "XY" "(525,3300)"
					( Origin gFrontEnd )
				)
				( attribute "CHIPS_PART_NAME" "RES"
					( Origin gPackager )
				)
				( attribute "CDS_PART_NAME" "RES_0402-1.00K,1%,1/16W,CHIP,GA"
					( Origin gPackager )
				)
				( objectStatus "R1G3" )
				( pin "a"
					( attribute "PN" "1"
						( Origin gPackager )
					)
					( objectStatus "R1G3.1" )
				)
				( pin "b"
					( attribute "PN" "2"
						( Origin gPackager )
					)
					( objectStatus "R1G3.2" )
				)
			)
			( gate "@baseboard_fab2_lib.baseboard_fab2(sch_1):page100_i22"
				( attribute "BOM_COST" "SM_CONTROLLER"
					( Origin gFrontEnd )
				)
				( attribute "CDS_LIB" "mstr_discrete"
					( Origin gPackager )
				)
				( attribute "CDS_LOCATION" "R9L7"
					( Origin gPackager )
				)
				( attribute "CDS_SEC" "1"
					( Origin gPackager )
				)
				( attribute "LOCATION" "R9L7"
					( Origin gFrontEnd )
				)
				( attribute "MATERIAL" "CHIP"
					( Origin gFrontEnd )
				)
				( attribute "PACK_TYPE" "0402"
					( Origin gFrontEnd )
				)
				( attribute "PART_NUMBER" "G21796-026"
					( Origin gFrontEnd )
				)
				( attribute "PHYS_PAGE" "100"
					( Origin gFrontEnd )
				)
				( attribute "ROOM" "MEM"
					( Origin gFrontEnd )
				)
				( attribute "ROT" "2"
					( Origin gFrontEnd )
				)
				( attribute "SEC" "1"
					( Origin gFrontEnd )
				)
				( attribute "SEC_TYPE" "0402"
					( Origin gFrontEnd )
				)
				( attribute "TOLERANCE" "1%"
					( Origin gFrontEnd )
				)
				( attribute "VALUE" "1.00K"
					( Origin gFrontEnd )
				)
				( attribute "VER" "2"
					( Origin gFrontEnd )
				)
				( attribute "WATTAGE" "1/16W"
					( Origin gFrontEnd )
				)
				( attribute "XY" "(450,2275)"
					( Origin gFrontEnd )
				)
				( attribute "CHIPS_PART_NAME" "RES"
					( Origin gPackager )
				)
				( attribute "CDS_PART_NAME" "RES_0402-1.00K,1%,1/16W,CHIP,GA"
					( Origin gPackager )
				)
				( objectStatus "R9L7" )
				( pin "a"
					( attribute "PN" "1"
						( Origin gPackager )
					)
					( objectStatus "R9L7.1" )
				)
				( pin "b"
					( attribute "PN" "2"
						( Origin gPackager )
					)
					( objectStatus "R9L7.2" )
				)
			)
			( gate "@baseboard_fab2_lib.baseboard_fab2(sch_1):page100_i24"
				( attribute "BOM_COST" "PROC_SOCKET"
					( Origin gFrontEnd )
				)
				( attribute "CDS_LIB" "mstr_discrete"
					( Origin gPackager )
				)
				( attribute "CDS_LOCATION" "R9L6"
					( Origin gPackager )
				)
				( attribute "CDS_SEC" "1"
					( Origin gPackager )
				)
				( attribute "LOCATION" "R9L6"
					( Origin gFrontEnd )
				)
				( attribute "MATERIAL" "CHIP"
					( Origin gFrontEnd )
				)
				( attribute "PACK_TYPE" "0402"
					( Origin gFrontEnd )
				)
				( attribute "PART_NUMBER" "G21796-026"
					( Origin gFrontEnd )
				)
				( attribute "PHYS_PAGE" "100"
					( Origin gFrontEnd )
				)
				( attribute "ROOM" "PROC"
					( Origin gFrontEnd )
				)
				( attribute "ROT" "2"
					( Origin gFrontEnd )
				)
				( attribute "SEC" "1"
					( Origin gFrontEnd )
				)
				( attribute "SEC_TYPE" "0402"
					( Origin gFrontEnd )
				)
				( attribute "TOLERANCE" "1%"
					( Origin gFrontEnd )
				)
				( attribute "VALUE" "1.00K"
					( Origin gFrontEnd )
				)
				( attribute "VER" "2"
					( Origin gFrontEnd )
				)
				( attribute "WATTAGE" "1/16W"
					( Origin gFrontEnd )
				)
				( attribute "XY" "(525,1625)"
					( Origin gFrontEnd )
				)
				( attribute "CHIPS_PART_NAME" "RES"
					( Origin gPackager )
				)
				( attribute "CDS_PART_NAME" "RES_0402-1.00K,1%,1/16W,CHIP,GA"
					( Origin gPackager )
				)
				( objectStatus "R9L6" )
				( pin "a"
					( attribute "PN" "1"
						( Origin gPackager )
					)
					( objectStatus "R9L6.1" )
				)
				( pin "b"
					( attribute "PN" "2"
						( Origin gPackager )
					)
					( objectStatus "R9L6.2" )
				)
			)
			( gate "@baseboard_fab2_lib.baseboard_fab2(sch_1):page100_i25"
				( attribute "BOM_COST" "PROC_SOCKET"
					( Origin gFrontEnd )
				)
				( attribute "CDS_LIB" "mstr_discrete"
					( Origin gPackager )
				)
				( attribute "CDS_LOCATION" "R1G1"
					( Origin gPackager )
				)
				( attribute "CDS_SEC" "1"
					( Origin gPackager )
				)
				( attribute "LOCATION" "R1G1"
					( Origin gFrontEnd )
				)
				( attribute "MATERIAL" "CHIP"
					( Origin gFrontEnd )
				)
				( attribute "PACK_TYPE" "0402"
					( Origin gFrontEnd )
				)
				( attribute "PART_NUMBER" "G21796-274"
					( Origin gFrontEnd )
				)
				( attribute "PHYS_PAGE" "100"
					( Origin gFrontEnd )
				)
				( attribute "ROOM" "PROC"
					( Origin gFrontEnd )
				)
				( attribute "ROT" "0"
					( Origin gFrontEnd )
				)
				( attribute "SEC" "1"
					( Origin gFrontEnd )
				)
				( attribute "SEC_TYPE" "0402"
					( Origin gFrontEnd )
				)
				( attribute "TOLERANCE" "1.0%"
					( Origin gFrontEnd )
				)
				( attribute "VALUE" "2"
					( Origin gFrontEnd )
				)
				( attribute "VER" "1"
					( Origin gFrontEnd )
				)
				( attribute "WATTAGE" "1/16W"
					( Origin gFrontEnd )
				)
				( attribute "XY" "(225,3625)"
					( Origin gFrontEnd )
				)
				( attribute "CHIPS_PART_NAME" "RES"
					( Origin gPackager )
				)
				( attribute "CDS_PART_NAME" "RES_0402-2,1.0%,1/16W,CHIP,G21A"
					( Origin gPackager )
				)
				( objectStatus "R1G1" )
				( pin "a"
					( attribute "PN" "1"
						( Origin gPackager )
					)
					( objectStatus "R1G1.1" )
				)
				( pin "b"
					( attribute "PN" "2"
						( Origin gPackager )
					)
					( objectStatus "R1G1.2" )
				)
			)
			( gate "@baseboard_fab2_lib.baseboard_fab2(sch_1):page100_i26"
				( attribute "BOM_COST" "PROC_SOCKET"
					( Origin gFrontEnd )
				)
				( attribute "CDS_LIB" "dev_discrete"
					( Origin gPackager )
				)
				( attribute "CDS_LOCATION" "C1G8"
					( Origin gPackager )
				)
				( attribute "CDS_SEC" "1"
					( Origin gPackager )
				)
				( attribute "LOCATION" "C1G8"
					( Origin gFrontEnd )
				)
				( attribute "MATERIAL" "X7R"
					( Origin gFrontEnd )
				)
				( attribute "PACK_TYPE" "0402V"
					( Origin gFrontEnd )
				)
				( attribute "PART_NUMBER" "A36096-045"
					( Origin gFrontEnd )
				)
				( attribute "PHYS_PAGE" "100"
					( Origin gFrontEnd )
				)
				( attribute "ROOM" "PROC"
					( Origin gFrontEnd )
				)
				( attribute "ROT" "0"
					( Origin gFrontEnd )
				)
				( attribute "SEC" "1"
					( Origin gFrontEnd )
				)
				( attribute "SEC_TYPE" "0402V"
					( Origin gFrontEnd )
				)
				( attribute "TOLERANCE" "10%"
					( Origin gFrontEnd )
				)
				( attribute "VALUE" "0.01UF"
					( Origin gFrontEnd )
				)
				( attribute "VER" "1"
					( Origin gFrontEnd )
				)
				( attribute "VOLTAGE" "25V"
					( Units "uVoltage" "V" 1.000000)
					( Origin gFrontEnd )
				)
				( attribute "XY" "(0,3325)"
					( Origin gFrontEnd )
				)
				( attribute "CHIPS_PART_NAME" "CAP_A"
					( Origin gPackager )
				)
				( attribute "CDS_PART_NAME" "CAP_A_0402V-0.01UF,25V,10%,X7RA"
					( Origin gPackager )
				)
				( objectStatus "C1G8" )
				( pin "a"
					( attribute "PN" "1"
						( Origin gPackager )
					)
					( objectStatus "C1G8.1" )
				)
				( pin "b"
					( attribute "PN" "2"
						( Origin gPackager )
					)
					( objectStatus "C1G8.2" )
				)
			)
			( gate "@baseboard_fab2_lib.baseboard_fab2(sch_1):page100_i29"
				( attribute "BOM_COST" "PROC_SOCKET"
					( Origin gFrontEnd )
				)
				( attribute "CDS_LIB" "mstr_discrete"
					( Origin gPackager )
				)
				( attribute "CDS_LOCATION" "R9L8"
					( Origin gPackager )
				)
				( attribute "CDS_SEC" "1"
					( Origin gPackager )
				)
				( attribute "LOCATION" "R9L8"
					( Origin gFrontEnd )
				)
				( attribute "MATERIAL" "CHIP"
					( Origin gFrontEnd )
				)
				( attribute "PACK_TYPE" "0402"
					( Origin gFrontEnd )
				)
				( attribute "PART_NUMBER" "G21796-274"
					( Origin gFrontEnd )
				)
				( attribute "PHYS_PAGE" "100"
					( Origin gFrontEnd )
				)
				( attribute "ROOM" "PROC"
					( Origin gFrontEnd )
				)
				( attribute "ROT" "0"
					( Origin gFrontEnd )
				)
				( attribute "SEC" "1"
					( Origin gFrontEnd )
				)
				( attribute "SEC_TYPE" "0402"
					( Origin gFrontEnd )
				)
				( attribute "TOLERANCE" "1.0%"
					( Origin gFrontEnd )
				)
				( attribute "VALUE" "2"
					( Origin gFrontEnd )
				)
				( attribute "VER" "1"
					( Origin gFrontEnd )
				)
				( attribute "WATTAGE" "1/16W"
					( Origin gFrontEnd )
				)
				( attribute "XY" "(225,1950)"
					( Origin gFrontEnd )
				)
				( attribute "CHIPS_PART_NAME" "RES"
					( Origin gPackager )
				)
				( attribute "CDS_PART_NAME" "RES_0402-2,1.0%,1/16W,CHIP,G21A"
					( Origin gPackager )
				)
				( objectStatus "R9L8" )
				( pin "a"
					( attribute "PN" "1"
						( Origin gPackager )
					)
					( objectStatus "R9L8.1" )
				)
				( pin "b"
					( attribute "PN" "2"
						( Origin gPackager )
					)
					( objectStatus "R9L8.2" )
				)
			)
			( gate "@baseboard_fab2_lib.baseboard_fab2(sch_1):page100_i30"
				( attribute "BOM_COST" "SM_CONTROLLER"
					( Origin gFrontEnd )
				)
				( attribute "CDS_LIB" "dev_discrete"
					( Origin gPackager )
				)
				( attribute "CDS_LOCATION" "C9L8"
					( Origin gPackager )
				)
				( attribute "CDS_SEC" "1"
					( Origin gPackager )
				)
				( attribute "LOCATION" "C9L8"
					( Origin gFrontEnd )
				)
				( attribute "MATERIAL" "X7R"
					( Origin gFrontEnd )
				)
				( attribute "PACK_TYPE" "0402V"
					( Origin gFrontEnd )
				)
				( attribute "PART_NUMBER" "A36096-045"
					( Origin gFrontEnd )
				)
				( attribute "PHYS_PAGE" "100"
					( Origin gFrontEnd )
				)
				( attribute "ROOM" "MEM"
					( Origin gFrontEnd )
				)
				( attribute "ROT" "0"
					( Origin gFrontEnd )
				)
				( attribute "SEC" "1"
					( Origin gFrontEnd )
				)
				( attribute "SEC_TYPE" "0402V"
					( Origin gFrontEnd )
				)
				( attribute "TOLERANCE" "10%"
					( Origin gFrontEnd )
				)
				( attribute "VALUE" "0.01UF"
					( Origin gFrontEnd )
				)
				( attribute "VER" "1"
					( Origin gFrontEnd )
				)
				( attribute "VOLTAGE" "25V"
					( Units "uVoltage" "V" 1.000000)
					( Origin gFrontEnd )
				)
				( attribute "XY" "(0,1650)"
					( Origin gFrontEnd )
				)
				( attribute "CHIPS_PART_NAME" "CAP_A"
					( Origin gPackager )
				)
				( attribute "CDS_PART_NAME" "CAP_A_0402V-0.01UF,25V,10%,X7RA"
					( Origin gPackager )
				)
				( objectStatus "C9L8" )
				( pin "a"
					( attribute "PN" "1"
						( Origin gPackager )
					)
					( objectStatus "C9L8.1" )
				)
				( pin "b"
					( attribute "PN" "2"
						( Origin gPackager )
					)
					( objectStatus "C9L8.2" )
				)
			)
			( gate "@baseboard_fab2_lib.baseboard_fab2(sch_1):page100_i35"
				( attribute "BOM_COST" "SM_CONTROLLER"
					( Origin gFrontEnd )
				)
				( attribute "CDS_LIB" "mstr_discrete"
					( Origin gPackager )
				)
				( attribute "CDS_LOCATION" "R1G15"
					( Origin gPackager )
				)
				( attribute "CDS_SEC" "1"
					( Origin gPackager )
				)
				( attribute "LOCATION" "R1G15"
					( Origin gFrontEnd )
				)
				( attribute "MATERIAL" "CHIP"
					( Origin gFrontEnd )
				)
				( attribute "PACK_TYPE" "0402"
					( Origin gFrontEnd )
				)
				( attribute "PART_NUMBER" "G21796-026"
					( Origin gFrontEnd )
				)
				( attribute "PHYS_PAGE" "100"
					( Origin gFrontEnd )
				)
				( attribute "ROOM" "MEM"
					( Origin gFrontEnd )
				)
				( attribute "ROT" "2"
					( Origin gFrontEnd )
				)
				( attribute "SEC" "1"
					( Origin gFrontEnd )
				)
				( attribute "SEC_TYPE" "0402"
					( Origin gFrontEnd )
				)
				( attribute "TOLERANCE" "1%"
					( Origin gFrontEnd )
				)
				( attribute "VALUE" "1.00K"
					( Origin gFrontEnd )
				)
				( attribute "VER" "2"
					( Origin gFrontEnd )
				)
				( attribute "WATTAGE" "1/16W"
					( Origin gFrontEnd )
				)
				( attribute "XY" "(2900,3950)"
					( Origin gFrontEnd )
				)
				( attribute "CHIPS_PART_NAME" "RES"
					( Origin gPackager )
				)
				( attribute "CDS_PART_NAME" "RES_0402-1.00K,1%,1/16W,CHIP,GA"
					( Origin gPackager )
				)
				( objectStatus "R1G15" )
				( pin "a"
					( attribute "PN" "1"
						( Origin gPackager )
					)
					( objectStatus "R1G15.1" )
				)
				( pin "b"
					( attribute "PN" "2"
						( Origin gPackager )
					)
					( objectStatus "R1G15.2" )
				)
			)
			( gate "@baseboard_fab2_lib.baseboard_fab2(sch_1):page100_i36"
				( attribute "BOM_COST" "SM_CONTROLLER"
					( Origin gFrontEnd )
				)
				( attribute "CDS_LIB" "mstr_discrete"
					( Origin gPackager )
				)
				( attribute "CDS_LOCATION" "R1G17"
					( Origin gPackager )
				)
				( attribute "CDS_SEC" "1"
					( Origin gPackager )
				)
				( attribute "LOCATION" "R1G17"
					( Origin gFrontEnd )
				)
				( attribute "MATERIAL" "CHIP"
					( Origin gFrontEnd )
				)
				( attribute "PACK_TYPE" "0402"
					( Origin gFrontEnd )
				)
				( attribute "PART_NUMBER" "G21796-026"
					( Origin gFrontEnd )
				)
				( attribute "PHYS_PAGE" "100"
					( Origin gFrontEnd )
				)
				( attribute "ROOM" "MEM"
					( Origin gFrontEnd )
				)
				( attribute "ROT" "2"
					( Origin gFrontEnd )
				)
				( attribute "SEC" "1"
					( Origin gFrontEnd )
				)
				( attribute "SEC_TYPE" "0402"
					( Origin gFrontEnd )
				)
				( attribute "TOLERANCE" "1%"
					( Origin gFrontEnd )
				)
				( attribute "VALUE" "1.00K"
					( Origin gFrontEnd )
				)
				( attribute "VER" "2"
					( Origin gFrontEnd )
				)
				( attribute "WATTAGE" "1/16W"
					( Origin gFrontEnd )
				)
				( attribute "XY" "(2975,3300)"
					( Origin gFrontEnd )
				)
				( attribute "CHIPS_PART_NAME" "RES"
					( Origin gPackager )
				)
				( attribute "CDS_PART_NAME" "RES_0402-1.00K,1%,1/16W,CHIP,GA"
					( Origin gPackager )
				)
				( objectStatus "R1G17" )
				( pin "a"
					( attribute "PN" "1"
						( Origin gPackager )
					)
					( objectStatus "R1G17.1" )
				)
				( pin "b"
					( attribute "PN" "2"
						( Origin gPackager )
					)
					( objectStatus "R1G17.2" )
				)
			)
			( gate "@baseboard_fab2_lib.baseboard_fab2(sch_1):page100_i38"
				( attribute "BOM_COST" "SM_CONTROLLER"
					( Origin gFrontEnd )
				)
				( attribute "CDS_LIB" "mstr_discrete"
					( Origin gPackager )
				)
				( attribute "CDS_LOCATION" "R9L2"
					( Origin gPackager )
				)
				( attribute "CDS_SEC" "1"
					( Origin gPackager )
				)
				( attribute "LOCATION" "R9L2"
					( Origin gFrontEnd )
				)
				( attribute "MATERIAL" "CHIP"
					( Origin gFrontEnd )
				)
				( attribute "PACK_TYPE" "0402"
					( Origin gFrontEnd )
				)
				( attribute "PART_NUMBER" "G21796-026"
					( Origin gFrontEnd )
				)
				( attribute "PHYS_PAGE" "100"
					( Origin gFrontEnd )
				)
				( attribute "ROOM" "MEM"
					( Origin gFrontEnd )
				)
				( attribute "ROT" "2"
					( Origin gFrontEnd )
				)
				( attribute "SEC" "1"
					( Origin gFrontEnd )
				)
				( attribute "SEC_TYPE" "0402"
					( Origin gFrontEnd )
				)
				( attribute "TOLERANCE" "1%"
					( Origin gFrontEnd )
				)
				( attribute "VALUE" "1.00K"
					( Origin gFrontEnd )
				)
				( attribute "VER" "2"
					( Origin gFrontEnd )
				)
				( attribute "WATTAGE" "1/16W"
					( Origin gFrontEnd )
				)
				( attribute "XY" "(2900,2275)"
					( Origin gFrontEnd )
				)
				( attribute "CHIPS_PART_NAME" "RES"
					( Origin gPackager )
				)
				( attribute "CDS_PART_NAME" "RES_0402-1.00K,1%,1/16W,CHIP,GA"
					( Origin gPackager )
				)
				( objectStatus "R9L2" )
				( pin "a"
					( attribute "PN" "1"
						( Origin gPackager )
					)
					( objectStatus "R9L2.1" )
				)
				( pin "b"
					( attribute "PN" "2"
						( Origin gPackager )
					)
					( objectStatus "R9L2.2" )
				)
			)
			( gate "@baseboard_fab2_lib.baseboard_fab2(sch_1):page100_i40"
				( attribute "BOM_COST" "PROC_SOCKET"
					( Origin gFrontEnd )
				)
				( attribute "CDS_LIB" "mstr_discrete"
					( Origin gPackager )
				)
				( attribute "CDS_LOCATION" "R9L1"
					( Origin gPackager )
				)
				( attribute "CDS_SEC" "1"
					( Origin gPackager )
				)
				( attribute "LOCATION" "R9L1"
					( Origin gFrontEnd )
				)
				( attribute "MATERIAL" "CHIP"
					( Origin gFrontEnd )
				)
				( attribute "PACK_TYPE" "0402"
					( Origin gFrontEnd )
				)
				( attribute "PART_NUMBER" "G21796-026"
					( Origin gFrontEnd )
				)
				( attribute "PHYS_PAGE" "100"
					( Origin gFrontEnd )
				)
				( attribute "ROOM" "PROC"
					( Origin gFrontEnd )
				)
				( attribute "ROT" "2"
					( Origin gFrontEnd )
				)
				( attribute "SEC" "1"
					( Origin gFrontEnd )
				)
				( attribute "SEC_TYPE" "0402"
					( Origin gFrontEnd )
				)
				( attribute "TOLERANCE" "1%"
					( Origin gFrontEnd )
				)
				( attribute "VALUE" "1.00K"
					( Origin gFrontEnd )
				)
				( attribute "VER" "2"
					( Origin gFrontEnd )
				)
				( attribute "WATTAGE" "1/16W"
					( Origin gFrontEnd )
				)
				( attribute "XY" "(2975,1625)"
					( Origin gFrontEnd )
				)
				( attribute "CHIPS_PART_NAME" "RES"
					( Origin gPackager )
				)
				( attribute "CDS_PART_NAME" "RES_0402-1.00K,1%,1/16W,CHIP,GA"
					( Origin gPackager )
				)
				( objectStatus "R9L1" )
				( pin "a"
					( attribute "PN" "1"
						( Origin gPackager )
					)
					( objectStatus "R9L1.1" )
				)
				( pin "b"
					( attribute "PN" "2"
						( Origin gPackager )
					)
					( objectStatus "R9L1.2" )
				)
			)
			( gate "@baseboard_fab2_lib.baseboard_fab2(sch_1):page100_i41"
				( attribute "BOM_COST" "PROC_SOCKET"
					( Origin gFrontEnd )
				)
				( attribute "CDS_LIB" "mstr_discrete"
					( Origin gPackager )
				)
				( attribute "CDS_LOCATION" "R1G14"
					( Origin gPackager )
				)
				( attribute "CDS_SEC" "1"
					( Origin gPackager )
				)
				( attribute "LOCATION" "R1G14"
					( Origin gFrontEnd )
				)
				( attribute "MATERIAL" "CHIP"
					( Origin gFrontEnd )
				)
				( attribute "PACK_TYPE" "0402"
					( Origin gFrontEnd )
				)
				( attribute "PART_NUMBER" "G21796-274"
					( Origin gFrontEnd )
				)
				( attribute "PHYS_PAGE" "100"
					( Origin gFrontEnd )
				)
				( attribute "ROOM" "PROC"
					( Origin gFrontEnd )
				)
				( attribute "ROT" "0"
					( Origin gFrontEnd )
				)
				( attribute "SEC" "1"
					( Origin gFrontEnd )
				)
				( attribute "SEC_TYPE" "0402"
					( Origin gFrontEnd )
				)
				( attribute "TOLERANCE" "1.0%"
					( Origin gFrontEnd )
				)
				( attribute "VALUE" "2"
					( Origin gFrontEnd )
				)
				( attribute "VER" "1"
					( Origin gFrontEnd )
				)
				( attribute "WATTAGE" "1/16W"
					( Origin gFrontEnd )
				)
				( attribute "XY" "(2675,3625)"
					( Origin gFrontEnd )
				)
				( attribute "CHIPS_PART_NAME" "RES"
					( Origin gPackager )
				)
				( attribute "CDS_PART_NAME" "RES_0402-2,1.0%,1/16W,CHIP,G21A"
					( Origin gPackager )
				)
				( objectStatus "R1G14" )
				( pin "a"
					( attribute "PN" "1"
						( Origin gPackager )
					)
					( objectStatus "R1G14.1" )
				)
				( pin "b"
					( attribute "PN" "2"
						( Origin gPackager )
					)
					( objectStatus "R1G14.2" )
				)
			)
			( gate "@baseboard_fab2_lib.baseboard_fab2(sch_1):page100_i42"
				( attribute "BOM_COST" "PROC_SOCKET"
					( Origin gFrontEnd )
				)
				( attribute "CDS_LIB" "dev_discrete"
					( Origin gPackager )
				)
				( attribute "CDS_LOCATION" "C1G18"
					( Origin gPackager )
				)
				( attribute "CDS_SEC" "1"
					( Origin gPackager )
				)
				( attribute "LOCATION" "C1G18"
					( Origin gFrontEnd )
				)
				( attribute "MATERIAL" "X7R"
					( Origin gFrontEnd )
				)
				( attribute "PACK_TYPE" "0402V"
					( Origin gFrontEnd )
				)
				( attribute "PART_NUMBER" "A36096-045"
					( Origin gFrontEnd )
				)
				( attribute "PHYS_PAGE" "100"
					( Origin gFrontEnd )
				)
				( attribute "ROOM" "PROC"
					( Origin gFrontEnd )
				)
				( attribute "ROT" "0"
					( Origin gFrontEnd )
				)
				( attribute "SEC" "1"
					( Origin gFrontEnd )
				)
				( attribute "SEC_TYPE" "0402V"
					( Origin gFrontEnd )
				)
				( attribute "TOLERANCE" "10%"
					( Origin gFrontEnd )
				)
				( attribute "VALUE" "0.01UF"
					( Origin gFrontEnd )
				)
				( attribute "VER" "1"
					( Origin gFrontEnd )
				)
				( attribute "VOLTAGE" "25V"
					( Units "uVoltage" "V" 1.000000)
					( Origin gFrontEnd )
				)
				( attribute "XY" "(2450,3325)"
					( Origin gFrontEnd )
				)
				( attribute "CHIPS_PART_NAME" "CAP_A"
					( Origin gPackager )
				)
				( attribute "CDS_PART_NAME" "CAP_A_0402V-0.01UF,25V,10%,X7RA"
					( Origin gPackager )
				)
				( objectStatus "C1G18" )
				( pin "a"
					( attribute "PN" "1"
						( Origin gPackager )
					)
					( objectStatus "C1G18.1" )
				)
				( pin "b"
					( attribute "PN" "2"
						( Origin gPackager )
					)
					( objectStatus "C1G18.2" )
				)
			)
			( gate "@baseboard_fab2_lib.baseboard_fab2(sch_1):page100_i45"
				( attribute "BOM_COST" "PROC_SOCKET"
					( Origin gFrontEnd )
				)
				( attribute "CDS_LIB" "mstr_discrete"
					( Origin gPackager )
				)
				( attribute "CDS_LOCATION" "R9L3"
					( Origin gPackager )
				)
				( attribute "CDS_SEC" "1"
					( Origin gPackager )
				)
				( attribute "LOCATION" "R9L3"
					( Origin gFrontEnd )
				)
				( attribute "MATERIAL" "CHIP"
					( Origin gFrontEnd )
				)
				( attribute "PACK_TYPE" "0402"
					( Origin gFrontEnd )
				)
				( attribute "PART_NUMBER" "G21796-274"
					( Origin gFrontEnd )
				)
				( attribute "PHYS_PAGE" "100"
					( Origin gFrontEnd )
				)
				( attribute "ROOM" "PROC"
					( Origin gFrontEnd )
				)
				( attribute "ROT" "0"
					( Origin gFrontEnd )
				)
				( attribute "SEC" "1"
					( Origin gFrontEnd )
				)
				( attribute "SEC_TYPE" "0402"
					( Origin gFrontEnd )
				)
				( attribute "TOLERANCE" "1.0%"
					( Origin gFrontEnd )
				)
				( attribute "VALUE" "2"
					( Origin gFrontEnd )
				)
				( attribute "VER" "1"
					( Origin gFrontEnd )
				)
				( attribute "WATTAGE" "1/16W"
					( Origin gFrontEnd )
				)
				( attribute "XY" "(2675,1950)"
					( Origin gFrontEnd )
				)
				( attribute "CHIPS_PART_NAME" "RES"
					( Origin gPackager )
				)
				( attribute "CDS_PART_NAME" "RES_0402-2,1.0%,1/16W,CHIP,G21A"
					( Origin gPackager )
				)
				( objectStatus "R9L3" )
				( pin "a"
					( attribute "PN" "1"
						( Origin gPackager )
					)
					( objectStatus "R9L3.1" )
				)
				( pin "b"
					( attribute "PN" "2"
						( Origin gPackager )
					)
					( objectStatus "R9L3.2" )
				)
			)
			( gate "@baseboard_fab2_lib.baseboard_fab2(sch_1):page100_i46"
				( attribute "BOM_COST" "SM_CONTROLLER"
					( Origin gFrontEnd )
				)
				( attribute "CDS_LIB" "dev_discrete"
					( Origin gPackager )
				)
				( attribute "CDS_LOCATION" "C9L3"
					( Origin gPackager )
				)
				( attribute "CDS_SEC" "1"
					( Origin gPackager )
				)
				( attribute "LOCATION" "C9L3"
					( Origin gFrontEnd )
				)
				( attribute "MATERIAL" "X7R"
					( Origin gFrontEnd )
				)
				( attribute "PACK_TYPE" "0402V"
					( Origin gFrontEnd )
				)
				( attribute "PART_NUMBER" "A36096-045"
					( Origin gFrontEnd )
				)
				( attribute "PHYS_PAGE" "100"
					( Origin gFrontEnd )
				)
				( attribute "ROOM" "MEM"
					( Origin gFrontEnd )
				)
				( attribute "ROT" "0"
					( Origin gFrontEnd )
				)
				( attribute "SEC" "1"
					( Origin gFrontEnd )
				)
				( attribute "SEC_TYPE" "0402V"
					( Origin gFrontEnd )
				)
				( attribute "TOLERANCE" "10%"
					( Origin gFrontEnd )
				)
				( attribute "VALUE" "0.01UF"
					( Origin gFrontEnd )
				)
				( attribute "VER" "1"
					( Origin gFrontEnd )
				)
				( attribute "VOLTAGE" "25V"
					( Units "uVoltage" "V" 1.000000)
					( Origin gFrontEnd )
				)
				( attribute "XY" "(2450,1650)"
					( Origin gFrontEnd )
				)
				( attribute "CHIPS_PART_NAME" "CAP_A"
					( Origin gPackager )
				)
				( attribute "CDS_PART_NAME" "CAP_A_0402V-0.01UF,25V,10%,X7RA"
					( Origin gPackager )
				)
				( objectStatus "C9L3" )
				( pin "a"
					( attribute "PN" "1"
						( Origin gPackager )
					)
					( objectStatus "C9L3.1" )
				)
				( pin "b"
					( attribute "PN" "2"
						( Origin gPackager )
					)
					( objectStatus "C9L3.2" )
				)
			)
			( gate "@baseboard_fab2_lib.baseboard_fab2(sch_1):page101_i20"
				( attribute "BOM_COST" "SM_CONTROLLER"
					( Origin gFrontEnd )
				)
				( attribute "CDS_LIB" "mstr_discrete"
					( Origin gPackager )
				)
				( attribute "CDS_LOCATION" "R8F29"
					( Origin gPackager )
				)
				( attribute "CDS_SEC" "1"
					( Origin gPackager )
				)
				( attribute "LOCATION" "R8F29"
					( Origin gFrontEnd )
				)
				( attribute "MATERIAL" "CHIP"
					( Origin gFrontEnd )
				)
				( attribute "PACK_TYPE" "0402"
					( Origin gFrontEnd )
				)
				( attribute "PART_NUMBER" "G21796-074"
					( Origin gFrontEnd )
				)
				( attribute "PHYS_PAGE" "101"
					( Origin gFrontEnd )
				)
				( attribute "ROOM" "SYS_CLOCK"
					( Origin gFrontEnd )
				)
				( attribute "ROT" "0"
					( Origin gFrontEnd )
				)
				( attribute "SEC" "1"
					( Origin gFrontEnd )
				)
				( attribute "SEC_TYPE" "0402"
					( Origin gFrontEnd )
				)
				( attribute "TOLERANCE" "1%"
					( Origin gFrontEnd )
				)
				( attribute "VALUE" "33.2"
					( Origin gFrontEnd )
				)
				( attribute "VER" "1"
					( Origin gFrontEnd )
				)
				( attribute "WATTAGE" "1/16W"
					( Origin gFrontEnd )
				)
				( attribute "XY" "(-3425,2425)"
					( Origin gFrontEnd )
				)
				( attribute "CHIPS_PART_NAME" "RES"
					( Origin gPackager )
				)
				( attribute "CDS_PART_NAME" "RES_0402-33.2,1%,1/16W,CHIP,G2A"
					( Origin gPackager )
				)
				( objectStatus "R8F29" )
				( pin "a"
					( attribute "PN" "1"
						( Origin gPackager )
					)
					( objectStatus "R8F29.1" )
				)
				( pin "b"
					( attribute "PN" "2"
						( Origin gPackager )
					)
					( objectStatus "R8F29.2" )
				)
			)
			( gate "@baseboard_fab2_lib.baseboard_fab2(sch_1):page101_i28"
				( attribute "BOM_COST" "SM_CONTROLLER"
					( Origin gFrontEnd )
				)
				( attribute "CDS_LIB" "mstr_discrete"
					( Origin gPackager )
				)
				( attribute "CDS_LOCATION" "R8F25"
					( Origin gPackager )
				)
				( attribute "CDS_SEC" "1"
					( Origin gPackager )
				)
				( attribute "LOCATION" "R8F25"
					( Origin gFrontEnd )
				)
				( attribute "MATERIAL" "CHIP"
					( Origin gFrontEnd )
				)
				( attribute "PACK_TYPE" "0402"
					( Origin gFrontEnd )
				)
				( attribute "PART_NUMBER" "G21796-077"
					( Origin gFrontEnd )
				)
				( attribute "PHYS_PAGE" "101"
					( Origin gFrontEnd )
				)
				( attribute "ROOM" "SYS_CLOCK"
					( Origin gFrontEnd )
				)
				( attribute "ROT" "2"
					( Origin gFrontEnd )
				)
				( attribute "SEC" "1"
					( Origin gPackager )
				)
				( attribute "TOLERANCE" "1%"
					( Origin gFrontEnd )
				)
				( attribute "VALUE" "475.0"
					( Origin gFrontEnd )
				)
				( attribute "VER" "2"
					( Origin gFrontEnd )
				)
				( attribute "WATTAGE" "1/16W"
					( Origin gFrontEnd )
				)
				( attribute "XY" "(-4750,2975)"
					( Origin gFrontEnd )
				)
				( attribute "CHIPS_PART_NAME" "RES"
					( Origin gPackager )
				)
				( attribute "CDS_PART_NAME" "RES_0402-475.0,1%,1/16W,CHIP,GA"
					( Origin gPackager )
				)
				( objectStatus "R8F25" )
				( pin "a"
					( attribute "PN" "1"
						( Origin gPackager )
					)
					( objectStatus "R8F25.1" )
				)
				( pin "b"
					( attribute "PN" "2"
						( Origin gPackager )
					)
					( objectStatus "R8F25.2" )
				)
			)
			( gate "@baseboard_fab2_lib.baseboard_fab2(sch_1):page101_i34"
				( attribute "BOM_COST" "SM_CONTROLLER"
					( Origin gFrontEnd )
				)
				( attribute "CDS_LIB" "mstr_clock"
					( Origin gPackager )
				)
				( attribute "CDS_LMAN_SYM_OUTLINE" "-600,900,600,-900"
					( Origin gPackager )
				)
				( attribute "CDS_LOCATION" "EU8F2"
					( Origin gPackager )
				)
				( attribute "CDS_SEC" "1"
					( Origin gPackager )
				)
				( attribute "LOCATION" "EU8F2"
					( Origin gFrontEnd )
				)
				( attribute "MATERIAL" "IC"
					( Origin gFrontEnd )
				)
				( attribute "PACK_TYPE" "MLFP"
					( Origin gFrontEnd )
				)
				( attribute "PART_NUMBER" "E95226-001"
					( Origin gFrontEnd )
				)
				( attribute "PHYS_PAGE" "101"
					( Origin gFrontEnd )
				)
				( attribute "ROOM" "SYS_CLOCK"
					( Origin gFrontEnd )
				)
				( attribute "ROT" "0"
					( Origin gFrontEnd )
				)
				( attribute "SEC" "1"
					( Origin gFrontEnd )
				)
				( attribute "SEC_TYPE" "MLFP"
					( Origin gFrontEnd )
				)
				( attribute "VER" "1"
					( Origin gFrontEnd )
				)
				( attribute "XY" "(-5875,1825)"
					( Origin gFrontEnd )
				)
				( attribute "CHIPS_PART_NAME" "ICS9FGP204"
					( Origin gPackager )
				)
				( attribute "CDS_PART_NAME" "ICS9FGP204_MLFP-IC,E95226-001"
					( Origin gPackager )
				)
				( objectStatus "EU8F2" )
				( pin "\25mhz_0\"
					( attribute "PN" "16"
						( Origin gPackager )
					)
					( objectStatus "EU8F2.16" )
				)
				( pin "\25mhz_1\"
					( attribute "PN" "17"
						( Origin gPackager )
					)
					( objectStatus "EU8F2.17" )
				)
				( pin "\32khz\"
					( attribute "PN" "13"
						( Origin gPackager )
					)
					( objectStatus "EU8F2.13" )
				)
				( pin "\33mhz_smbadr\"
					( attribute "PN" "22"
						( Origin gPackager )
					)
					( objectStatus "EU8F2.22" )
				)
				( pin "cpuclkc0"
					( attribute "PN" "8"
						( Origin gPackager )
					)
					( objectStatus "EU8F2.8" )
				)
				( pin "cpuclkt0"
					( attribute "PN" "7"
						( Origin gPackager )
					)
					( objectStatus "EU8F2.7" )
				)
				( pin "dot96ssc"
					( attribute "PN" "4"
						( Origin gPackager )
					)
					( objectStatus "EU8F2.4" )
				)
				( pin "dot96sst"
					( attribute "PN" "3"
						( Origin gPackager )
					)
					( objectStatus "EU8F2.3" )
				)
				( pin "gnd(0)"
					( attribute "PN" "1"
						( Origin gPackager )
					)
					( objectStatus "EU8F2.1" )
				)
				( pin "gnd(1)"
					( attribute "PN" "41"
						( Origin gPackager )
					)
					( objectStatus "EU8F2.41" )
				)
				( pin "gnd32k"
					( attribute "PN" "14"
						( Origin gPackager )
					)
					( objectStatus "EU8F2.14" )
				)
				( pin "gnd33"
					( attribute "PN" "21"
						( Origin gPackager )
					)
					( objectStatus "EU8F2.21" )
				)
				( pin "gnd_rgmii"
					( attribute "PN" "35"
						( Origin gPackager )
					)
					( objectStatus "EU8F2.35" )
				)
				( pin "gndcpu"
					( attribute "PN" "10"
						( Origin gPackager )
					)
					( objectStatus "EU8F2.10" )
				)
				( pin "gndref"
					( attribute "PN" "18"
						( Origin gPackager )
					)
					( objectStatus "EU8F2.18" )
				)
				( pin "gndrmii(0)"
					( attribute "PN" "27"
						( Origin gPackager )
					)
					( objectStatus "EU8F2.27" )
				)
				( pin "gndrmii(1)"
					( attribute "PN" "30"
						( Origin gPackager )
					)
					( objectStatus "EU8F2.30" )
				)
				( pin "iref"
					( attribute "PN" "11"
						( Origin gPackager )
					)
					( objectStatus "EU8F2.11" )
				)
				( pin "oe_96"
					( attribute "PN" "5"
						( Origin gPackager )
					)
					( objectStatus "EU8F2.5" )
				)
				( pin "oe_cpu"
					( attribute "PN" "6"
						( Origin gPackager )
					)
					( objectStatus "EU8F2.6" )
				)
				( pin "rgmii(0)"
					( attribute "PN" "37"
						( Origin gPackager )
					)
					( objectStatus "EU8F2.37" )
				)
				( pin "rgmii(1)"
					( attribute "PN" "36"
						( Origin gPackager )
					)
					( objectStatus "EU8F2.36" )
				)
				( pin "rmii(0)"
					( attribute "PN" "33"
						( Origin gPackager )
					)
					( objectStatus "EU8F2.33" )
				)
				( pin "rmii(1)"
					( attribute "PN" "32"
						( Origin gPackager )
					)
					( objectStatus "EU8F2.32" )
				)
				( pin "rmii(2)"
					( attribute "PN" "29"
						( Origin gPackager )
					)
					( objectStatus "EU8F2.29" )
				)
				( pin "rmii(3)"
					( attribute "PN" "28"
						( Origin gPackager )
					)
					( objectStatus "EU8F2.28" )
				)
				( pin "rmii(4)"
					( attribute "PN" "25"
						( Origin gPackager )
					)
					( objectStatus "EU8F2.25" )
				)
				( pin "rmii(5)"
					( attribute "PN" "24"
						( Origin gPackager )
					)
					( objectStatus "EU8F2.24" )
				)
				( pin "smbclk"
					( attribute "PN" "38"
						( Origin gPackager )
					)
					( objectStatus "EU8F2.38" )
				)
				( pin "smbdat"
					( attribute "PN" "39"
						( Origin gPackager )
					)
					( objectStatus "EU8F2.39" )
				)
				( pin "vdd32k"
					( attribute "PN" "12"
						( Origin gPackager )
					)
					( objectStatus "EU8F2.12" )
				)
				( pin "vdd33"
					( attribute "PN" "23"
						( Origin gPackager )
					)
					( objectStatus "EU8F2.23" )
				)
				( pin "vdd96"
					( attribute "PN" "2"
						( Origin gPackager )
					)
					( objectStatus "EU8F2.2" )
				)
				( pin "vdd_rgmii"
					( attribute "PN" "34"
						( Origin gPackager )
					)
					( objectStatus "EU8F2.34" )
				)
				( pin "vddcpu"
					( attribute "PN" "9"
						( Origin gPackager )
					)
					( objectStatus "EU8F2.9" )
				)
				( pin "vddref"
					( attribute "PN" "15"
						( Origin gPackager )
					)
					( objectStatus "EU8F2.15" )
				)
				( pin "vddrmii(0)"
					( attribute "PN" "26"
						( Origin gPackager )
					)
					( objectStatus "EU8F2.26" )
				)
				( pin "vddrmii(1)"
					( attribute "PN" "31"
						( Origin gPackager )
					)
					( objectStatus "EU8F2.31" )
				)
				( pin "vttpwr_gd_pd_n"
					( attribute "PN" "40"
						( Origin gPackager )
					)
					( objectStatus "EU8F2.40" )
				)
				( pin "x1_25"
					( attribute "PN" "19"
						( Origin gPackager )
					)
					( objectStatus "EU8F2.19" )
				)
				( pin "x2_25"
					( attribute "PN" "20"
						( Origin gPackager )
					)
					( objectStatus "EU8F2.20" )
				)
			)
			( gate "@baseboard_fab2_lib.baseboard_fab2(sch_1):page101_i48"
				( attribute "BOM_COST" "SM_CONTROLLER"
					( Origin gFrontEnd )
				)
				( attribute "CDS_LIB" "mstr_discrete"
					( Origin gPackager )
				)
				( attribute "CDS_LOCATION" "R2T25"
					( Origin gPackager )
				)
				( attribute "CDS_SEC" "1"
					( Origin gPackager )
				)
				( attribute "LOCATION" "R2T25"
					( Origin gFrontEnd )
				)
				( attribute "MATERIAL" "CHIP"
					( Origin gFrontEnd )
				)
				( attribute "PACK_TYPE" "0402"
					( Origin gFrontEnd )
				)
				( attribute "PART_NUMBER" "G21796-026"
					( Origin gFrontEnd )
				)
				( attribute "PHYS_PAGE" "101"
					( Origin gFrontEnd )
				)
				( attribute "ROOM" "SYS_CLOCK"
					( Origin gFrontEnd )
				)
				( attribute "ROT" "0"
					( Origin gFrontEnd )
				)
				( attribute "SEC" "1"
					( Origin gFrontEnd )
				)
				( attribute "SEC_TYPE" "0402"
					( Origin gFrontEnd )
				)
				( attribute "TOLERANCE" "1%"
					( Origin gFrontEnd )
				)
				( attribute "VALUE" "1.00K"
					( Origin gFrontEnd )
				)
				( attribute "VER" "2"
					( Origin gFrontEnd )
				)
				( attribute "WATTAGE" "1/16W"
					( Origin gFrontEnd )
				)
				( attribute "XY" "(-8300,1200)"
					( Origin gFrontEnd )
				)
				( attribute "CHIPS_PART_NAME" "RES"
					( Origin gPackager )
				)
				( attribute "CDS_PART_NAME" "RES_0402-1.00K,1%,1/16W,CHIP,GA"
					( Origin gPackager )
				)
				( objectStatus "R2T25" )
				( pin "a"
					( attribute "PN" "1"
						( Origin gPackager )
					)
					( objectStatus "R2T25.1" )
				)
				( pin "b"
					( attribute "PN" "2"
						( Origin gPackager )
					)
					( objectStatus "R2T25.2" )
				)
			)
			( gate "@baseboard_fab2_lib.baseboard_fab2(sch_1):page101_i49"
				( attribute "BOM_COST" "SM_CONTROLLER"
					( Origin gFrontEnd )
				)
				( attribute "CDS_LIB" "mstr_discrete"
					( Origin gPackager )
				)
				( attribute "CDS_LOCATION" "C8F18"
					( Origin gPackager )
				)
				( attribute "CDS_SEC" "1"
					( Origin gPackager )
				)
				( attribute "LOCATION" "C8F18"
					( Origin gFrontEnd )
				)
				( attribute "MATERIAL" "COG"
					( Origin gFrontEnd )
				)
				( attribute "PACK_TYPE" "0402LF"
					( Origin gFrontEnd )
				)
				( attribute "PART_NUMBER" "A36095-038"
					( Origin gFrontEnd )
				)
				( attribute "PHYS_PAGE" "101"
					( Origin gFrontEnd )
				)
				( attribute "ROOM" "SYS_CLOCK"
					( Origin gFrontEnd )
				)
				( attribute "ROT" "0"
					( Origin gFrontEnd )
				)
				( attribute "SEC" "1"
					( Origin gPackager )
				)
				( attribute "TOLERANCE" "5%"
					( Origin gFrontEnd )
				)
				( attribute "VALUE" "27.0PF"
					( Origin gFrontEnd )
				)
				( attribute "VER" "1"
					( Origin gFrontEnd )
				)
				( attribute "VOLTAGE" "50V"
					( Units "uVoltage" "V" 1.000000)
					( Origin gFrontEnd )
				)
				( attribute "XY" "(-7275,775)"
					( Origin gFrontEnd )
				)
				( attribute "CHIPS_PART_NAME" "CAP"
					( Origin gPackager )
				)
				( attribute "CDS_PART_NAME" "CAP_0402LF-27.0PF,50V,5%,COG,AA"
					( Origin gPackager )
				)
				( objectStatus "C8F18" )
				( pin "a"
					( attribute "PN" "1"
						( Origin gPackager )
					)
					( objectStatus "C8F18.1" )
				)
				( pin "b"
					( attribute "PN" "2"
						( Origin gPackager )
					)
					( objectStatus "C8F18.2" )
				)
			)
			( gate "@baseboard_fab2_lib.baseboard_fab2(sch_1):page101_i52"
				( attribute "BOM_COST" "SM_CONTROLLER"
					( Origin gFrontEnd )
				)
				( attribute "CDS_LIB" "mstr_discrete"
					( Origin gPackager )
				)
				( attribute "CDS_LOCATION" "Y8F1"
					( Origin gPackager )
				)
				( attribute "CDS_SEC" "1"
					( Origin gPackager )
				)
				( attribute "LOCATION" "Y8F1"
					( Origin gFrontEnd )
				)
				( attribute "MATERIAL" "IC"
					( Origin gFrontEnd )
				)
				( attribute "PACK_TYPE" "2013LF"
					( Origin gFrontEnd )
				)
				( attribute "PART_NUMBER" "D71700-033"
					( Origin gFrontEnd )
				)
				( attribute "PHYS_PAGE" "101"
					( Origin gFrontEnd )
				)
				( attribute "ROOM" "SYS_CLOCK"
					( Origin gFrontEnd )
				)
				( attribute "ROT" "2"
					( Origin gFrontEnd )
				)
				( attribute "SEC" "1"
					( Origin gPackager )
				)
				( attribute "VALUE" "25.000MHZ"
					( Origin gFrontEnd )
				)
				( attribute "VER" "3"
					( Origin gFrontEnd )
				)
				( attribute "XY" "(-7450,1000)"
					( Origin gFrontEnd )
				)
				( attribute "CHIPS_PART_NAME" "CRYSTAL"
					( Origin gPackager )
				)
				( attribute "CDS_PART_NAME" "CRYSTAL_2013LF-25.000MHZ,IC,D7A"
					( Origin gPackager )
				)
				( objectStatus "Y8F1" )
				( pin "a"
					( attribute "PN" "1"
						( Origin gPackager )
					)
					( objectStatus "Y8F1.1" )
				)
				( pin "b"
					( attribute "PN" "3"
						( Origin gPackager )
					)
					( objectStatus "Y8F1.3" )
				)
			)
			( gate "@baseboard_fab2_lib.baseboard_fab2(sch_1):page101_i53"
				( attribute "BOM_COST" "SM_CONTROLLER"
					( Origin gFrontEnd )
				)
				( attribute "CDS_LIB" "mstr_discrete"
					( Origin gPackager )
				)
				( attribute "CDS_LOCATION" "C8F19"
					( Origin gPackager )
				)
				( attribute "CDS_SEC" "1"
					( Origin gPackager )
				)
				( attribute "LOCATION" "C8F19"
					( Origin gFrontEnd )
				)
				( attribute "MATERIAL" "COG"
					( Origin gFrontEnd )
				)
				( attribute "PACK_TYPE" "0402LF"
					( Origin gFrontEnd )
				)
				( attribute "PART_NUMBER" "A36095-038"
					( Origin gFrontEnd )
				)
				( attribute "PHYS_PAGE" "101"
					( Origin gFrontEnd )
				)
				( attribute "ROOM" "SYS_CLOCK"
					( Origin gFrontEnd )
				)
				( attribute "ROT" "2"
					( Origin gFrontEnd )
				)
				( attribute "SEC" "1"
					( Origin gPackager )
				)
				( attribute "TOLERANCE" "5%"
					( Origin gFrontEnd )
				)
				( attribute "VALUE" "27.0PF"
					( Origin gFrontEnd )
				)
				( attribute "VER" "1"
					( Origin gFrontEnd )
				)
				( attribute "VOLTAGE" "50V"
					( Units "uVoltage" "V" 1.000000)
					( Origin gFrontEnd )
				)
				( attribute "XY" "(-7625,775)"
					( Origin gFrontEnd )
				)
				( attribute "CHIPS_PART_NAME" "CAP"
					( Origin gPackager )
				)
				( attribute "CDS_PART_NAME" "CAP_0402LF-27.0PF,50V,5%,COG,AA"
					( Origin gPackager )
				)
				( objectStatus "C8F19" )
				( pin "a"
					( attribute "PN" "1"
						( Origin gPackager )
					)
					( objectStatus "C8F19.1" )
				)
				( pin "b"
					( attribute "PN" "2"
						( Origin gPackager )
					)
					( objectStatus "C8F19.2" )
				)
			)
			( gate "@baseboard_fab2_lib.baseboard_fab2(sch_1):page101_i89"
				( attribute "BOM_COST" "SM_CONTROLLER"
					( Origin gFrontEnd )
				)
				( attribute "CDS_LIB" "dev_discrete"
					( Origin gPackager )
				)
				( attribute "CDS_LOCATION" "C2T31"
					( Origin gPackager )
				)
				( attribute "CDS_SEC" "1"
					( Origin gPackager )
				)
				( attribute "LOCATION" "C2T31"
					( Origin gFrontEnd )
				)
				( attribute "MATERIAL" "X6S"
					( Origin gFrontEnd )
				)
				( attribute "PACK_TYPE" "0402V"
					( Origin gFrontEnd )
				)
				( attribute "PART_NUMBER" "D97712-004"
					( Origin gFrontEnd )
				)
				( attribute "PHYS_PAGE" "101"
					( Origin gFrontEnd )
				)
				( attribute "ROOM" "SYS_CLOCK"
					( Origin gFrontEnd )
				)
				( attribute "ROT" "0"
					( Origin gFrontEnd )
				)
				( attribute "SEC" "1"
					( Origin gPackager )
				)
				( attribute "TOLERANCE" "10%"
					( Origin gFrontEnd )
				)
				( attribute "VALUE" "1.0UF"
					( Origin gFrontEnd )
				)
				( attribute "VER" "1"
					( Origin gFrontEnd )
				)
				( attribute "VOLTAGE" "6.3V"
					( Units "uVoltage" "V" 1.000000)
					( Origin gFrontEnd )
				)
				( attribute "XY" "(-2975,3925)"
					( Origin gFrontEnd )
				)
				( attribute "CHIPS_PART_NAME" "CAP_A"
					( Origin gPackager )
				)
				( attribute "CDS_PART_NAME" "CAP_A_0402V-1.0UF,6.3V,10%,X6SA"
					( Origin gPackager )
				)
				( objectStatus "C2T31" )
				( pin "a"
					( attribute "PN" "1"
						( Origin gPackager )
					)
					( objectStatus "C2T31.1" )
				)
				( pin "b"
					( attribute "PN" "2"
						( Origin gPackager )
					)
					( objectStatus "C2T31.2" )
				)
			)
			( gate "@baseboard_fab2_lib.baseboard_fab2(sch_1):page101_i90"
				( attribute "BOM_COST" "SM_CONTROLLER"
					( Origin gFrontEnd )
				)
				( attribute "CDS_LIB" "dev_discrete"
					( Origin gPackager )
				)
				( attribute "CDS_LOCATION" "C2T27"
					( Origin gPackager )
				)
				( attribute "CDS_SEC" "1"
					( Origin gPackager )
				)
				( attribute "LOCATION" "C2T27"
					( Origin gFrontEnd )
				)
				( attribute "MATERIAL" "X7R"
					( Origin gFrontEnd )
				)
				( attribute "PACK_TYPE" "0402V"
					( Origin gFrontEnd )
				)
				( attribute "PART_NUMBER" "A36096-045"
					( Origin gFrontEnd )
				)
				( attribute "PHYS_PAGE" "101"
					( Origin gFrontEnd )
				)
				( attribute "ROOM" "SYS_CLOCK"
					( Origin gFrontEnd )
				)
				( attribute "ROT" "0"
					( Origin gFrontEnd )
				)
				( attribute "SEC" "1"
					( Origin gPackager )
				)
				( attribute "TOLERANCE" "10%"
					( Origin gFrontEnd )
				)
				( attribute "VALUE" "0.01UF"
					( Origin gFrontEnd )
				)
				( attribute "VER" "1"
					( Origin gFrontEnd )
				)
				( attribute "VOLTAGE" "25V"
					( Units "uVoltage" "V" 1.000000)
					( Origin gFrontEnd )
				)
				( attribute "XY" "(-3400,3925)"
					( Origin gFrontEnd )
				)
				( attribute "CHIPS_PART_NAME" "CAP_A"
					( Origin gPackager )
				)
				( attribute "CDS_PART_NAME" "CAP_A_0402V-0.01UF,25V,10%,X7RA"
					( Origin gPackager )
				)
				( objectStatus "C2T27" )
				( pin "a"
					( attribute "PN" "1"
						( Origin gPackager )
					)
					( objectStatus "C2T27.1" )
				)
				( pin "b"
					( attribute "PN" "2"
						( Origin gPackager )
					)
					( objectStatus "C2T27.2" )
				)
			)
			( gate "@baseboard_fab2_lib.baseboard_fab2(sch_1):page101_i94"
				( attribute "BOM_COST" "SM_CONTROLLER"
					( Origin gFrontEnd )
				)
				( attribute "CDS_LIB" "mstr_discrete"
					( Origin gPackager )
				)
				( attribute "CDS_LOCATION" "R2T23"
					( Origin gPackager )
				)
				( attribute "CDS_SEC" "1"
					( Origin gPackager )
				)
				( attribute "LOCATION" "R2T23"
					( Origin gFrontEnd )
				)
				( attribute "MATERIAL" "CHIP"
					( Origin gFrontEnd )
				)
				( attribute "PACK_TYPE" "0603"
					( Origin gFrontEnd )
				)
				( attribute "PART_NUMBER" "G22026-127"
					( Origin gFrontEnd )
				)
				( attribute "PHYS_PAGE" "101"
					( Origin gFrontEnd )
				)
				( attribute "ROOM" "SYS_CLOCK"
					( Origin gFrontEnd )
				)
				( attribute "ROT" "0"
					( Origin gFrontEnd )
				)
				( attribute "SEC" "1"
					( Origin gPackager )
				)
				( attribute "TOLERANCE" "1.0%"
					( Origin gFrontEnd )
				)
				( attribute "VALUE" "2.2"
					( Origin gFrontEnd )
				)
				( attribute "VER" "1"
					( Origin gFrontEnd )
				)
				( attribute "WATTAGE" "1/10W"
					( Origin gFrontEnd )
				)
				( attribute "XY" "(-3675,4150)"
					( Origin gFrontEnd )
				)
				( attribute "CHIPS_PART_NAME" "RES"
					( Origin gPackager )
				)
				( attribute "CDS_PART_NAME" "RES_0603-2.2,1.0%,1/10W,CHIP,GA"
					( Origin gPackager )
				)
				( objectStatus "R2T23" )
				( pin "a"
					( attribute "PN" "1"
						( Origin gPackager )
					)
					( objectStatus "R2T23.1" )
				)
				( pin "b"
					( attribute "PN" "2"
						( Origin gPackager )
					)
					( objectStatus "R2T23.2" )
				)
			)
			( gate "@baseboard_fab2_lib.baseboard_fab2(sch_1):page101_i95"
				( attribute "BOM_COST" "SM_CONTROLLER"
					( Origin gFrontEnd )
				)
				( attribute "CDS_LIB" "mstr_discrete"
					( Origin gPackager )
				)
				( attribute "CDS_LOCATION" "R2T52"
					( Origin gPackager )
				)
				( attribute "CDS_SEC" "1"
					( Origin gPackager )
				)
				( attribute "LOCATION" "R2T52"
					( Origin gFrontEnd )
				)
				( attribute "MATERIAL" "CHIP"
					( Origin gFrontEnd )
				)
				( attribute "PACK_TYPE" "0603"
					( Origin gFrontEnd )
				)
				( attribute "PART_NUMBER" "G22026-127"
					( Origin gFrontEnd )
				)
				( attribute "PHYS_PAGE" "101"
					( Origin gFrontEnd )
				)
				( attribute "ROOM" "SYS_CLOCK"
					( Origin gFrontEnd )
				)
				( attribute "ROT" "0"
					( Origin gFrontEnd )
				)
				( attribute "SEC" "1"
					( Origin gPackager )
				)
				( attribute "TOLERANCE" "1.0%"
					( Origin gFrontEnd )
				)
				( attribute "VALUE" "2.2"
					( Origin gFrontEnd )
				)
				( attribute "VER" "1"
					( Origin gFrontEnd )
				)
				( attribute "WATTAGE" "1/10W"
					( Origin gFrontEnd )
				)
				( attribute "XY" "(-2250,4200)"
					( Origin gFrontEnd )
				)
				( attribute "CHIPS_PART_NAME" "RES"
					( Origin gPackager )
				)
				( attribute "CDS_PART_NAME" "RES_0603-2.2,1.0%,1/10W,CHIP,GA"
					( Origin gPackager )
				)
				( objectStatus "R2T52" )
				( pin "a"
					( attribute "PN" "1"
						( Origin gPackager )
					)
					( objectStatus "R2T52.1" )
				)
				( pin "b"
					( attribute "PN" "2"
						( Origin gPackager )
					)
					( objectStatus "R2T52.2" )
				)
			)
			( gate "@baseboard_fab2_lib.baseboard_fab2(sch_1):page101_i97"
				( attribute "BOM_COST" "SM_CONTROLLER"
					( Origin gFrontEnd )
				)
				( attribute "CDS_LIB" "dev_discrete"
					( Origin gPackager )
				)
				( attribute "CDS_LOCATION" "C2T38"
					( Origin gPackager )
				)
				( attribute "CDS_SEC" "1"
					( Origin gPackager )
				)
				( attribute "LOCATION" "C2T38"
					( Origin gFrontEnd )
				)
				( attribute "MATERIAL" "X6S"
					( Origin gFrontEnd )
				)
				( attribute "PACK_TYPE" "0402V"
					( Origin gFrontEnd )
				)
				( attribute "PART_NUMBER" "D97712-004"
					( Origin gFrontEnd )
				)
				( attribute "PHYS_PAGE" "101"
					( Origin gFrontEnd )
				)
				( attribute "ROOM" "SYS_CLOCK"
					( Origin gFrontEnd )
				)
				( attribute "ROT" "0"
					( Origin gFrontEnd )
				)
				( attribute "SEC" "1"
					( Origin gPackager )
				)
				( attribute "TOLERANCE" "10%"
					( Origin gFrontEnd )
				)
				( attribute "VALUE" "1.0UF"
					( Origin gFrontEnd )
				)
				( attribute "VER" "1"
					( Origin gFrontEnd )
				)
				( attribute "VOLTAGE" "6.3V"
					( Units "uVoltage" "V" 1.000000)
					( Origin gFrontEnd )
				)
				( attribute "XY" "(-1675,4000)"
					( Origin gFrontEnd )
				)
				( attribute "CHIPS_PART_NAME" "CAP_A"
					( Origin gPackager )
				)
				( attribute "CDS_PART_NAME" "CAP_A_0402V-1.0UF,6.3V,10%,X6SA"
					( Origin gPackager )
				)
				( objectStatus "C2T38" )
				( pin "a"
					( attribute "PN" "1"
						( Origin gPackager )
					)
					( objectStatus "C2T38.1" )
				)
				( pin "b"
					( attribute "PN" "2"
						( Origin gPackager )
					)
					( objectStatus "C2T38.2" )
				)
			)
			( gate "@baseboard_fab2_lib.baseboard_fab2(sch_1):page101_i99"
				( attribute "BOM_COST" "SM_CONTROLLER"
					( Origin gFrontEnd )
				)
				( attribute "CDS_LIB" "dev_discrete"
					( Origin gPackager )
				)
				( attribute "CDS_LOCATION" "C2T37"
					( Origin gPackager )
				)
				( attribute "CDS_SEC" "1"
					( Origin gPackager )
				)
				( attribute "LOCATION" "C2T37"
					( Origin gFrontEnd )
				)
				( attribute "MATERIAL" "X7R"
					( Origin gFrontEnd )
				)
				( attribute "PACK_TYPE" "0402V"
					( Origin gFrontEnd )
				)
				( attribute "PART_NUMBER" "A36096-045"
					( Origin gFrontEnd )
				)
				( attribute "PHYS_PAGE" "101"
					( Origin gFrontEnd )
				)
				( attribute "ROOM" "SYS_CLOCK"
					( Origin gFrontEnd )
				)
				( attribute "ROT" "0"
					( Origin gFrontEnd )
				)
				( attribute "SEC" "1"
					( Origin gPackager )
				)
				( attribute "TOLERANCE" "10%"
					( Origin gFrontEnd )
				)
				( attribute "VALUE" "0.01UF"
					( Origin gFrontEnd )
				)
				( attribute "VER" "1"
					( Origin gFrontEnd )
				)
				( attribute "VOLTAGE" "25V"
					( Units "uVoltage" "V" 1.000000)
					( Origin gFrontEnd )
				)
				( attribute "XY" "(-2050,4000)"
					( Origin gFrontEnd )
				)
				( attribute "CHIPS_PART_NAME" "CAP_A"
					( Origin gPackager )
				)
				( attribute "CDS_PART_NAME" "CAP_A_0402V-0.01UF,25V,10%,X7RA"
					( Origin gPackager )
				)
				( objectStatus "C2T37" )
				( pin "a"
					( attribute "PN" "1"
						( Origin gPackager )
					)
					( objectStatus "C2T37.1" )
				)
				( pin "b"
					( attribute "PN" "2"
						( Origin gPackager )
					)
					( objectStatus "C2T37.2" )
				)
			)
			( gate "@baseboard_fab2_lib.baseboard_fab2(sch_1):page101_i104"
				( attribute "BOM_COST" "SM_CONTROLLER"
					( Origin gFrontEnd )
				)
				( attribute "CDS_LIB" "dev_discrete"
					( Origin gPackager )
				)
				( attribute "CDS_LOCATION" "C2T18"
					( Origin gPackager )
				)
				( attribute "CDS_SEC" "1"
					( Origin gPackager )
				)
				( attribute "LOCATION" "C2T18"
					( Origin gFrontEnd )
				)
				( attribute "MATERIAL" "X7R"
					( Origin gFrontEnd )
				)
				( attribute "PACK_TYPE" "0402V"
					( Origin gFrontEnd )
				)
				( attribute "PART_NUMBER" "A36096-045"
					( Origin gFrontEnd )
				)
				( attribute "PHYS_PAGE" "101"
					( Origin gFrontEnd )
				)
				( attribute "ROOM" "SYS_CLOCK"
					( Origin gFrontEnd )
				)
				( attribute "ROT" "0"
					( Origin gFrontEnd )
				)
				( attribute "SEC" "1"
					( Origin gPackager )
				)
				( attribute "TOLERANCE" "10%"
					( Origin gFrontEnd )
				)
				( attribute "VALUE" "0.01UF"
					( Origin gFrontEnd )
				)
				( attribute "VER" "1"
					( Origin gFrontEnd )
				)
				( attribute "VOLTAGE" "25V"
					( Units "uVoltage" "V" 1.000000)
					( Origin gFrontEnd )
				)
				( attribute "XY" "(-4875,4000)"
					( Origin gFrontEnd )
				)
				( attribute "CHIPS_PART_NAME" "CAP_A"
					( Origin gPackager )
				)
				( attribute "CDS_PART_NAME" "CAP_A_0402V-0.01UF,25V,10%,X7RA"
					( Origin gPackager )
				)
				( objectStatus "C2T18" )
				( pin "a"
					( attribute "PN" "1"
						( Origin gPackager )
					)
					( objectStatus "C2T18.1" )
				)
				( pin "b"
					( attribute "PN" "2"
						( Origin gPackager )
					)
					( objectStatus "C2T18.2" )
				)
			)
			( gate "@baseboard_fab2_lib.baseboard_fab2(sch_1):page101_i105"
				( attribute "BOM_COST" "SM_CONTROLLER"
					( Origin gFrontEnd )
				)
				( attribute "CDS_LIB" "mstr_discrete"
					( Origin gPackager )
				)
				( attribute "CDS_LOCATION" "R2T21"
					( Origin gPackager )
				)
				( attribute "CDS_SEC" "1"
					( Origin gPackager )
				)
				( attribute "LOCATION" "R2T21"
					( Origin gFrontEnd )
				)
				( attribute "MATERIAL" "CHIP"
					( Origin gFrontEnd )
				)
				( attribute "PACK_TYPE" "0603"
					( Origin gFrontEnd )
				)
				( attribute "PART_NUMBER" "G22026-127"
					( Origin gFrontEnd )
				)
				( attribute "PHYS_PAGE" "101"
					( Origin gFrontEnd )
				)
				( attribute "ROOM" "SYS_CLOCK"
					( Origin gFrontEnd )
				)
				( attribute "ROT" "0"
					( Origin gFrontEnd )
				)
				( attribute "SEC" "1"
					( Origin gFrontEnd )
				)
				( attribute "SEC_TYPE" "0603"
					( Origin gFrontEnd )
				)
				( attribute "TOLERANCE" "1.0%"
					( Origin gFrontEnd )
				)
				( attribute "VALUE" "2.2"
					( Origin gFrontEnd )
				)
				( attribute "VER" "1"
					( Origin gFrontEnd )
				)
				( attribute "WATTAGE" "1/10W"
					( Origin gFrontEnd )
				)
				( attribute "XY" "(-5150,4175)"
					( Origin gFrontEnd )
				)
				( attribute "CHIPS_PART_NAME" "RES"
					( Origin gPackager )
				)
				( attribute "CDS_PART_NAME" "RES_0603-2.2,1.0%,1/10W,CHIP,GA"
					( Origin gPackager )
				)
				( objectStatus "R2T21" )
				( pin "a"
					( attribute "PN" "1"
						( Origin gPackager )
					)
					( objectStatus "R2T21.1" )
				)
				( pin "b"
					( attribute "PN" "2"
						( Origin gPackager )
					)
					( objectStatus "R2T21.2" )
				)
			)
			( gate "@baseboard_fab2_lib.baseboard_fab2(sch_1):page101_i106"
				( attribute "BOM_COST" "SM_CONTROLLER"
					( Origin gFrontEnd )
				)
				( attribute "CDS_LIB" "dev_discrete"
					( Origin gPackager )
				)
				( attribute "CDS_LOCATION" "C2T19"
					( Origin gPackager )
				)
				( attribute "CDS_SEC" "1"
					( Origin gPackager )
				)
				( attribute "LOCATION" "C2T19"
					( Origin gFrontEnd )
				)
				( attribute "MATERIAL" "X6S"
					( Origin gFrontEnd )
				)
				( attribute "PACK_TYPE" "0402V"
					( Origin gFrontEnd )
				)
				( attribute "PART_NUMBER" "D97712-004"
					( Origin gFrontEnd )
				)
				( attribute "PHYS_PAGE" "101"
					( Origin gFrontEnd )
				)
				( attribute "ROOM" "SYS_CLOCK"
					( Origin gFrontEnd )
				)
				( attribute "ROT" "0"
					( Origin gFrontEnd )
				)
				( attribute "SEC" "1"
					( Origin gPackager )
				)
				( attribute "TOLERANCE" "10%"
					( Origin gFrontEnd )
				)
				( attribute "VALUE" "1.0UF"
					( Origin gFrontEnd )
				)
				( attribute "VER" "1"
					( Origin gFrontEnd )
				)
				( attribute "VOLTAGE" "6.3V"
					( Units "uVoltage" "V" 1.000000)
					( Origin gFrontEnd )
				)
				( attribute "XY" "(-4475,4000)"
					( Origin gFrontEnd )
				)
				( attribute "CHIPS_PART_NAME" "CAP_A"
					( Origin gPackager )
				)
				( attribute "CDS_PART_NAME" "CAP_A_0402V-1.0UF,6.3V,10%,X6SA"
					( Origin gPackager )
				)
				( objectStatus "C2T19" )
				( pin "a"
					( attribute "PN" "1"
						( Origin gPackager )
					)
					( objectStatus "C2T19.1" )
				)
				( pin "b"
					( attribute "PN" "2"
						( Origin gPackager )
					)
					( objectStatus "C2T19.2" )
				)
			)
			( gate "@baseboard_fab2_lib.baseboard_fab2(sch_1):page101_i109"
				( attribute "BOM_COST" "SM_CONTROLLER"
					( Origin gFrontEnd )
				)
				( attribute "CDS_LIB" "dev_discrete"
					( Origin gPackager )
				)
				( attribute "CDS_LOCATION" "C2T34"
					( Origin gPackager )
				)
				( attribute "CDS_SEC" "1"
					( Origin gPackager )
				)
				( attribute "LOCATION" "C2T34"
					( Origin gFrontEnd )
				)
				( attribute "MATERIAL" "X7R"
					( Origin gFrontEnd )
				)
				( attribute "PACK_TYPE" "0402V"
					( Origin gFrontEnd )
				)
				( attribute "PART_NUMBER" "A36096-030"
					( Origin gFrontEnd )
				)
				( attribute "PHYS_PAGE" "101"
					( Origin gFrontEnd )
				)
				( attribute "ROOM" "SYS_CLOCK"
					( Origin gFrontEnd )
				)
				( attribute "ROT" "0"
					( Origin gFrontEnd )
				)
				( attribute "SEC" "1"
					( Origin gFrontEnd )
				)
				( attribute "SEC_TYPE" "0402V"
					( Origin gFrontEnd )
				)
				( attribute "TOLERANCE" "10%"
					( Origin gFrontEnd )
				)
				( attribute "VALUE" "0.1UF"
					( Origin gFrontEnd )
				)
				( attribute "VER" "1"
					( Origin gFrontEnd )
				)
				( attribute "VOLTAGE" "16V"
					( Units "uVoltage" "V" 1.000000)
					( Origin gFrontEnd )
				)
				( attribute "XY" "(-6600,3975)"
					( Origin gFrontEnd )
				)
				( attribute "CHIPS_PART_NAME" "CAP_A"
					( Origin gPackager )
				)
				( attribute "CDS_PART_NAME" "CAP_A_0402V-0.1UF,16V,10%,X7R,A"
					( Origin gPackager )
				)
				( objectStatus "C2T34" )
				( pin "a"
					( attribute "PN" "1"
						( Origin gPackager )
					)
					( objectStatus "C2T34.1" )
				)
				( pin "b"
					( attribute "PN" "2"
						( Origin gPackager )
					)
					( objectStatus "C2T34.2" )
				)
			)
			( gate "@baseboard_fab2_lib.baseboard_fab2(sch_1):page101_i110"
				( attribute "BOM_COST" "SM_CONTROLLER"
					( Origin gFrontEnd )
				)
				( attribute "CDS_LIB" "dev_discrete"
					( Origin gPackager )
				)
				( attribute "CDS_LOCATION" "C2T30"
					( Origin gPackager )
				)
				( attribute "CDS_SEC" "1"
					( Origin gPackager )
				)
				( attribute "LOCATION" "C2T30"
					( Origin gFrontEnd )
				)
				( attribute "MATERIAL" "X7R"
					( Origin gFrontEnd )
				)
				( attribute "PACK_TYPE" "0402V"
					( Origin gFrontEnd )
				)
				( attribute "PART_NUMBER" "A36096-030"
					( Origin gFrontEnd )
				)
				( attribute "PHYS_PAGE" "101"
					( Origin gFrontEnd )
				)
				( attribute "ROOM" "SYS_CLOCK"
					( Origin gFrontEnd )
				)
				( attribute "ROT" "0"
					( Origin gFrontEnd )
				)
				( attribute "SEC" "1"
					( Origin gPackager )
				)
				( attribute "TOLERANCE" "10%"
					( Origin gFrontEnd )
				)
				( attribute "VALUE" "0.1UF"
					( Origin gFrontEnd )
				)
				( attribute "VER" "1"
					( Origin gFrontEnd )
				)
				( attribute "VOLTAGE" "16V"
					( Units "uVoltage" "V" 1.000000)
					( Origin gFrontEnd )
				)
				( attribute "XY" "(-6900,3975)"
					( Origin gFrontEnd )
				)
				( attribute "CHIPS_PART_NAME" "CAP_A"
					( Origin gPackager )
				)
				( attribute "CDS_PART_NAME" "CAP_A_0402V-0.1UF,16V,10%,X7R,A"
					( Origin gPackager )
				)
				( objectStatus "C2T30" )
				( pin "a"
					( attribute "PN" "1"
						( Origin gPackager )
					)
					( objectStatus "C2T30.1" )
				)
				( pin "b"
					( attribute "PN" "2"
						( Origin gPackager )
					)
					( objectStatus "C2T30.2" )
				)
			)
			( gate "@baseboard_fab2_lib.baseboard_fab2(sch_1):page101_i111"
				( attribute "BOM_COST" "SM_CONTROLLER"
					( Origin gFrontEnd )
				)
				( attribute "CDS_LIB" "dev_discrete"
					( Origin gPackager )
				)
				( attribute "CDS_LOCATION" "C2T25"
					( Origin gPackager )
				)
				( attribute "CDS_SEC" "1"
					( Origin gPackager )
				)
				( attribute "LOCATION" "C2T25"
					( Origin gFrontEnd )
				)
				( attribute "MATERIAL" "X7R"
					( Origin gFrontEnd )
				)
				( attribute "PACK_TYPE" "0402V"
					( Origin gFrontEnd )
				)
				( attribute "PART_NUMBER" "A36096-030"
					( Origin gFrontEnd )
				)
				( attribute "PHYS_PAGE" "101"
					( Origin gFrontEnd )
				)
				( attribute "ROOM" "SYS_CLOCK"
					( Origin gFrontEnd )
				)
				( attribute "ROT" "0"
					( Origin gFrontEnd )
				)
				( attribute "SEC" "1"
					( Origin gPackager )
				)
				( attribute "TOLERANCE" "10%"
					( Origin gFrontEnd )
				)
				( attribute "VALUE" "0.1UF"
					( Origin gFrontEnd )
				)
				( attribute "VER" "1"
					( Origin gFrontEnd )
				)
				( attribute "VOLTAGE" "16V"
					( Units "uVoltage" "V" 1.000000)
					( Origin gFrontEnd )
				)
				( attribute "XY" "(-7300,3975)"
					( Origin gFrontEnd )
				)
				( attribute "CHIPS_PART_NAME" "CAP_A"
					( Origin gPackager )
				)
				( attribute "CDS_PART_NAME" "CAP_A_0402V-0.1UF,16V,10%,X7R,A"
					( Origin gPackager )
				)
				( objectStatus "C2T25" )
				( pin "a"
					( attribute "PN" "1"
						( Origin gPackager )
					)
					( objectStatus "C2T25.1" )
				)
				( pin "b"
					( attribute "PN" "2"
						( Origin gPackager )
					)
					( objectStatus "C2T25.2" )
				)
			)
			( gate "@baseboard_fab2_lib.baseboard_fab2(sch_1):page101_i112"
				( attribute "BOM_COST" "SM_CONTROLLER"
					( Origin gFrontEnd )
				)
				( attribute "CDS_LIB" "dev_discrete"
					( Origin gPackager )
				)
				( attribute "CDS_LOCATION" "C2T17"
					( Origin gPackager )
				)
				( attribute "CDS_SEC" "1"
					( Origin gPackager )
				)
				( attribute "LOCATION" "C2T17"
					( Origin gFrontEnd )
				)
				( attribute "MATERIAL" "X7R"
					( Origin gFrontEnd )
				)
				( attribute "PACK_TYPE" "0402V"
					( Origin gFrontEnd )
				)
				( attribute "PART_NUMBER" "A36096-030"
					( Origin gFrontEnd )
				)
				( attribute "PHYS_PAGE" "101"
					( Origin gFrontEnd )
				)
				( attribute "ROOM" "SYS_CLOCK"
					( Origin gFrontEnd )
				)
				( attribute "ROT" "0"
					( Origin gFrontEnd )
				)
				( attribute "SEC" "1"
					( Origin gPackager )
				)
				( attribute "TOLERANCE" "10%"
					( Origin gFrontEnd )
				)
				( attribute "VALUE" "0.1UF"
					( Origin gFrontEnd )
				)
				( attribute "VER" "1"
					( Origin gFrontEnd )
				)
				( attribute "VOLTAGE" "16V"
					( Units "uVoltage" "V" 1.000000)
					( Origin gFrontEnd )
				)
				( attribute "XY" "(-7600,3975)"
					( Origin gFrontEnd )
				)
				( attribute "CHIPS_PART_NAME" "CAP_A"
					( Origin gPackager )
				)
				( attribute "CDS_PART_NAME" "CAP_A_0402V-0.1UF,16V,10%,X7R,A"
					( Origin gPackager )
				)
				( objectStatus "C2T17" )
				( pin "a"
					( attribute "PN" "1"
						( Origin gPackager )
					)
					( objectStatus "C2T17.1" )
				)
				( pin "b"
					( attribute "PN" "2"
						( Origin gPackager )
					)
					( objectStatus "C2T17.2" )
				)
			)
			( gate "@baseboard_fab2_lib.baseboard_fab2(sch_1):page101_i113"
				( attribute "BOM_COST" "SM_CONTROLLER"
					( Origin gFrontEnd )
				)
				( attribute "CDS_LIB" "mstr_discrete"
					( Origin gPackager )
				)
				( attribute "CDS_LOCATION" "C2T22"
					( Origin gPackager )
				)
				( attribute "CDS_SEC" "1"
					( Origin gPackager )
				)
				( attribute "LOCATION" "C2T22"
					( Origin gFrontEnd )
				)
				( attribute "MATERIAL" "X6S"
					( Origin gFrontEnd )
				)
				( attribute "PACK_TYPE" "0805"
					( Origin gFrontEnd )
				)
				( attribute "PART_NUMBER" "C95333-007"
					( Origin gFrontEnd )
				)
				( attribute "PHYS_PAGE" "101"
					( Origin gFrontEnd )
				)
				( attribute "ROOM" "SYS_CLOCK"
					( Origin gFrontEnd )
				)
				( attribute "ROT" "0"
					( Origin gFrontEnd )
				)
				( attribute "SEC" "1"
					( Origin gFrontEnd )
				)
				( attribute "SEC_TYPE" "0805"
					( Origin gFrontEnd )
				)
				( attribute "TOLERANCE" "10%"
					( Origin gFrontEnd )
				)
				( attribute "VALUE" "10UF"
					( Origin gFrontEnd )
				)
				( attribute "VER" "1"
					( Origin gFrontEnd )
				)
				( attribute "VOLTAGE" "16V"
					( Units "uVoltage" "V" 1.000000)
					( Origin gFrontEnd )
				)
				( attribute "XY" "(-7900,3975)"
					( Origin gFrontEnd )
				)
				( attribute "CHIPS_PART_NAME" "CAP"
					( Origin gPackager )
				)
				( attribute "CDS_PART_NAME" "CAP_0805-10UF,16V,10%,X6S,C953A"
					( Origin gPackager )
				)
				( objectStatus "C2T22" )
				( pin "a"
					( attribute "PN" "1"
						( Origin gPackager )
					)
					( objectStatus "C2T22.1" )
				)
				( pin "b"
					( attribute "PN" "2"
						( Origin gPackager )
					)
					( objectStatus "C2T22.2" )
				)
			)
			( gate "@baseboard_fab2_lib.baseboard_fab2(sch_1):page101_i114"
				( attribute "BOM_COST" "SM_CONTROLLER"
					( Origin gFrontEnd )
				)
				( attribute "CDS_LIB" "mstr_discrete"
					( Origin gPackager )
				)
				( attribute "CDS_LOCATION" "FB2T2"
					( Origin gPackager )
				)
				( attribute "CDS_SEC" "1"
					( Origin gPackager )
				)
				( attribute "LOCATION" "FB2T2"
					( Origin gFrontEnd )
				)
				( attribute "MATERIAL" "FB"
					( Origin gFrontEnd )
				)
				( attribute "PACK_TYPE" "SMLF"
					( Origin gFrontEnd )
				)
				( attribute "PART_NUMBER" "656554-043"
					( Origin gFrontEnd )
				)
				( attribute "PHYS_PAGE" "101"
					( Origin gFrontEnd )
				)
				( attribute "ROOM" "SYS_CLOCK"
					( Origin gFrontEnd )
				)
				( attribute "ROT" "0"
					( Origin gFrontEnd )
				)
				( attribute "SEC" "1"
					( Origin gPackager )
				)
				( attribute "VALUE" "600"
					( Origin gFrontEnd )
				)
				( attribute "VER" "1"
					( Origin gFrontEnd )
				)
				( attribute "XY" "(-8125,4125)"
					( Origin gFrontEnd )
				)
				( attribute "CHIPS_PART_NAME" "FERRITE"
					( Origin gPackager )
				)
				( attribute "CDS_PART_NAME" "FERRITE_SMLF-600,FB,656554-043"
					( Origin gPackager )
				)
				( objectStatus "FB2T2" )
				( pin "a"
					( attribute "PN" "1"
						( Origin gPackager )
					)
					( objectStatus "FB2T2.1" )
				)
				( pin "b"
					( attribute "PN" "2"
						( Origin gPackager )
					)
					( objectStatus "FB2T2.2" )
				)
			)
			( gate "@baseboard_fab2_lib.baseboard_fab2(sch_1):page101_i116"
				( attribute "BOM_COST" "SM_CONTROLLER"
					( Origin gFrontEnd )
				)
				( attribute "CDS_LIB" "dev_discrete"
					( Origin gPackager )
				)
				( attribute "CDS_LOCATION" "C2T28"
					( Origin gPackager )
				)
				( attribute "CDS_SEC" "1"
					( Origin gPackager )
				)
				( attribute "LOCATION" "C2T28"
					( Origin gFrontEnd )
				)
				( attribute "MATERIAL" "X6S"
					( Origin gFrontEnd )
				)
				( attribute "PACK_TYPE" "0402V"
					( Origin gFrontEnd )
				)
				( attribute "PART_NUMBER" "D97712-004"
					( Origin gFrontEnd )
				)
				( attribute "PHYS_PAGE" "101"
					( Origin gFrontEnd )
				)
				( attribute "ROOM" "SYS_CLOCK"
					( Origin gFrontEnd )
				)
				( attribute "ROT" "0"
					( Origin gFrontEnd )
				)
				( attribute "SEC" "1"
					( Origin gPackager )
				)
				( attribute "TOLERANCE" "10%"
					( Origin gFrontEnd )
				)
				( attribute "VALUE" "1.0UF"
					( Origin gFrontEnd )
				)
				( attribute "VER" "1"
					( Origin gFrontEnd )
				)
				( attribute "VOLTAGE" "6.3V"
					( Units "uVoltage" "V" 1.000000)
					( Origin gFrontEnd )
				)
				( attribute "XY" "(-8475,3950)"
					( Origin gFrontEnd )
				)
				( attribute "CHIPS_PART_NAME" "CAP_A"
					( Origin gPackager )
				)
				( attribute "CDS_PART_NAME" "CAP_A_0402V-1.0UF,6.3V,10%,X6SA"
					( Origin gPackager )
				)
				( objectStatus "C2T28" )
				( pin "a"
					( attribute "PN" "1"
						( Origin gPackager )
					)
					( objectStatus "C2T28.1" )
				)
				( pin "b"
					( attribute "PN" "2"
						( Origin gPackager )
					)
					( objectStatus "C2T28.2" )
				)
			)
			( gate "@baseboard_fab2_lib.baseboard_fab2(sch_1):page101_i124"
				( attribute "BOM_COST" "SM_CONTROLLER"
					( Origin gFrontEnd )
				)
				( attribute "CDS_LIB" "mstr_discrete"
					( Origin gPackager )
				)
				( attribute "CDS_LOCATION" "R2T42"
					( Origin gPackager )
				)
				( attribute "CDS_SEC" "1"
					( Origin gPackager )
				)
				( attribute "LOCATION" "R2T42"
					( Origin gFrontEnd )
				)
				( attribute "MATERIAL" "CHIP"
					( Origin gFrontEnd )
				)
				( attribute "PACK_TYPE" "0402"
					( Origin gFrontEnd )
				)
				( attribute "PART_NUMBER" "G21796-250"
					( Origin gFrontEnd )
				)
				( attribute "PHYS_PAGE" "101"
					( Origin gFrontEnd )
				)
				( attribute "ROOM" "SYS_CLOCK"
					( Origin gFrontEnd )
				)
				( attribute "ROT" "0"
					( Origin gFrontEnd )
				)
				( attribute "SEC" "1"
					( Origin gFrontEnd )
				)
				( attribute "SEC_TYPE" "0402"
					( Origin gFrontEnd )
				)
				( attribute "TOLERANCE" "1.0%"
					( Origin gFrontEnd )
				)
				( attribute "VALUE" "22.1"
					( Origin gFrontEnd )
				)
				( attribute "VER" "1"
					( Origin gFrontEnd )
				)
				( attribute "WATTAGE" "1/16W"
					( Origin gFrontEnd )
				)
				( attribute "XY" "(-3425,1525)"
					( Origin gFrontEnd )
				)
				( attribute "CHIPS_PART_NAME" "RES"
					( Origin gPackager )
				)
				( attribute "CDS_PART_NAME" "RES_0402-22.1,1.0%,1/16W,CHIP,A"
					( Origin gPackager )
				)
				( objectStatus "R2T42" )
				( pin "a"
					( attribute "PN" "1"
						( Origin gPackager )
					)
					( objectStatus "R2T42.1" )
				)
				( pin "b"
					( attribute "PN" "2"
						( Origin gPackager )
					)
					( objectStatus "R2T42.2" )
				)
			)
			( gate "@baseboard_fab2_lib.baseboard_fab2(sch_1):page101_i125"
				( attribute "BOM_COST" "SM_CONTROLLER"
					( Origin gFrontEnd )
				)
				( attribute "CDS_LIB" "mstr_discrete"
					( Origin gPackager )
				)
				( attribute "CDS_LOCATION" "R2T46"
					( Origin gPackager )
				)
				( attribute "CDS_SEC" "1"
					( Origin gPackager )
				)
				( attribute "LOCATION" "R2T46"
					( Origin gFrontEnd )
				)
				( attribute "MATERIAL" "CHIP"
					( Origin gFrontEnd )
				)
				( attribute "PACK_TYPE" "0402"
					( Origin gFrontEnd )
				)
				( attribute "PART_NUMBER" "G21796-250"
					( Origin gFrontEnd )
				)
				( attribute "PHYS_PAGE" "101"
					( Origin gFrontEnd )
				)
				( attribute "ROOM" "SYS_CLOCK"
					( Origin gFrontEnd )
				)
				( attribute "ROT" "0"
					( Origin gFrontEnd )
				)
				( attribute "SEC" "1"
					( Origin gFrontEnd )
				)
				( attribute "SEC_TYPE" "0402"
					( Origin gFrontEnd )
				)
				( attribute "TOLERANCE" "1.0%"
					( Origin gFrontEnd )
				)
				( attribute "VALUE" "22.1"
					( Origin gFrontEnd )
				)
				( attribute "VER" "1"
					( Origin gFrontEnd )
				)
				( attribute "WATTAGE" "1/16W"
					( Origin gFrontEnd )
				)
				( attribute "XY" "(-3425,1675)"
					( Origin gFrontEnd )
				)
				( attribute "CHIPS_PART_NAME" "RES"
					( Origin gPackager )
				)
				( attribute "CDS_PART_NAME" "RES_0402-22.1,1.0%,1/16W,CHIP,A"
					( Origin gPackager )
				)
				( objectStatus "R2T46" )
				( pin "a"
					( attribute "PN" "1"
						( Origin gPackager )
					)
					( objectStatus "R2T46.1" )
				)
				( pin "b"
					( attribute "PN" "2"
						( Origin gPackager )
					)
					( objectStatus "R2T46.2" )
				)
			)
			( gate "@baseboard_fab2_lib.baseboard_fab2(sch_1):page101_i129"
				( attribute "BOM_COST" "SM_CONTROLLER"
					( Origin gFrontEnd )
				)
				( attribute "CDS_LIB" "mstr_discrete"
					( Origin gPackager )
				)
				( attribute "CDS_LOCATION" "R8F27"
					( Origin gPackager )
				)
				( attribute "CDS_SEC" "1"
					( Origin gPackager )
				)
				( attribute "LOCATION" "R8F27"
					( Origin gFrontEnd )
				)
				( attribute "MATERIAL" "CHIP"
					( Origin gFrontEnd )
				)
				( attribute "PACK_TYPE" "0402"
					( Origin gFrontEnd )
				)
				( attribute "PART_NUMBER" "G21796-250"
					( Origin gFrontEnd )
				)
				( attribute "PHYS_PAGE" "101"
					( Origin gFrontEnd )
				)
				( attribute "ROOM" "SYS_CLOCK"
					( Origin gFrontEnd )
				)
				( attribute "ROT" "0"
					( Origin gFrontEnd )
				)
				( attribute "SEC" "1"
					( Origin gPackager )
				)
				( attribute "TOLERANCE" "1.0%"
					( Origin gFrontEnd )
				)
				( attribute "VALUE" "22.1"
					( Origin gFrontEnd )
				)
				( attribute "VER" "1"
					( Origin gFrontEnd )
				)
				( attribute "WATTAGE" "1/16W"
					( Origin gFrontEnd )
				)
				( attribute "XY" "(-3425,2750)"
					( Origin gFrontEnd )
				)
				( attribute "CHIPS_PART_NAME" "RES"
					( Origin gPackager )
				)
				( attribute "CDS_PART_NAME" "RES_0402-22.1,1.0%,1/16W,CHIP,A"
					( Origin gPackager )
				)
				( objectStatus "R8F27" )
				( pin "a"
					( attribute "PN" "1"
						( Origin gPackager )
					)
					( objectStatus "R8F27.1" )
				)
				( pin "b"
					( attribute "PN" "2"
						( Origin gPackager )
					)
					( objectStatus "R8F27.2" )
				)
			)
			( gate "@baseboard_fab2_lib.baseboard_fab2(sch_1):page101_i130"
				( attribute "BOM_COST" "SM_CONTROLLER"
					( Origin gFrontEnd )
				)
				( attribute "CDS_LIB" "mstr_discrete"
					( Origin gPackager )
				)
				( attribute "CDS_LOCATION" "R2T47"
					( Origin gPackager )
				)
				( attribute "CDS_SEC" "1"
					( Origin gPackager )
				)
				( attribute "LOCATION" "R2T47"
					( Origin gFrontEnd )
				)
				( attribute "MATERIAL" "CHIP"
					( Origin gFrontEnd )
				)
				( attribute "PACK_TYPE" "0402"
					( Origin gFrontEnd )
				)
				( attribute "PART_NUMBER" "G21796-074"
					( Origin gFrontEnd )
				)
				( attribute "PHYS_PAGE" "101"
					( Origin gFrontEnd )
				)
				( attribute "ROOM" "SYS_CLOCK"
					( Origin gFrontEnd )
				)
				( attribute "ROT" "0"
					( Origin gFrontEnd )
				)
				( attribute "SEC" "1"
					( Origin gFrontEnd )
				)
				( attribute "SEC_TYPE" "0402"
					( Origin gFrontEnd )
				)
				( attribute "TOLERANCE" "1%"
					( Origin gFrontEnd )
				)
				( attribute "VALUE" "33.2"
					( Origin gFrontEnd )
				)
				( attribute "VER" "1"
					( Origin gFrontEnd )
				)
				( attribute "WATTAGE" "1/16W"
					( Origin gFrontEnd )
				)
				( attribute "XY" "(-3425,2575)"
					( Origin gFrontEnd )
				)
				( attribute "CHIPS_PART_NAME" "RES"
					( Origin gPackager )
				)
				( attribute "CDS_PART_NAME" "RES_0402-33.2,1%,1/16W,CHIP,G2A"
					( Origin gPackager )
				)
				( objectStatus "R2T47" )
				( pin "a"
					( attribute "PN" "1"
						( Origin gPackager )
					)
					( objectStatus "R2T47.1" )
				)
				( pin "b"
					( attribute "PN" "2"
						( Origin gPackager )
					)
					( objectStatus "R2T47.2" )
				)
			)
			( gate "@baseboard_fab2_lib.baseboard_fab2(sch_1):page101_i131"
				( attribute "CDS_LIB" "mstr_discrete"
					( Origin gPackager )
				)
				( attribute "CDS_LOCATION" "R8G25"
					( Origin gPackager )
				)
				( attribute "CDS_SEC" "1"
					( Origin gPackager )
				)
				( attribute "LOCATION" "R8G25"
					( Origin gFrontEnd )
				)
				( attribute "MATERIAL" "CHIP"
					( Origin gFrontEnd )
				)
				( attribute "PACK_TYPE" "0402"
					( Origin gFrontEnd )
				)
				( attribute "PART_NUMBER" "G21796-074"
					( Origin gFrontEnd )
				)
				( attribute "PHYS_PAGE" "101"
					( Origin gFrontEnd )
				)
				( attribute "ROT" "0"
					( Origin gFrontEnd )
				)
				( attribute "SEC" "1"
					( Origin gFrontEnd )
				)
				( attribute "SEC_TYPE" "0402"
					( Origin gFrontEnd )
				)
				( attribute "TOLERANCE" "1%"
					( Origin gFrontEnd )
				)
				( attribute "VALUE" "33.2"
					( Origin gFrontEnd )
				)
				( attribute "VER" "1"
					( Origin gFrontEnd )
				)
				( attribute "WATTAGE" "1/16W"
					( Origin gFrontEnd )
				)
				( attribute "XY" "(-3425,1975)"
					( Origin gFrontEnd )
				)
				( attribute "CHIPS_PART_NAME" "RES"
					( Origin gPackager )
				)
				( attribute "CDS_PART_NAME" "RES_0402-33.2,1%,1/16W,CHIP,G2A"
					( Origin gPackager )
				)
				( objectStatus "R8G25" )
				( pin "a"
					( attribute "PN" "1"
						( Origin gPackager )
					)
					( objectStatus "R8G25.1" )
				)
				( pin "b"
					( attribute "PN" "2"
						( Origin gPackager )
					)
					( objectStatus "R8G25.2" )
				)
			)
			( gate "@baseboard_fab2_lib.baseboard_fab2(sch_1):page101_i132"
				( attribute "CDS_LIB" "mstr_discrete"
					( Origin gPackager )
				)
				( attribute "CDS_LOCATION" "R8G24"
					( Origin gPackager )
				)
				( attribute "CDS_SEC" "1"
					( Origin gPackager )
				)
				( attribute "LOCATION" "R8G24"
					( Origin gFrontEnd )
				)
				( attribute "MATERIAL" "CHIP"
					( Origin gFrontEnd )
				)
				( attribute "PACK_TYPE" "0402"
					( Origin gFrontEnd )
				)
				( attribute "PART_NUMBER" "G21796-074"
					( Origin gFrontEnd )
				)
				( attribute "PHYS_PAGE" "101"
					( Origin gFrontEnd )
				)
				( attribute "ROOM" "SB"
					( Origin gFrontEnd )
				)
				( attribute "ROT" "0"
					( Origin gFrontEnd )
				)
				( attribute "SEC" "1"
					( Origin gFrontEnd )
				)
				( attribute "SEC_TYPE" "0402"
					( Origin gFrontEnd )
				)
				( attribute "TOLERANCE" "1%"
					( Origin gFrontEnd )
				)
				( attribute "VALUE" "33.2"
					( Origin gFrontEnd )
				)
				( attribute "VER" "1"
					( Origin gFrontEnd )
				)
				( attribute "WATTAGE" "1/16W"
					( Origin gFrontEnd )
				)
				( attribute "XY" "(-3425,2125)"
					( Origin gFrontEnd )
				)
				( attribute "CHIPS_PART_NAME" "RES"
					( Origin gPackager )
				)
				( attribute "CDS_PART_NAME" "RES_0402-33.2,1%,1/16W,CHIP,G2A"
					( Origin gPackager )
				)
				( objectStatus "R8G24" )
				( pin "a"
					( attribute "PN" "1"
						( Origin gPackager )
					)
					( objectStatus "R8G24.1" )
				)
				( pin "b"
					( attribute "PN" "2"
						( Origin gPackager )
					)
					( objectStatus "R8G24.2" )
				)
			)
			( gate "@baseboard_fab2_lib.baseboard_fab2(sch_1):page101_i133"
				( attribute "CDS_LIB" "mstr_discrete"
					( Origin gPackager )
				)
				( attribute "CDS_LOCATION" "R8G1"
					( Origin gPackager )
				)
				( attribute "CDS_SEC" "1"
					( Origin gPackager )
				)
				( attribute "LOCATION" "R8G1"
					( Origin gFrontEnd )
				)
				( attribute "MATERIAL" "CHIP"
					( Origin gFrontEnd )
				)
				( attribute "PACK_TYPE" "0402"
					( Origin gFrontEnd )
				)
				( attribute "PART_NUMBER" "G21796-074"
					( Origin gFrontEnd )
				)
				( attribute "PHYS_PAGE" "101"
					( Origin gFrontEnd )
				)
				( attribute "ROT" "0"
					( Origin gFrontEnd )
				)
				( attribute "SEC" "1"
					( Origin gPackager )
				)
				( attribute "TOLERANCE" "1%"
					( Origin gFrontEnd )
				)
				( attribute "VALUE" "33.2"
					( Origin gFrontEnd )
				)
				( attribute "VER" "1"
					( Origin gFrontEnd )
				)
				( attribute "WATTAGE" "1/16W"
					( Origin gFrontEnd )
				)
				( attribute "XY" "(-3425,1825)"
					( Origin gFrontEnd )
				)
				( attribute "CHIPS_PART_NAME" "RES"
					( Origin gPackager )
				)
				( attribute "CDS_PART_NAME" "RES_0402-33.2,1%,1/16W,CHIP,G2A"
					( Origin gPackager )
				)
				( objectStatus "R8G1" )
				( pin "a"
					( attribute "PN" "1"
						( Origin gPackager )
					)
					( objectStatus "R8G1.1" )
				)
				( pin "b"
					( attribute "PN" "2"
						( Origin gPackager )
					)
					( objectStatus "R8G1.2" )
				)
			)
			( gate "@baseboard_fab2_lib.baseboard_fab2(sch_1):page102_i1"
				( attribute "BOM_COST" "SYS_CLOCK"
					( Origin gFrontEnd )
				)
				( attribute "CDS_LIB" "mstr_clock"
					( Origin gPackager )
				)
				( attribute "CDS_LMAN_SYM_OUTLINE" "-600,1000,600,-1000"
					( Origin gPackager )
				)
				( attribute "CDS_LOCATION" "EU4D2"
					( Origin gPackager )
				)
				( attribute "CDS_SEC" "1"
					( Origin gPackager )
				)
				( attribute "LOCATION" "EU4D2"
					( Origin gFrontEnd )
				)
				( attribute "MATERIAL" "IC"
					( Origin gFrontEnd )
				)
				( attribute "PACK_TYPE" "LCC"
					( Origin gFrontEnd )
				)
				( attribute "PART_NUMBER" "H13585-001"
					( Origin gFrontEnd )
				)
				( attribute "PHYS_PAGE" "102"
					( Origin gFrontEnd )
				)
				( attribute "ROOM" "DB1200ZL"
					( Origin gFrontEnd )
				)
				( attribute "ROT" "0"
					( Origin gFrontEnd )
				)
				( attribute "SEC" "1"
					( Origin gFrontEnd )
				)
				( attribute "SEC_TYPE" "LCC"
					( Origin gFrontEnd )
				)
				( attribute "VER" "1"
					( Origin gFrontEnd )
				)
				( attribute "XY" "(350,2975)"
					( Origin gFrontEnd )
				)
				( attribute "CHIPS_PART_NAME" "NB3W1200L"
					( Origin gPackager )
				)
				( attribute "CDS_PART_NAME" "NB3W1200L_LCC-IC,H13585-001"
					( Origin gPackager )
				)
				( objectStatus "EU4D2" )
				( pin "\100m_133m_n\"
					( attribute "PN" "4"
						( Origin gPackager )
					)
					( objectStatus "EU4D2.4" )
				)
				( pin "clk_inn"
					( attribute "PN" "10"
						( Origin gPackager )
					)
					( objectStatus "EU4D2.10" )
				)
				( pin "clk_inp"
					( attribute "PN" "9"
						( Origin gPackager )
					)
					( objectStatus "EU4D2.9" )
				)
				( pin "dif_0n"
					( attribute "PN" "18"
						( Origin gPackager )
					)
					( objectStatus "EU4D2.18" )
				)
				( pin "dif_0p"
					( attribute "PN" "17"
						( Origin gPackager )
					)
					( objectStatus "EU4D2.17" )
				)
				( pin "dif_1n"
					( attribute "PN" "22"
						( Origin gPackager )
					)
					( objectStatus "EU4D2.22" )
				)
				( pin "dif_1p"
					( attribute "PN" "21"
						( Origin gPackager )
					)
					( objectStatus "EU4D2.21" )
				)
				( pin "dif_2n"
					( attribute "PN" "27"
						( Origin gPackager )
					)
					( objectStatus "EU4D2.27" )
				)
				( pin "dif_2p"
					( attribute "PN" "26"
						( Origin gPackager )
					)
					( objectStatus "EU4D2.26" )
				)
				( pin "dif_3n"
					( attribute "PN" "31"
						( Origin gPackager )
					)
					( objectStatus "EU4D2.31" )
				)
				( pin "dif_3p"
					( attribute "PN" "30"
						( Origin gPackager )
					)
					( objectStatus "EU4D2.30" )
				)
				( pin "dif_4n"
					( attribute "PN" "35"
						( Origin gPackager )
					)
					( objectStatus "EU4D2.35" )
				)
				( pin "dif_4p"
					( attribute "PN" "34"
						( Origin gPackager )
					)
					( objectStatus "EU4D2.34" )
				)
				( pin "dif_5n"
					( attribute "PN" "39"
						( Origin gPackager )
					)
					( objectStatus "EU4D2.39" )
				)
				( pin "dif_5p"
					( attribute "PN" "38"
						( Origin gPackager )
					)
					( objectStatus "EU4D2.38" )
				)
				( pin "dif_6n"
					( attribute "PN" "43"
						( Origin gPackager )
					)
					( objectStatus "EU4D2.43" )
				)
				( pin "dif_6p"
					( attribute "PN" "42"
						( Origin gPackager )
					)
					( objectStatus "EU4D2.42" )
				)
				( pin "dif_7n"
					( attribute "PN" "47"
						( Origin gPackager )
					)
					( objectStatus "EU4D2.47" )
				)
				( pin "dif_7p"
					( attribute "PN" "46"
						( Origin gPackager )
					)
					( objectStatus "EU4D2.46" )
				)
				( pin "dif_8n"
					( attribute "PN" "51"
						( Origin gPackager )
					)
					( objectStatus "EU4D2.51" )
				)
				( pin "dif_8p"
					( attribute "PN" "50"
						( Origin gPackager )
					)
					( objectStatus "EU4D2.50" )
				)
				( pin "dif_9n"
					( attribute "PN" "55"
						( Origin gPackager )
					)
					( objectStatus "EU4D2.55" )
				)
				( pin "dif_9p"
					( attribute "PN" "54"
						( Origin gPackager )
					)
					( objectStatus "EU4D2.54" )
				)
				( pin "dif_10n"
					( attribute "PN" "60"
						( Origin gPackager )
					)
					( objectStatus "EU4D2.60" )
				)
				( pin "dif_10p"
					( attribute "PN" "59"
						( Origin gPackager )
					)
					( objectStatus "EU4D2.59" )
				)
				( pin "dif_11n"
					( attribute "PN" "64"
						( Origin gPackager )
					)
					( objectStatus "EU4D2.64" )
				)
				( pin "dif_11p"
					( attribute "PN" "63"
						( Origin gPackager )
					)
					( objectStatus "EU4D2.63" )
				)
				( pin "gnd(0)"
					( attribute "PN" "7"
						( Origin gPackager )
					)
					( objectStatus "EU4D2.7" )
				)
				( pin "gnd(1)"
					( attribute "PN" "23"
						( Origin gPackager )
					)
					( objectStatus "EU4D2.23" )
				)
				( pin "gnd(2)"
					( attribute "PN" "33"
						( Origin gPackager )
					)
					( objectStatus "EU4D2.33" )
				)
				( pin "gnd(3)"
					( attribute "PN" "41"
						( Origin gPackager )
					)
					( objectStatus "EU4D2.41" )
				)
				( pin "gnd(4)"
					( attribute "PN" "48"
						( Origin gPackager )
					)
					( objectStatus "EU4D2.48" )
				)
				( pin "gnd(5)"
					( attribute "PN" "58"
						( Origin gPackager )
					)
					( objectStatus "EU4D2.58" )
				)
				( pin "gnda"
					( attribute "PN" "2"
						( Origin gPackager )
					)
					( objectStatus "EU4D2.2" )
				)
				( pin "hbw_bypass_lobw_n"
					( attribute "PN" "5"
						( Origin gPackager )
					)
					( objectStatus "EU4D2.5" )
				)
				( pin "nc(0)"
					( attribute "PN" "3"
						( Origin gPackager )
					)
					( objectStatus "EU4D2.3" )
				)
				( pin "nc(1)"
					( attribute "PN" "16"
						( Origin gPackager )
					)
					( objectStatus "EU4D2.16" )
				)
				( pin "nc(2)"
					( attribute "PN" "15"
						( Origin gPackager )
					)
					( objectStatus "EU4D2.15" )
				)
				( pin "oe_0_n"
					( attribute "PN" "19"
						( Origin gPackager )
					)
					( objectStatus "EU4D2.19" )
				)
				( pin "oe_1_n"
					( attribute "PN" "20"
						( Origin gPackager )
					)
					( objectStatus "EU4D2.20" )
				)
				( pin "oe_2_n"
					( attribute "PN" "28"
						( Origin gPackager )
					)
					( objectStatus "EU4D2.28" )
				)
				( pin "oe_3_n"
					( attribute "PN" "29"
						( Origin gPackager )
					)
					( objectStatus "EU4D2.29" )
				)
				( pin "oe_4_n"
					( attribute "PN" "36"
						( Origin gPackager )
					)
					( objectStatus "EU4D2.36" )
				)
				( pin "oe_5_n"
					( attribute "PN" "37"
						( Origin gPackager )
					)
					( objectStatus "EU4D2.37" )
				)
				( pin "oe_6_n"
					( attribute "PN" "44"
						( Origin gPackager )
					)
					( objectStatus "EU4D2.44" )
				)
				( pin "oe_7_n"
					( attribute "PN" "45"
						( Origin gPackager )
					)
					( objectStatus "EU4D2.45" )
				)
				( pin "oe_8_n"
					( attribute "PN" "52"
						( Origin gPackager )
					)
					( objectStatus "EU4D2.52" )
				)
				( pin "oe_9_n"
					( attribute "PN" "53"
						( Origin gPackager )
					)
					( objectStatus "EU4D2.53" )
				)
				( pin "oe_10_n"
					( attribute "PN" "61"
						( Origin gPackager )
					)
					( objectStatus "EU4D2.61" )
				)
				( pin "oe_11_n"
					( attribute "PN" "62"
						( Origin gPackager )
					)
					( objectStatus "EU4D2.62" )
				)
				( pin "pwrgd_pwrdn_n"
					( attribute "PN" "6"
						( Origin gPackager )
					)
					( objectStatus "EU4D2.6" )
				)
				( pin "sa_0"
					( attribute "PN" "11"
						( Origin gPackager )
					)
					( objectStatus "EU4D2.11" )
				)
				( pin "sa_1"
					( attribute "PN" "14"
						( Origin gPackager )
					)
					( objectStatus "EU4D2.14" )
				)
				( pin "scl"
					( attribute "PN" "13"
						( Origin gPackager )
					)
					( objectStatus "EU4D2.13" )
				)
				( pin "sda"
					( attribute "PN" "12"
						( Origin gPackager )
					)
					( objectStatus "EU4D2.12" )
				)
				( pin "thpad"
					( attribute "PN" "65"
						( Origin gPackager )
					)
					( objectStatus "EU4D2.65" )
				)
				( pin "vdd(0)"
					( attribute "PN" "24"
						( Origin gPackager )
					)
					( objectStatus "EU4D2.24" )
				)
				( pin "vdd(1)"
					( attribute "PN" "40"
						( Origin gPackager )
					)
					( objectStatus "EU4D2.40" )
				)
				( pin "vdd(2)"
					( attribute "PN" "57"
						( Origin gPackager )
					)
					( objectStatus "EU4D2.57" )
				)
				( pin "vdda"
					( attribute "PN" "1"
						( Origin gPackager )
					)
					( objectStatus "EU4D2.1" )
				)
				( pin "vddio(0)"
					( attribute "PN" "25"
						( Origin gPackager )
					)
					( objectStatus "EU4D2.25" )
				)
				( pin "vddio(1)"
					( attribute "PN" "32"
						( Origin gPackager )
					)
					( objectStatus "EU4D2.32" )
				)
				( pin "vddio(2)"
					( attribute "PN" "49"
						( Origin gPackager )
					)
					( objectStatus "EU4D2.49" )
				)
				( pin "vddio(3)"
					( attribute "PN" "56"
						( Origin gPackager )
					)
					( objectStatus "EU4D2.56" )
				)
				( pin "vddr"
					( attribute "PN" "8"
						( Origin gPackager )
					)
					( objectStatus "EU4D2.8" )
				)
			)
			( gate "@baseboard_fab2_lib.baseboard_fab2(sch_1):page102_i8"
				( attribute "BOM_COST" "SYS_CLOCK"
					( Origin gFrontEnd )
				)
				( attribute "CDS_LIB" "mstr_discrete"
					( Origin gPackager )
				)
				( attribute "CDS_LOCATION" "FB6P1"
					( Origin gPackager )
				)
				( attribute "CDS_SEC" "1"
					( Origin gPackager )
				)
				( attribute "LOCATION" "FB6P1"
					( Origin gFrontEnd )
				)
				( attribute "MATERIAL" "FB"
					( Origin gFrontEnd )
				)
				( attribute "PACK_TYPE" "SMLF"
					( Origin gFrontEnd )
				)
				( attribute "PART_NUMBER" "656554-043"
					( Origin gFrontEnd )
				)
				( attribute "PHYS_PAGE" "102"
					( Origin gFrontEnd )
				)
				( attribute "ROOM" "DB1200ZL"
					( Origin gFrontEnd )
				)
				( attribute "ROT" "0"
					( Origin gFrontEnd )
				)
				( attribute "SEC" "1"
					( Origin gFrontEnd )
				)
				( attribute "SEC_TYPE" "SMLF"
					( Origin gFrontEnd )
				)
				( attribute "VALUE" "600"
					( Origin gFrontEnd )
				)
				( attribute "VER" "1"
					( Origin gFrontEnd )
				)
				( attribute "XY" "(1700,1200)"
					( Origin gFrontEnd )
				)
				( attribute "CHIPS_PART_NAME" "FERRITE"
					( Origin gPackager )
				)
				( attribute "CDS_PART_NAME" "FERRITE_SMLF-600,FB,656554-043"
					( Origin gPackager )
				)
				( objectStatus "FB6P1" )
				( pin "a"
					( attribute "PN" "1"
						( Origin gPackager )
					)
					( objectStatus "FB6P1.1" )
				)
				( pin "b"
					( attribute "PN" "2"
						( Origin gPackager )
					)
					( objectStatus "FB6P1.2" )
				)
			)
			( gate "@baseboard_fab2_lib.baseboard_fab2(sch_1):page102_i10"
				( attribute "BOM_COST" "SYS_CLOCK"
					( Origin gFrontEnd )
				)
				( attribute "CDS_LIB" "mstr_discrete"
					( Origin gPackager )
				)
				( attribute "CDS_LOCATION" "C3D22"
					( Origin gPackager )
				)
				( attribute "CDS_SEC" "1"
					( Origin gPackager )
				)
				( attribute "LOCATION" "C3D22"
					( Origin gFrontEnd )
				)
				( attribute "MATERIAL" "X7R"
					( Origin gFrontEnd )
				)
				( attribute "PACK_TYPE" "0805"
					( Origin gFrontEnd )
				)
				( attribute "PART_NUMBER" "G10601-001"
					( Origin gFrontEnd )
				)
				( attribute "PHYS_PAGE" "102"
					( Origin gFrontEnd )
				)
				( attribute "ROOM" "DB1200ZL"
					( Origin gFrontEnd )
				)
				( attribute "ROT" "0"
					( Origin gFrontEnd )
				)
				( attribute "SEC" "1"
					( Origin gFrontEnd )
				)
				( attribute "SEC_TYPE" "0805"
					( Origin gFrontEnd )
				)
				( attribute "TOLERANCE" "10%"
					( Origin gFrontEnd )
				)
				( attribute "VALUE" "10UF"
					( Origin gFrontEnd )
				)
				( attribute "VER" "1"
					( Origin gFrontEnd )
				)
				( attribute "VOLTAGE" "16V"
					( Units "uVoltage" "V" 1.000000)
					( Origin gFrontEnd )
				)
				( attribute "XY" "(1975,975)"
					( Origin gFrontEnd )
				)
				( attribute "CHIPS_PART_NAME" "CAP"
					( Origin gPackager )
				)
				( attribute "CDS_PART_NAME" "CAP_0805-10UF,16V,10%,X7R,G106A"
					( Origin gPackager )
				)
				( objectStatus "C3D22" )
				( pin "a"
					( attribute "PN" "1"
						( Origin gPackager )
					)
					( objectStatus "C3D22.1" )
				)
				( pin "b"
					( attribute "PN" "2"
						( Origin gPackager )
					)
					( objectStatus "C3D22.2" )
				)
			)
			( gate "@baseboard_fab2_lib.baseboard_fab2(sch_1):page102_i11"
				( attribute "BOM_COST" "SYS_CLOCK"
					( Origin gFrontEnd )
				)
				( attribute "CDS_LIB" "dev_discrete"
					( Origin gPackager )
				)
				( attribute "CDS_LOCATION" "C6P4"
					( Origin gPackager )
				)
				( attribute "CDS_SEC" "1"
					( Origin gPackager )
				)
				( attribute "LOCATION" "C6P4"
					( Origin gFrontEnd )
				)
				( attribute "MATERIAL" "X7R"
					( Origin gFrontEnd )
				)
				( attribute "PACK_TYPE" "0402V"
					( Origin gFrontEnd )
				)
				( attribute "PART_NUMBER" "A36096-030"
					( Origin gFrontEnd )
				)
				( attribute "PHYS_PAGE" "102"
					( Origin gFrontEnd )
				)
				( attribute "ROOM" "DB1200ZL"
					( Origin gFrontEnd )
				)
				( attribute "ROT" "0"
					( Origin gFrontEnd )
				)
				( attribute "SEC" "1"
					( Origin gFrontEnd )
				)
				( attribute "SEC_TYPE" "0402V"
					( Origin gFrontEnd )
				)
				( attribute "TOLERANCE" "10%"
					( Origin gFrontEnd )
				)
				( attribute "VALUE" "0.1UF"
					( Origin gFrontEnd )
				)
				( attribute "VER" "1"
					( Origin gFrontEnd )
				)
				( attribute "VOLTAGE" "16V"
					( Units "uVoltage" "V" 1.000000)
					( Origin gFrontEnd )
				)
				( attribute "XY" "(2575,975)"
					( Origin gFrontEnd )
				)
				( attribute "CHIPS_PART_NAME" "CAP_A"
					( Origin gPackager )
				)
				( attribute "CDS_PART_NAME" "CAP_A_0402V-0.1UF,16V,10%,X7R,A"
					( Origin gPackager )
				)
				( objectStatus "C6P4" )
				( pin "a"
					( attribute "PN" "1"
						( Origin gPackager )
					)
					( objectStatus "C6P4.1" )
				)
				( pin "b"
					( attribute "PN" "2"
						( Origin gPackager )
					)
					( objectStatus "C6P4.2" )
				)
			)
			( gate "@baseboard_fab2_lib.baseboard_fab2(sch_1):page102_i12"
				( attribute "BOM_COST" "SYS_CLOCK"
					( Origin gFrontEnd )
				)
				( attribute "CDS_LIB" "dev_discrete"
					( Origin gPackager )
				)
				( attribute "CDS_LOCATION" "C6P6"
					( Origin gPackager )
				)
				( attribute "CDS_SEC" "1"
					( Origin gPackager )
				)
				( attribute "LOCATION" "C6P6"
					( Origin gFrontEnd )
				)
				( attribute "MATERIAL" "X7R"
					( Origin gFrontEnd )
				)
				( attribute "PACK_TYPE" "0402V"
					( Origin gFrontEnd )
				)
				( attribute "PART_NUMBER" "A36096-030"
					( Origin gFrontEnd )
				)
				( attribute "PHYS_PAGE" "102"
					( Origin gFrontEnd )
				)
				( attribute "ROOM" "DB1200ZL"
					( Origin gFrontEnd )
				)
				( attribute "ROT" "0"
					( Origin gFrontEnd )
				)
				( attribute "SEC" "1"
					( Origin gFrontEnd )
				)
				( attribute "SEC_TYPE" "0402V"
					( Origin gFrontEnd )
				)
				( attribute "TOLERANCE" "10%"
					( Origin gFrontEnd )
				)
				( attribute "VALUE" "0.1UF"
					( Origin gFrontEnd )
				)
				( attribute "VER" "1"
					( Origin gFrontEnd )
				)
				( attribute "VOLTAGE" "16V"
					( Units "uVoltage" "V" 1.000000)
					( Origin gFrontEnd )
				)
				( attribute "XY" "(2825,975)"
					( Origin gFrontEnd )
				)
				( attribute "CHIPS_PART_NAME" "CAP_A"
					( Origin gPackager )
				)
				( attribute "CDS_PART_NAME" "CAP_A_0402V-0.1UF,16V,10%,X7R,A"
					( Origin gPackager )
				)
				( objectStatus "C6P6" )
				( pin "a"
					( attribute "PN" "1"
						( Origin gPackager )
					)
					( objectStatus "C6P6.1" )
				)
				( pin "b"
					( attribute "PN" "2"
						( Origin gPackager )
					)
					( objectStatus "C6P6.2" )
				)
			)
			( gate "@baseboard_fab2_lib.baseboard_fab2(sch_1):page102_i13"
				( attribute "BOM_COST" "SYS_CLOCK"
					( Origin gFrontEnd )
				)
				( attribute "CDS_LIB" "dev_discrete"
					( Origin gPackager )
				)
				( attribute "CDS_LOCATION" "C6P10"
					( Origin gPackager )
				)
				( attribute "CDS_SEC" "1"
					( Origin gPackager )
				)
				( attribute "LOCATION" "C6P10"
					( Origin gFrontEnd )
				)
				( attribute "MATERIAL" "X7R"
					( Origin gFrontEnd )
				)
				( attribute "PACK_TYPE" "0402V"
					( Origin gFrontEnd )
				)
				( attribute "PART_NUMBER" "A36096-030"
					( Origin gFrontEnd )
				)
				( attribute "PHYS_PAGE" "102"
					( Origin gFrontEnd )
				)
				( attribute "ROOM" "DB1200ZL"
					( Origin gFrontEnd )
				)
				( attribute "ROT" "0"
					( Origin gFrontEnd )
				)
				( attribute "SEC" "1"
					( Origin gFrontEnd )
				)
				( attribute "SEC_TYPE" "0402V"
					( Origin gFrontEnd )
				)
				( attribute "TOLERANCE" "10%"
					( Origin gFrontEnd )
				)
				( attribute "VALUE" "0.1UF"
					( Origin gFrontEnd )
				)
				( attribute "VER" "1"
					( Origin gFrontEnd )
				)
				( attribute "VOLTAGE" "16V"
					( Units "uVoltage" "V" 1.000000)
					( Origin gFrontEnd )
				)
				( attribute "XY" "(3050,975)"
					( Origin gFrontEnd )
				)
				( attribute "CHIPS_PART_NAME" "CAP_A"
					( Origin gPackager )
				)
				( attribute "CDS_PART_NAME" "CAP_A_0402V-0.1UF,16V,10%,X7R,A"
					( Origin gPackager )
				)
				( objectStatus "C6P10" )
				( pin "a"
					( attribute "PN" "1"
						( Origin gPackager )
					)
					( objectStatus "C6P10.1" )
				)
				( pin "b"
					( attribute "PN" "2"
						( Origin gPackager )
					)
					( objectStatus "C6P10.2" )
				)
			)
			( gate "@baseboard_fab2_lib.baseboard_fab2(sch_1):page102_i14"
				( attribute "BOM_COST" "SYS_CLOCK"
					( Origin gFrontEnd )
				)
				( attribute "CDS_LIB" "dev_discrete"
					( Origin gPackager )
				)
				( attribute "CDS_LOCATION" "C6P5"
					( Origin gPackager )
				)
				( attribute "CDS_SEC" "1"
					( Origin gPackager )
				)
				( attribute "LOCATION" "C6P5"
					( Origin gFrontEnd )
				)
				( attribute "MATERIAL" "X7R"
					( Origin gFrontEnd )
				)
				( attribute "PACK_TYPE" "0402V"
					( Origin gFrontEnd )
				)
				( attribute "PART_NUMBER" "A36096-030"
					( Origin gFrontEnd )
				)
				( attribute "PHYS_PAGE" "102"
					( Origin gFrontEnd )
				)
				( attribute "ROOM" "DB1200ZL"
					( Origin gFrontEnd )
				)
				( attribute "ROT" "0"
					( Origin gFrontEnd )
				)
				( attribute "SEC" "1"
					( Origin gFrontEnd )
				)
				( attribute "SEC_TYPE" "0402V"
					( Origin gFrontEnd )
				)
				( attribute "TOLERANCE" "10%"
					( Origin gFrontEnd )
				)
				( attribute "VALUE" "0.1UF"
					( Origin gFrontEnd )
				)
				( attribute "VER" "1"
					( Origin gFrontEnd )
				)
				( attribute "VOLTAGE" "16V"
					( Units "uVoltage" "V" 1.000000)
					( Origin gFrontEnd )
				)
				( attribute "XY" "(3275,975)"
					( Origin gFrontEnd )
				)
				( attribute "CHIPS_PART_NAME" "CAP_A"
					( Origin gPackager )
				)
				( attribute "CDS_PART_NAME" "CAP_A_0402V-0.1UF,16V,10%,X7R,A"
					( Origin gPackager )
				)
				( objectStatus "C6P5" )
				( pin "a"
					( attribute "PN" "1"
						( Origin gPackager )
					)
					( objectStatus "C6P5.1" )
				)
				( pin "b"
					( attribute "PN" "2"
						( Origin gPackager )
					)
					( objectStatus "C6P5.2" )
				)
			)
			( gate "@baseboard_fab2_lib.baseboard_fab2(sch_1):page102_i15"
				( attribute "BOM_COST" "SYS_CLOCK"
					( Origin gFrontEnd )
				)
				( attribute "CDS_LIB" "dev_discrete"
					( Origin gPackager )
				)
				( attribute "CDS_LOCATION" "C6P12"
					( Origin gPackager )
				)
				( attribute "CDS_SEC" "1"
					( Origin gPackager )
				)
				( attribute "LOCATION" "C6P12"
					( Origin gFrontEnd )
				)
				( attribute "MATERIAL" "X7R"
					( Origin gFrontEnd )
				)
				( attribute "PACK_TYPE" "0402V"
					( Origin gFrontEnd )
				)
				( attribute "PART_NUMBER" "A36096-030"
					( Origin gFrontEnd )
				)
				( attribute "PHYS_PAGE" "102"
					( Origin gFrontEnd )
				)
				( attribute "ROOM" "DB1200ZL"
					( Origin gFrontEnd )
				)
				( attribute "ROT" "0"
					( Origin gFrontEnd )
				)
				( attribute "SEC" "1"
					( Origin gFrontEnd )
				)
				( attribute "SEC_TYPE" "0402V"
					( Origin gFrontEnd )
				)
				( attribute "TOLERANCE" "10%"
					( Origin gFrontEnd )
				)
				( attribute "VALUE" "0.1UF"
					( Origin gFrontEnd )
				)
				( attribute "VER" "1"
					( Origin gFrontEnd )
				)
				( attribute "VOLTAGE" "16V"
					( Units "uVoltage" "V" 1.000000)
					( Origin gFrontEnd )
				)
				( attribute "XY" "(3475,975)"
					( Origin gFrontEnd )
				)
				( attribute "CHIPS_PART_NAME" "CAP_A"
					( Origin gPackager )
				)
				( attribute "CDS_PART_NAME" "CAP_A_0402V-0.1UF,16V,10%,X7R,A"
					( Origin gPackager )
				)
				( objectStatus "C6P12" )
				( pin "a"
					( attribute "PN" "1"
						( Origin gPackager )
					)
					( objectStatus "C6P12.1" )
				)
				( pin "b"
					( attribute "PN" "2"
						( Origin gPackager )
					)
					( objectStatus "C6P12.2" )
				)
			)
			( gate "@baseboard_fab2_lib.baseboard_fab2(sch_1):page102_i16"
				( attribute "BOM_COST" "SYS_CLOCK"
					( Origin gFrontEnd )
				)
				( attribute "CDS_LIB" "dev_discrete"
					( Origin gPackager )
				)
				( attribute "CDS_LOCATION" "C6P11"
					( Origin gPackager )
				)
				( attribute "CDS_SEC" "1"
					( Origin gPackager )
				)
				( attribute "LOCATION" "C6P11"
					( Origin gFrontEnd )
				)
				( attribute "MATERIAL" "X7R"
					( Origin gFrontEnd )
				)
				( attribute "PACK_TYPE" "0402V"
					( Origin gFrontEnd )
				)
				( attribute "PART_NUMBER" "A36096-030"
					( Origin gFrontEnd )
				)
				( attribute "PHYS_PAGE" "102"
					( Origin gFrontEnd )
				)
				( attribute "ROOM" "DB1200ZL"
					( Origin gFrontEnd )
				)
				( attribute "ROT" "0"
					( Origin gFrontEnd )
				)
				( attribute "SEC" "1"
					( Origin gFrontEnd )
				)
				( attribute "SEC_TYPE" "0402V"
					( Origin gFrontEnd )
				)
				( attribute "TOLERANCE" "10%"
					( Origin gFrontEnd )
				)
				( attribute "VALUE" "0.1UF"
					( Origin gFrontEnd )
				)
				( attribute "VER" "1"
					( Origin gFrontEnd )
				)
				( attribute "VOLTAGE" "16V"
					( Units "uVoltage" "V" 1.000000)
					( Origin gFrontEnd )
				)
				( attribute "XY" "(3700,975)"
					( Origin gFrontEnd )
				)
				( attribute "CHIPS_PART_NAME" "CAP_A"
					( Origin gPackager )
				)
				( attribute "CDS_PART_NAME" "CAP_A_0402V-0.1UF,16V,10%,X7R,A"
					( Origin gPackager )
				)
				( objectStatus "C6P11" )
				( pin "a"
					( attribute "PN" "1"
						( Origin gPackager )
					)
					( objectStatus "C6P11.1" )
				)
				( pin "b"
					( attribute "PN" "2"
						( Origin gPackager )
					)
					( objectStatus "C6P11.2" )
				)
			)
			( gate "@baseboard_fab2_lib.baseboard_fab2(sch_1):page102_i18"
				( attribute "BOM_COST" "SYS_CLOCK"
					( Origin gFrontEnd )
				)
				( attribute "CDS_LIB" "dev_discrete"
					( Origin gPackager )
				)
				( attribute "CDS_LOCATION" "C4D24"
					( Origin gPackager )
				)
				( attribute "CDS_SEC" "1"
					( Origin gPackager )
				)
				( attribute "LOCATION" "C4D24"
					( Origin gFrontEnd )
				)
				( attribute "MATERIAL" "X7R"
					( Origin gFrontEnd )
				)
				( attribute "PACK_TYPE" "0402V"
					( Origin gFrontEnd )
				)
				( attribute "PART_NUMBER" "A36096-030"
					( Origin gFrontEnd )
				)
				( attribute "PHYS_PAGE" "102"
					( Origin gFrontEnd )
				)
				( attribute "ROOM" "DB1200ZL"
					( Origin gFrontEnd )
				)
				( attribute "ROT" "0"
					( Origin gFrontEnd )
				)
				( attribute "SEC" "1"
					( Origin gFrontEnd )
				)
				( attribute "SEC_TYPE" "0402V"
					( Origin gFrontEnd )
				)
				( attribute "TOLERANCE" "10%"
					( Origin gFrontEnd )
				)
				( attribute "VALUE" "0.1UF"
					( Origin gFrontEnd )
				)
				( attribute "VER" "1"
					( Origin gFrontEnd )
				)
				( attribute "VOLTAGE" "16V"
					( Units "uVoltage" "V" 1.000000)
					( Origin gFrontEnd )
				)
				( attribute "XY" "(-1550,3975)"
					( Origin gFrontEnd )
				)
				( attribute "CHIPS_PART_NAME" "CAP_A"
					( Origin gPackager )
				)
				( attribute "CDS_PART_NAME" "CAP_A_0402V-0.1UF,16V,10%,X7R,A"
					( Origin gPackager )
				)
				( objectStatus "C4D24" )
				( pin "a"
					( attribute "PN" "1"
						( Origin gPackager )
					)
					( objectStatus "C4D24.1" )
				)
				( pin "b"
					( attribute "PN" "2"
						( Origin gPackager )
					)
					( objectStatus "C4D24.2" )
				)
			)
			( gate "@baseboard_fab2_lib.baseboard_fab2(sch_1):page102_i19"
				( attribute "BOM_COST" "SYS_CLOCK"
					( Origin gFrontEnd )
				)
				( attribute "CDS_LIB" "dev_discrete"
					( Origin gPackager )
				)
				( attribute "CDS_LOCATION" "C4D23"
					( Origin gPackager )
				)
				( attribute "CDS_SEC" "1"
					( Origin gPackager )
				)
				( attribute "LOCATION" "C4D23"
					( Origin gFrontEnd )
				)
				( attribute "MATERIAL" "X6S"
					( Origin gFrontEnd )
				)
				( attribute "PACK_TYPE" "0402V"
					( Origin gFrontEnd )
				)
				( attribute "PART_NUMBER" "D97712-004"
					( Origin gFrontEnd )
				)
				( attribute "PHYS_PAGE" "102"
					( Origin gFrontEnd )
				)
				( attribute "ROOM" "DB1200ZL"
					( Origin gFrontEnd )
				)
				( attribute "ROT" "0"
					( Origin gFrontEnd )
				)
				( attribute "SEC" "1"
					( Origin gFrontEnd )
				)
				( attribute "SEC_TYPE" "0402V"
					( Origin gFrontEnd )
				)
				( attribute "TOLERANCE" "10%"
					( Origin gFrontEnd )
				)
				( attribute "VALUE" "1.0UF"
					( Origin gFrontEnd )
				)
				( attribute "VER" "1"
					( Origin gFrontEnd )
				)
				( attribute "VOLTAGE" "6.3V"
					( Units "uVoltage" "V" 1.000000)
					( Origin gFrontEnd )
				)
				( attribute "XY" "(-1800,3975)"
					( Origin gFrontEnd )
				)
				( attribute "CHIPS_PART_NAME" "CAP_A"
					( Origin gPackager )
				)
				( attribute "CDS_PART_NAME" "CAP_A_0402V-1.0UF,6.3V,10%,X6SA"
					( Origin gPackager )
				)
				( objectStatus "C4D23" )
				( pin "a"
					( attribute "PN" "1"
						( Origin gPackager )
					)
					( objectStatus "C4D23.1" )
				)
				( pin "b"
					( attribute "PN" "2"
						( Origin gPackager )
					)
					( objectStatus "C4D23.2" )
				)
			)
			( gate "@baseboard_fab2_lib.baseboard_fab2(sch_1):page102_i21"
				( attribute "BOM_COST" "SYS_CLOCK"
					( Origin gFrontEnd )
				)
				( attribute "CDS_LIB" "mstr_discrete"
					( Origin gPackager )
				)
				( attribute "CDS_LOCATION" "R3D14"
					( Origin gPackager )
				)
				( attribute "CDS_SEC" "1"
					( Origin gPackager )
				)
				( attribute "LOCATION" "R3D14"
					( Origin gFrontEnd )
				)
				( attribute "MATERIAL" "CHIP"
					( Origin gFrontEnd )
				)
				( attribute "PACK_TYPE" "0603"
					( Origin gFrontEnd )
				)
				( attribute "PART_NUMBER" "G22026-127"
					( Origin gFrontEnd )
				)
				( attribute "PHYS_PAGE" "102"
					( Origin gFrontEnd )
				)
				( attribute "ROOM" "DB1200ZL"
					( Origin gFrontEnd )
				)
				( attribute "ROT" "0"
					( Origin gFrontEnd )
				)
				( attribute "SEC" "1"
					( Origin gFrontEnd )
				)
				( attribute "SEC_TYPE" "0603"
					( Origin gFrontEnd )
				)
				( attribute "TOLERANCE" "1.0%"
					( Origin gFrontEnd )
				)
				( attribute "VALUE" "2.2"
					( Origin gFrontEnd )
				)
				( attribute "VER" "1"
					( Origin gFrontEnd )
				)
				( attribute "WATTAGE" "1/10W"
					( Origin gFrontEnd )
				)
				( attribute "XY" "(-2425,4200)"
					( Origin gFrontEnd )
				)
				( attribute "CHIPS_PART_NAME" "RES"
					( Origin gPackager )
				)
				( attribute "CDS_PART_NAME" "RES_0603-2.2,1.0%,1/10W,CHIP,GA"
					( Origin gPackager )
				)
				( objectStatus "R3D14" )
				( pin "a"
					( attribute "PN" "1"
						( Origin gPackager )
					)
					( objectStatus "R3D14.1" )
				)
				( pin "b"
					( attribute "PN" "2"
						( Origin gPackager )
					)
					( objectStatus "R3D14.2" )
				)
			)
			( gate "@baseboard_fab2_lib.baseboard_fab2(sch_1):page102_i26"
				( attribute "BOM_COST" "SYS_CLOCK"
					( Origin gFrontEnd )
				)
				( attribute "CDS_LIB" "mstr_discrete"
					( Origin gPackager )
				)
				( attribute "CDS_LOCATION" "R6P25"
					( Origin gPackager )
				)
				( attribute "CDS_SEC" "1"
					( Origin gPackager )
				)
				( attribute "LOCATION" "R6P25"
					( Origin gFrontEnd )
				)
				( attribute "MATERIAL" "CHIP"
					( Origin gFrontEnd )
				)
				( attribute "PACK_TYPE" "0603"
					( Origin gFrontEnd )
				)
				( attribute "PART_NUMBER" "G22026-127"
					( Origin gFrontEnd )
				)
				( attribute "PHYS_PAGE" "102"
					( Origin gFrontEnd )
				)
				( attribute "ROOM" "DB1200ZL"
					( Origin gFrontEnd )
				)
				( attribute "ROT" "0"
					( Origin gFrontEnd )
				)
				( attribute "SEC" "1"
					( Origin gFrontEnd )
				)
				( attribute "SEC_TYPE" "0603"
					( Origin gFrontEnd )
				)
				( attribute "TOLERANCE" "1.0%"
					( Origin gFrontEnd )
				)
				( attribute "VALUE" "2.2"
					( Origin gFrontEnd )
				)
				( attribute "VER" "1"
					( Origin gFrontEnd )
				)
				( attribute "WATTAGE" "1/10W"
					( Origin gFrontEnd )
				)
				( attribute "XY" "(-2825,3475)"
					( Origin gFrontEnd )
				)
				( attribute "CHIPS_PART_NAME" "RES"
					( Origin gPackager )
				)
				( attribute "CDS_PART_NAME" "RES_0603-2.2,1.0%,1/10W,CHIP,GA"
					( Origin gPackager )
				)
				( objectStatus "R6P25" )
				( pin "a"
					( attribute "PN" "1"
						( Origin gPackager )
					)
					( objectStatus "R6P25.1" )
				)
				( pin "b"
					( attribute "PN" "2"
						( Origin gPackager )
					)
					( objectStatus "R6P25.2" )
				)
			)
			( gate "@baseboard_fab2_lib.baseboard_fab2(sch_1):page102_i28"
				( attribute "BOM_COST" "SYS_CLOCK"
					( Origin gFrontEnd )
				)
				( attribute "CDS_LIB" "dev_discrete"
					( Origin gPackager )
				)
				( attribute "CDS_LOCATION" "C4D22"
					( Origin gPackager )
				)
				( attribute "CDS_SEC" "1"
					( Origin gPackager )
				)
				( attribute "LOCATION" "C4D22"
					( Origin gFrontEnd )
				)
				( attribute "MATERIAL" "X7R"
					( Origin gFrontEnd )
				)
				( attribute "PACK_TYPE" "0402V"
					( Origin gFrontEnd )
				)
				( attribute "PART_NUMBER" "A36096-030"
					( Origin gFrontEnd )
				)
				( attribute "PHYS_PAGE" "102"
					( Origin gFrontEnd )
				)
				( attribute "ROOM" "DB1200ZL"
					( Origin gFrontEnd )
				)
				( attribute "ROT" "0"
					( Origin gFrontEnd )
				)
				( attribute "SEC" "1"
					( Origin gFrontEnd )
				)
				( attribute "SEC_TYPE" "0402V"
					( Origin gFrontEnd )
				)
				( attribute "TOLERANCE" "10%"
					( Origin gFrontEnd )
				)
				( attribute "VALUE" "0.1UF"
					( Origin gFrontEnd )
				)
				( attribute "VER" "1"
					( Origin gFrontEnd )
				)
				( attribute "VOLTAGE" "16V"
					( Units "uVoltage" "V" 1.000000)
					( Origin gFrontEnd )
				)
				( attribute "XY" "(-2325,3300)"
					( Origin gFrontEnd )
				)
				( attribute "CHIPS_PART_NAME" "CAP_A"
					( Origin gPackager )
				)
				( attribute "CDS_PART_NAME" "CAP_A_0402V-0.1UF,16V,10%,X7R,A"
					( Origin gPackager )
				)
				( objectStatus "C4D22" )
				( pin "a"
					( attribute "PN" "1"
						( Origin gPackager )
					)
					( objectStatus "C4D22.1" )
				)
				( pin "b"
					( attribute "PN" "2"
						( Origin gPackager )
					)
					( objectStatus "C4D22.2" )
				)
			)
			( gate "@baseboard_fab2_lib.baseboard_fab2(sch_1):page102_i30"
				( attribute "BOM_COST" "SYS_CLOCK"
					( Origin gFrontEnd )
				)
				( attribute "CDS_LIB" "dev_discrete"
					( Origin gPackager )
				)
				( attribute "CDS_LOCATION" "C4D27"
					( Origin gPackager )
				)
				( attribute "CDS_SEC" "1"
					( Origin gPackager )
				)
				( attribute "LOCATION" "C4D27"
					( Origin gFrontEnd )
				)
				( attribute "MATERIAL" "X6S"
					( Origin gFrontEnd )
				)
				( attribute "PACK_TYPE" "0402V"
					( Origin gFrontEnd )
				)
				( attribute "PART_NUMBER" "D97712-004"
					( Origin gFrontEnd )
				)
				( attribute "PHYS_PAGE" "102"
					( Origin gFrontEnd )
				)
				( attribute "ROOM" "DB1200ZL"
					( Origin gFrontEnd )
				)
				( attribute "ROT" "0"
					( Origin gFrontEnd )
				)
				( attribute "SEC" "1"
					( Origin gFrontEnd )
				)
				( attribute "SEC_TYPE" "0402V"
					( Origin gFrontEnd )
				)
				( attribute "TOLERANCE" "10%"
					( Origin gFrontEnd )
				)
				( attribute "VALUE" "1.0UF"
					( Origin gFrontEnd )
				)
				( attribute "VER" "1"
					( Origin gFrontEnd )
				)
				( attribute "VOLTAGE" "6.3V"
					( Units "uVoltage" "V" 1.000000)
					( Origin gFrontEnd )
				)
				( attribute "XY" "(-2575,3300)"
					( Origin gFrontEnd )
				)
				( attribute "CHIPS_PART_NAME" "CAP_A"
					( Origin gPackager )
				)
				( attribute "CDS_PART_NAME" "CAP_A_0402V-1.0UF,6.3V,10%,X6SA"
					( Origin gPackager )
				)
				( objectStatus "C4D27" )
				( pin "a"
					( attribute "PN" "1"
						( Origin gPackager )
					)
					( objectStatus "C4D27.1" )
				)
				( pin "b"
					( attribute "PN" "2"
						( Origin gPackager )
					)
					( objectStatus "C4D27.2" )
				)
			)
			( gate "@baseboard_fab2_lib.baseboard_fab2(sch_1):page102_i37"
				( attribute "BOM_COST" "SYS_CLOCK"
					( Origin gFrontEnd )
				)
				( attribute "CDS_LIB" "mstr_discrete"
					( Origin gPackager )
				)
				( attribute "CDS_LOCATION" "R4D38"
					( Origin gPackager )
				)
				( attribute "CDS_SEC" "1"
					( Origin gPackager )
				)
				( attribute "LOCATION" "R4D38"
					( Origin gFrontEnd )
				)
				( attribute "MATERIAL" "EMPTY"
					( Origin gFrontEnd )
				)
				( attribute "PACK_TYPE" "0402"
					( Origin gFrontEnd )
				)
				( attribute "PART_NUMBER" "G21796-016"
					( Origin gFrontEnd )
				)
				( attribute "PHYS_PAGE" "102"
					( Origin gFrontEnd )
				)
				( attribute "ROOM" "DB1200ZL"
					( Origin gFrontEnd )
				)
				( attribute "ROT" "0"
					( Origin gFrontEnd )
				)
				( attribute "SEC" "1"
					( Origin gFrontEnd )
				)
				( attribute "SEC_TYPE" "0402"
					( Origin gFrontEnd )
				)
				( attribute "TOLERANCE" "1%"
					( Origin gFrontEnd )
				)
				( attribute "VALUE" "10.0K"
					( Origin gFrontEnd )
				)
				( attribute "VER" "2"
					( Origin gFrontEnd )
				)
				( attribute "WATTAGE" "1/16W"
					( Origin gFrontEnd )
				)
				( attribute "XY" "(-2850,2925)"
					( Origin gFrontEnd )
				)
				( attribute "CHIPS_PART_NAME" "RES"
					( Origin gPackager )
				)
				( attribute "CDS_PART_NAME" "RES_0402-10.0K,1%,1/16W,EMPTY,A"
					( Origin gPackager )
				)
				( objectStatus "R4D38" )
				( pin "a"
					( attribute "PN" "1"
						( Origin gPackager )
					)
					( objectStatus "R4D38.1" )
				)
				( pin "b"
					( attribute "PN" "2"
						( Origin gPackager )
					)
					( objectStatus "R4D38.2" )
				)
			)
			( gate "@baseboard_fab2_lib.baseboard_fab2(sch_1):page102_i38"
				( attribute "BOM_COST" "SYS_CLOCK"
					( Origin gFrontEnd )
				)
				( attribute "CDS_LIB" "mstr_discrete"
					( Origin gPackager )
				)
				( attribute "CDS_LOCATION" "R4D35"
					( Origin gPackager )
				)
				( attribute "CDS_SEC" "1"
					( Origin gPackager )
				)
				( attribute "LOCATION" "R4D35"
					( Origin gFrontEnd )
				)
				( attribute "MATERIAL" "EMPTY"
					( Origin gFrontEnd )
				)
				( attribute "PACK_TYPE" "0402"
					( Origin gFrontEnd )
				)
				( attribute "PART_NUMBER" "G21796-016"
					( Origin gFrontEnd )
				)
				( attribute "PHYS_PAGE" "102"
					( Origin gFrontEnd )
				)
				( attribute "ROOM" "DB1200ZL"
					( Origin gFrontEnd )
				)
				( attribute "ROT" "0"
					( Origin gFrontEnd )
				)
				( attribute "SEC" "1"
					( Origin gFrontEnd )
				)
				( attribute "SEC_TYPE" "0402"
					( Origin gFrontEnd )
				)
				( attribute "TOLERANCE" "1%"
					( Origin gFrontEnd )
				)
				( attribute "VALUE" "10.0K"
					( Origin gFrontEnd )
				)
				( attribute "VER" "2"
					( Origin gFrontEnd )
				)
				( attribute "WATTAGE" "1/16W"
					( Origin gFrontEnd )
				)
				( attribute "XY" "(-3225,2925)"
					( Origin gFrontEnd )
				)
				( attribute "CHIPS_PART_NAME" "RES"
					( Origin gPackager )
				)
				( attribute "CDS_PART_NAME" "RES_0402-10.0K,1%,1/16W,EMPTY,A"
					( Origin gPackager )
				)
				( objectStatus "R4D35" )
				( pin "a"
					( attribute "PN" "1"
						( Origin gPackager )
					)
					( objectStatus "R4D35.1" )
				)
				( pin "b"
					( attribute "PN" "2"
						( Origin gPackager )
					)
					( objectStatus "R4D35.2" )
				)
			)
			( gate "@baseboard_fab2_lib.baseboard_fab2(sch_1):page102_i45"
				( attribute "BOM_COST" "SYS_CLOCK"
					( Origin gFrontEnd )
				)
				( attribute "CDS_LIB" "mstr_discrete"
					( Origin gPackager )
				)
				( attribute "CDS_LOCATION" "R4D40"
					( Origin gPackager )
				)
				( attribute "CDS_SEC" "1"
					( Origin gPackager )
				)
				( attribute "LOCATION" "R4D40"
					( Origin gFrontEnd )
				)
				( attribute "MATERIAL" "CHIP"
					( Origin gFrontEnd )
				)
				( attribute "PACK_TYPE" "0402"
					( Origin gFrontEnd )
				)
				( attribute "PART_NUMBER" "G21796-072"
					( Origin gFrontEnd )
				)
				( attribute "PHYS_PAGE" "102"
					( Origin gFrontEnd )
				)
				( attribute "ROOM" "DB1200ZL"
					( Origin gFrontEnd )
				)
				( attribute "ROT" "0"
					( Origin gFrontEnd )
				)
				( attribute "SEC" "1"
					( Origin gFrontEnd )
				)
				( attribute "SEC_TYPE" "0402"
					( Origin gFrontEnd )
				)
				( attribute "TOLERANCE" "1%"
					( Origin gFrontEnd )
				)
				( attribute "VALUE" "4.75K"
					( Origin gFrontEnd )
				)
				( attribute "VER" "2"
					( Origin gFrontEnd )
				)
				( attribute "WATTAGE" "1/16W"
					( Origin gFrontEnd )
				)
				( attribute "XY" "(-2675,1500)"
					( Origin gFrontEnd )
				)
				( attribute "CHIPS_PART_NAME" "RES"
					( Origin gPackager )
				)
				( attribute "CDS_PART_NAME" "RES_0402-4.75K,1%,1/16W,CHIP,GA"
					( Origin gPackager )
				)
				( objectStatus "R4D40" )
				( pin "a"
					( attribute "PN" "1"
						( Origin gPackager )
					)
					( objectStatus "R4D40.1" )
				)
				( pin "b"
					( attribute "PN" "2"
						( Origin gPackager )
					)
					( objectStatus "R4D40.2" )
				)
			)
			( gate "@baseboard_fab2_lib.baseboard_fab2(sch_1):page102_i46"
				( attribute "BOM_COST" "SYS_CLOCK"
					( Origin gFrontEnd )
				)
				( attribute "CDS_LIB" "mstr_discrete"
					( Origin gPackager )
				)
				( attribute "CDS_LOCATION" "R6P23"
					( Origin gPackager )
				)
				( attribute "CDS_SEC" "1"
					( Origin gPackager )
				)
				( attribute "LOCATION" "R6P23"
					( Origin gFrontEnd )
				)
				( attribute "MATERIAL" "EMPTY"
					( Origin gFrontEnd )
				)
				( attribute "PACK_TYPE" "0402"
					( Origin gFrontEnd )
				)
				( attribute "PART_NUMBER" "G21796-072"
					( Origin gFrontEnd )
				)
				( attribute "PHYS_PAGE" "102"
					( Origin gFrontEnd )
				)
				( attribute "ROOM" "DB1200ZL"
					( Origin gFrontEnd )
				)
				( attribute "ROT" "0"
					( Origin gFrontEnd )
				)
				( attribute "SEC" "1"
					( Origin gFrontEnd )
				)
				( attribute "SEC_TYPE" "0402"
					( Origin gFrontEnd )
				)
				( attribute "TOLERANCE" "1%"
					( Origin gFrontEnd )
				)
				( attribute "VALUE" "4.75K"
					( Origin gFrontEnd )
				)
				( attribute "VER" "2"
					( Origin gFrontEnd )
				)
				( attribute "WATTAGE" "1/16W"
					( Origin gFrontEnd )
				)
				( attribute "XY" "(-2675,1100)"
					( Origin gFrontEnd )
				)
				( attribute "CHIPS_PART_NAME" "RES"
					( Origin gPackager )
				)
				( attribute "CDS_PART_NAME" "RES_0402-4.75K,1%,1/16W,EMPTY,A"
					( Origin gPackager )
				)
				( objectStatus "R6P23" )
				( pin "a"
					( attribute "PN" "1"
						( Origin gPackager )
					)
					( objectStatus "R6P23.1" )
				)
				( pin "b"
					( attribute "PN" "2"
						( Origin gPackager )
					)
					( objectStatus "R6P23.2" )
				)
			)
			( gate "@baseboard_fab2_lib.baseboard_fab2(sch_1):page102_i47"
				( attribute "BOM_COST" "SYS_CLOCK"
					( Origin gFrontEnd )
				)
				( attribute "CDS_LIB" "mstr_discrete"
					( Origin gPackager )
				)
				( attribute "CDS_LOCATION" "R6P22"
					( Origin gPackager )
				)
				( attribute "CDS_SEC" "1"
					( Origin gPackager )
				)
				( attribute "LOCATION" "R6P22"
					( Origin gFrontEnd )
				)
				( attribute "MATERIAL" "EMPTY"
					( Origin gFrontEnd )
				)
				( attribute "PACK_TYPE" "0402"
					( Origin gFrontEnd )
				)
				( attribute "PART_NUMBER" "G21796-072"
					( Origin gFrontEnd )
				)
				( attribute "PHYS_PAGE" "102"
					( Origin gFrontEnd )
				)
				( attribute "ROOM" "DB1200ZL"
					( Origin gFrontEnd )
				)
				( attribute "ROT" "2"
					( Origin gFrontEnd )
				)
				( attribute "SEC" "1"
					( Origin gFrontEnd )
				)
				( attribute "SEC_TYPE" "0402"
					( Origin gFrontEnd )
				)
				( attribute "TOLERANCE" "1%"
					( Origin gFrontEnd )
				)
				( attribute "VALUE" "4.75K"
					( Origin gFrontEnd )
				)
				( attribute "VER" "2"
					( Origin gFrontEnd )
				)
				( attribute "WATTAGE" "1/16W"
					( Origin gFrontEnd )
				)
				( attribute "XY" "(-2925,1100)"
					( Origin gFrontEnd )
				)
				( attribute "CHIPS_PART_NAME" "RES"
					( Origin gPackager )
				)
				( attribute "CDS_PART_NAME" "RES_0402-4.75K,1%,1/16W,EMPTY,A"
					( Origin gPackager )
				)
				( objectStatus "R6P22" )
				( pin "a"
					( attribute "PN" "1"
						( Origin gPackager )
					)
					( objectStatus "R6P22.1" )
				)
				( pin "b"
					( attribute "PN" "2"
						( Origin gPackager )
					)
					( objectStatus "R6P22.2" )
				)
			)
			( gate "@baseboard_fab2_lib.baseboard_fab2(sch_1):page102_i53"
				( attribute "BOM_COST" "SYS_CLOCK"
					( Origin gFrontEnd )
				)
				( attribute "CDS_LIB" "mstr_discrete"
					( Origin gPackager )
				)
				( attribute "CDS_LOCATION" "R4D41"
					( Origin gPackager )
				)
				( attribute "CDS_SEC" "1"
					( Origin gPackager )
				)
				( attribute "LOCATION" "R4D41"
					( Origin gFrontEnd )
				)
				( attribute "MATERIAL" "CHIP"
					( Origin gFrontEnd )
				)
				( attribute "PACK_TYPE" "0402"
					( Origin gFrontEnd )
				)
				( attribute "PART_NUMBER" "G21796-072"
					( Origin gFrontEnd )
				)
				( attribute "PHYS_PAGE" "102"
					( Origin gFrontEnd )
				)
				( attribute "ROOM" "DB1200ZL"
					( Origin gFrontEnd )
				)
				( attribute "ROT" "2"
					( Origin gFrontEnd )
				)
				( attribute "SEC" "1"
					( Origin gFrontEnd )
				)
				( attribute "SEC_TYPE" "0402"
					( Origin gFrontEnd )
				)
				( attribute "TOLERANCE" "1%"
					( Origin gFrontEnd )
				)
				( attribute "VALUE" "4.75K"
					( Origin gFrontEnd )
				)
				( attribute "VER" "2"
					( Origin gFrontEnd )
				)
				( attribute "WATTAGE" "1/16W"
					( Origin gFrontEnd )
				)
				( attribute "XY" "(-2925,1500)"
					( Origin gFrontEnd )
				)
				( attribute "CHIPS_PART_NAME" "RES"
					( Origin gPackager )
				)
				( attribute "CDS_PART_NAME" "RES_0402-4.75K,1%,1/16W,CHIP,GA"
					( Origin gPackager )
				)
				( objectStatus "R4D41" )
				( pin "a"
					( attribute "PN" "1"
						( Origin gPackager )
					)
					( objectStatus "R4D41.1" )
				)
				( pin "b"
					( attribute "PN" "2"
						( Origin gPackager )
					)
					( objectStatus "R4D41.2" )
				)
			)
			( gate "@baseboard_fab2_lib.baseboard_fab2(sch_1):page102_i79"
				( attribute "BOM_COST" "SYS_CLOCK"
					( Origin gFrontEnd )
				)
				( attribute "CDS_LIB" "dev_discrete"
					( Origin gPackager )
				)
				( attribute "CDS_LOCATION" "C6P9"
					( Origin gPackager )
				)
				( attribute "CDS_SEC" "1"
					( Origin gPackager )
				)
				( attribute "LOCATION" "C6P9"
					( Origin gFrontEnd )
				)
				( attribute "MATERIAL" "X7R"
					( Origin gFrontEnd )
				)
				( attribute "PACK_TYPE" "0402V"
					( Origin gFrontEnd )
				)
				( attribute "PART_NUMBER" "A36096-030"
					( Origin gFrontEnd )
				)
				( attribute "PHYS_PAGE" "102"
					( Origin gFrontEnd )
				)
				( attribute "ROOM" "DB1200ZL"
					( Origin gFrontEnd )
				)
				( attribute "ROT" "0"
					( Origin gFrontEnd )
				)
				( attribute "SEC" "1"
					( Origin gFrontEnd )
				)
				( attribute "SEC_TYPE" "0402V"
					( Origin gFrontEnd )
				)
				( attribute "TOLERANCE" "10%"
					( Origin gFrontEnd )
				)
				( attribute "VALUE" "0.1UF"
					( Origin gFrontEnd )
				)
				( attribute "VER" "1"
					( Origin gFrontEnd )
				)
				( attribute "VOLTAGE" "16V"
					( Units "uVoltage" "V" 1.000000)
					( Origin gFrontEnd )
				)
				( attribute "XY" "(2275,975)"
					( Origin gFrontEnd )
				)
				( attribute "CHIPS_PART_NAME" "CAP_A"
					( Origin gPackager )
				)
				( attribute "CDS_PART_NAME" "CAP_A_0402V-0.1UF,16V,10%,X7R,A"
					( Origin gPackager )
				)
				( objectStatus "C6P9" )
				( pin "a"
					( attribute "PN" "1"
						( Origin gPackager )
					)
					( objectStatus "C6P9.1" )
				)
				( pin "b"
					( attribute "PN" "2"
						( Origin gPackager )
					)
					( objectStatus "C6P9.2" )
				)
			)
			( gate "@baseboard_fab2_lib.baseboard_fab2(sch_1):page102_i80"
				( attribute "BOM_COST" "SYS_CLOCK"
					( Origin gFrontEnd )
				)
				( attribute "CDS_LIB" "mstr_discrete"
					( Origin gPackager )
				)
				( attribute "CDS_LOCATION" "R6P21"
					( Origin gPackager )
				)
				( attribute "CDS_SEC" "1"
					( Origin gPackager )
				)
				( attribute "LOCATION" "R6P21"
					( Origin gFrontEnd )
				)
				( attribute "MATERIAL" "CHIP"
					( Origin gFrontEnd )
				)
				( attribute "PACK_TYPE" "0402"
					( Origin gFrontEnd )
				)
				( attribute "PART_NUMBER" "G21796-026"
					( Origin gFrontEnd )
				)
				( attribute "PHYS_PAGE" "102"
					( Origin gFrontEnd )
				)
				( attribute "ROOM" "DB1200ZL"
					( Origin gFrontEnd )
				)
				( attribute "ROT" "0"
					( Origin gFrontEnd )
				)
				( attribute "SEC" "1"
					( Origin gFrontEnd )
				)
				( attribute "SEC_TYPE" "0402"
					( Origin gFrontEnd )
				)
				( attribute "TOLERANCE" "1%"
					( Origin gFrontEnd )
				)
				( attribute "VALUE" "1.00K"
					( Origin gFrontEnd )
				)
				( attribute "VER" "2"
					( Origin gFrontEnd )
				)
				( attribute "WATTAGE" "1/16W"
					( Origin gFrontEnd )
				)
				( attribute "XY" "(-3225,2550)"
					( Origin gFrontEnd )
				)
				( attribute "CHIPS_PART_NAME" "RES"
					( Origin gPackager )
				)
				( attribute "CDS_PART_NAME" "RES_0402-1.00K,1%,1/16W,CHIP,GA"
					( Origin gPackager )
				)
				( objectStatus "R6P21" )
				( pin "a"
					( attribute "PN" "1"
						( Origin gPackager )
					)
					( objectStatus "R6P21.1" )
				)
				( pin "b"
					( attribute "PN" "2"
						( Origin gPackager )
					)
					( objectStatus "R6P21.2" )
				)
			)
			( gate "@baseboard_fab2_lib.baseboard_fab2(sch_1):page102_i81"
				( attribute "BOM_COST" "SYS_CLOCK"
					( Origin gFrontEnd )
				)
				( attribute "CDS_LIB" "mstr_discrete"
					( Origin gPackager )
				)
				( attribute "CDS_LOCATION" "R6P20"
					( Origin gPackager )
				)
				( attribute "CDS_SEC" "1"
					( Origin gPackager )
				)
				( attribute "LOCATION" "R6P20"
					( Origin gFrontEnd )
				)
				( attribute "MATERIAL" "CHIP"
					( Origin gFrontEnd )
				)
				( attribute "PACK_TYPE" "0402"
					( Origin gFrontEnd )
				)
				( attribute "PART_NUMBER" "G21796-026"
					( Origin gFrontEnd )
				)
				( attribute "PHYS_PAGE" "102"
					( Origin gFrontEnd )
				)
				( attribute "ROOM" "DB1200ZL"
					( Origin gFrontEnd )
				)
				( attribute "ROT" "0"
					( Origin gFrontEnd )
				)
				( attribute "SEC" "1"
					( Origin gFrontEnd )
				)
				( attribute "SEC_TYPE" "0402"
					( Origin gFrontEnd )
				)
				( attribute "TOLERANCE" "1%"
					( Origin gFrontEnd )
				)
				( attribute "VALUE" "1.00K"
					( Origin gFrontEnd )
				)
				( attribute "VER" "2"
					( Origin gFrontEnd )
				)
				( attribute "WATTAGE" "1/16W"
					( Origin gFrontEnd )
				)
				( attribute "XY" "(-2850,2550)"
					( Origin gFrontEnd )
				)
				( attribute "CHIPS_PART_NAME" "RES"
					( Origin gPackager )
				)
				( attribute "CDS_PART_NAME" "RES_0402-1.00K,1%,1/16W,CHIP,GA"
					( Origin gPackager )
				)
				( objectStatus "R6P20" )
				( pin "a"
					( attribute "PN" "1"
						( Origin gPackager )
					)
					( objectStatus "R6P20.1" )
				)
				( pin "b"
					( attribute "PN" "2"
						( Origin gPackager )
					)
					( objectStatus "R6P20.2" )
				)
			)
			( gate "@baseboard_fab2_lib.baseboard_fab2(sch_1):page102_i82"
				( attribute "BOM_COST" "SYS_CLOCK"
					( Origin gFrontEnd )
				)
				( attribute "CDS_LIB" "mstr_discrete"
					( Origin gPackager )
				)
				( attribute "CDS_LOCATION" "R4D36"
					( Origin gPackager )
				)
				( attribute "CDS_SEC" "1"
					( Origin gPackager )
				)
				( attribute "LOCATION" "R4D36"
					( Origin gFrontEnd )
				)
				( attribute "MATERIAL" "CHIP"
					( Origin gFrontEnd )
				)
				( attribute "PACK_TYPE" "0402"
					( Origin gFrontEnd )
				)
				( attribute "PART_NUMBER" "G21796-074"
					( Origin gFrontEnd )
				)
				( attribute "PHYS_PAGE" "102"
					( Origin gFrontEnd )
				)
				( attribute "ROOM" "DB1200ZL"
					( Origin gFrontEnd )
				)
				( attribute "ROT" "0"
					( Origin gFrontEnd )
				)
				( attribute "SEC" "1"
					( Origin gPackager )
				)
				( attribute "TOLERANCE" "1%"
					( Origin gFrontEnd )
				)
				( attribute "VALUE" "33.2"
					( Origin gFrontEnd )
				)
				( attribute "VER" "1"
					( Origin gFrontEnd )
				)
				( attribute "WATTAGE" "1/16W"
					( Origin gFrontEnd )
				)
				( attribute "XY" "(-1350,4875)"
					( Origin gFrontEnd )
				)
				( attribute "CHIPS_PART_NAME" "RES"
					( Origin gPackager )
				)
				( attribute "CDS_PART_NAME" "RES_0402-33.2,1%,1/16W,CHIP,G2A"
					( Origin gPackager )
				)
				( objectStatus "R4D36" )
				( pin "a"
					( attribute "PN" "1"
						( Origin gPackager )
					)
					( objectStatus "R4D36.1" )
				)
				( pin "b"
					( attribute "PN" "2"
						( Origin gPackager )
					)
					( objectStatus "R4D36.2" )
				)
			)
			( gate "@baseboard_fab2_lib.baseboard_fab2(sch_1):page102_i87"
				( attribute "BOM_COST" "SYS_CLOCK"
					( Origin gFrontEnd )
				)
				( attribute "CDS_LIB" "mstr_discrete"
					( Origin gPackager )
				)
				( attribute "CDS_LOCATION" "R4D37"
					( Origin gPackager )
				)
				( attribute "CDS_SEC" "1"
					( Origin gPackager )
				)
				( attribute "LOCATION" "R4D37"
					( Origin gFrontEnd )
				)
				( attribute "MATERIAL" "CHIP"
					( Origin gFrontEnd )
				)
				( attribute "PACK_TYPE" "0402"
					( Origin gFrontEnd )
				)
				( attribute "PART_NUMBER" "G21796-074"
					( Origin gFrontEnd )
				)
				( attribute "PHYS_PAGE" "102"
					( Origin gFrontEnd )
				)
				( attribute "ROOM" "DB1200ZL"
					( Origin gFrontEnd )
				)
				( attribute "ROT" "0"
					( Origin gFrontEnd )
				)
				( attribute "SEC" "1"
					( Origin gPackager )
				)
				( attribute "TOLERANCE" "1%"
					( Origin gFrontEnd )
				)
				( attribute "VALUE" "33.2"
					( Origin gFrontEnd )
				)
				( attribute "VER" "1"
					( Origin gFrontEnd )
				)
				( attribute "WATTAGE" "1/16W"
					( Origin gFrontEnd )
				)
				( attribute "XY" "(-1350,4725)"
					( Origin gFrontEnd )
				)
				( attribute "CHIPS_PART_NAME" "RES"
					( Origin gPackager )
				)
				( attribute "CDS_PART_NAME" "RES_0402-33.2,1%,1/16W,CHIP,G2A"
					( Origin gPackager )
				)
				( objectStatus "R4D37" )
				( pin "a"
					( attribute "PN" "1"
						( Origin gPackager )
					)
					( objectStatus "R4D37.1" )
				)
				( pin "b"
					( attribute "PN" "2"
						( Origin gPackager )
					)
					( objectStatus "R4D37.2" )
				)
			)
			( gate "@baseboard_fab2_lib.baseboard_fab2(sch_1):page102_i91"
				( attribute "BOM_COST" "SYS_CLOCK"
					( Origin gFrontEnd )
				)
				( attribute "CDS_LIB" "mstr_discrete"
					( Origin gPackager )
				)
				( attribute "CDS_LOCATION" "R6P48"
					( Origin gPackager )
				)
				( attribute "CDS_SEC" "1"
					( Origin gPackager )
				)
				( attribute "LOCATION" "R6P48"
					( Origin gFrontEnd )
				)
				( attribute "MATERIAL" "CHIP"
					( Origin gFrontEnd )
				)
				( attribute "PACK_TYPE" "0402"
					( Origin gFrontEnd )
				)
				( attribute "PART_NUMBER" "G21796-072"
					( Origin gFrontEnd )
				)
				( attribute "PHYS_PAGE" "102"
					( Origin gFrontEnd )
				)
				( attribute "ROOM" "DB1200ZL"
					( Origin gFrontEnd )
				)
				( attribute "ROT" "2"
					( Origin gFrontEnd )
				)
				( attribute "SEC" "1"
					( Origin gFrontEnd )
				)
				( attribute "SEC_TYPE" "0402"
					( Origin gFrontEnd )
				)
				( attribute "SIGNAL_MODEL" "DEFAULT_RESISTOR_47000OHM_2_1"
					( Origin gFrontEnd )
				)
				( attribute "TOLERANCE" "1%"
					( Origin gFrontEnd )
				)
				( attribute "VALUE" "4.75K"
					( Origin gFrontEnd )
				)
				( attribute "VER" "2"
					( Origin gFrontEnd )
				)
				( attribute "WATTAGE" "1/16W"
					( Origin gFrontEnd )
				)
				( attribute "XY" "(-425,1150)"
					( Origin gFrontEnd )
				)
				( attribute "CHIPS_PART_NAME" "RES"
					( Origin gPackager )
				)
				( attribute "CDS_PART_NAME" "RES_0402-4.75K,1%,1/16W,CHIP,GA"
					( Origin gPackager )
				)
				( objectStatus "R6P48" )
				( pin "a"
					( attribute "PN" "1"
						( Origin gPackager )
					)
					( objectStatus "R6P48.1" )
				)
				( pin "b"
					( attribute "PN" "2"
						( Origin gPackager )
					)
					( objectStatus "R6P48.2" )
				)
			)
			( gate "@baseboard_fab2_lib.baseboard_fab2(sch_1):page102_i93"
				( attribute "BOM_COST" "SYS_CLOCK"
					( Origin gFrontEnd )
				)
				( attribute "CDS_LIB" "mstr_discrete"
					( Origin gPackager )
				)
				( attribute "CDS_LOCATION" "R4D69"
					( Origin gPackager )
				)
				( attribute "CDS_SEC" "1"
					( Origin gPackager )
				)
				( attribute "LOCATION" "R4D69"
					( Origin gFrontEnd )
				)
				( attribute "MATERIAL" "CHIP"
					( Origin gFrontEnd )
				)
				( attribute "PACK_TYPE" "0402"
					( Origin gFrontEnd )
				)
				( attribute "PART_NUMBER" "G21796-072"
					( Origin gFrontEnd )
				)
				( attribute "PHYS_PAGE" "102"
					( Origin gFrontEnd )
				)
				( attribute "ROOM" "DB1200ZL"
					( Origin gFrontEnd )
				)
				( attribute "ROT" "2"
					( Origin gFrontEnd )
				)
				( attribute "SEC" "1"
					( Origin gFrontEnd )
				)
				( attribute "SEC_TYPE" "0402"
					( Origin gFrontEnd )
				)
				( attribute "SIGNAL_MODEL" "DEFAULT_RESISTOR_47000OHM_2_1"
					( Origin gFrontEnd )
				)
				( attribute "TOLERANCE" "1%"
					( Origin gFrontEnd )
				)
				( attribute "VALUE" "4.75K"
					( Origin gFrontEnd )
				)
				( attribute "VER" "2"
					( Origin gFrontEnd )
				)
				( attribute "WATTAGE" "1/16W"
					( Origin gFrontEnd )
				)
				( attribute "XY" "(-125,1150)"
					( Origin gFrontEnd )
				)
				( attribute "CHIPS_PART_NAME" "RES"
					( Origin gPackager )
				)
				( attribute "CDS_PART_NAME" "RES_0402-4.75K,1%,1/16W,CHIP,GA"
					( Origin gPackager )
				)
				( objectStatus "R4D69" )
				( pin "a"
					( attribute "PN" "1"
						( Origin gPackager )
					)
					( objectStatus "R4D69.1" )
				)
				( pin "b"
					( attribute "PN" "2"
						( Origin gPackager )
					)
					( objectStatus "R4D69.2" )
				)
			)
			( gate "@baseboard_fab2_lib.baseboard_fab2(sch_1):page102_i94"
				( attribute "BOM_COST" "SYS_CLOCK"
					( Origin gFrontEnd )
				)
				( attribute "CDS_LIB" "mstr_discrete"
					( Origin gPackager )
				)
				( attribute "CDS_LOCATION" "R4D70"
					( Origin gPackager )
				)
				( attribute "CDS_SEC" "1"
					( Origin gPackager )
				)
				( attribute "LOCATION" "R4D70"
					( Origin gFrontEnd )
				)
				( attribute "MATERIAL" "CHIP"
					( Origin gFrontEnd )
				)
				( attribute "PACK_TYPE" "0402"
					( Origin gFrontEnd )
				)
				( attribute "PART_NUMBER" "G21796-072"
					( Origin gFrontEnd )
				)
				( attribute "PHYS_PAGE" "102"
					( Origin gFrontEnd )
				)
				( attribute "ROOM" "DB1200ZL"
					( Origin gFrontEnd )
				)
				( attribute "ROT" "2"
					( Origin gFrontEnd )
				)
				( attribute "SEC" "1"
					( Origin gFrontEnd )
				)
				( attribute "SEC_TYPE" "0402"
					( Origin gFrontEnd )
				)
				( attribute "SIGNAL_MODEL" "DEFAULT_RESISTOR_47000OHM_2_1"
					( Origin gFrontEnd )
				)
				( attribute "TOLERANCE" "1%"
					( Origin gFrontEnd )
				)
				( attribute "VALUE" "4.75K"
					( Origin gFrontEnd )
				)
				( attribute "VER" "2"
					( Origin gFrontEnd )
				)
				( attribute "WATTAGE" "1/16W"
					( Origin gFrontEnd )
				)
				( attribute "XY" "(200,1150)"
					( Origin gFrontEnd )
				)
				( attribute "CHIPS_PART_NAME" "RES"
					( Origin gPackager )
				)
				( attribute "CDS_PART_NAME" "RES_0402-4.75K,1%,1/16W,CHIP,GA"
					( Origin gPackager )
				)
				( objectStatus "R4D70" )
				( pin "a"
					( attribute "PN" "1"
						( Origin gPackager )
					)
					( objectStatus "R4D70.1" )
				)
				( pin "b"
					( attribute "PN" "2"
						( Origin gPackager )
					)
					( objectStatus "R4D70.2" )
				)
			)
			( gate "@baseboard_fab2_lib.baseboard_fab2(sch_1):page103_i1"
				( attribute "BOM_COST" "SYS_CLOCK"
					( Origin gFrontEnd )
				)
				( attribute "CDS_LIB" "mstr_discrete"
					( Origin gPackager )
				)
				( attribute "CDS_LOCATION" "R4D25"
					( Origin gPackager )
				)
				( attribute "CDS_SEC" "1"
					( Origin gPackager )
				)
				( attribute "LOCATION" "R4D25"
					( Origin gFrontEnd )
				)
				( attribute "MATERIAL" "CHIP"
					( Origin gFrontEnd )
				)
				( attribute "PACK_TYPE" "0402"
					( Origin gFrontEnd )
				)
				( attribute "PART_NUMBER" "G21796-182"
					( Origin gFrontEnd )
				)
				( attribute "PHYS_PAGE" "103"
					( Origin gFrontEnd )
				)
				( attribute "ROOM" "DB1200Z"
					( Origin gFrontEnd )
				)
				( attribute "ROT" "0"
					( Origin gFrontEnd )
				)
				( attribute "SEC" "1"
					( Origin gFrontEnd )
				)
				( attribute "SEC_TYPE" "0402"
					( Origin gFrontEnd )
				)
				( attribute "TOLERANCE" "1%"
					( Origin gFrontEnd )
				)
				( attribute "VALUE" "27.4"
					( Origin gFrontEnd )
				)
				( attribute "VER" "1"
					( Origin gFrontEnd )
				)
				( attribute "WATTAGE" "1/16W"
					( Origin gFrontEnd )
				)
				( attribute "XY" "(300,1250)"
					( Origin gFrontEnd )
				)
				( attribute "CHIPS_PART_NAME" "RES"
					( Origin gPackager )
				)
				( attribute "CDS_PART_NAME" "RES_0402-27.4,1%,1/16W,CHIP,G2A"
					( Origin gPackager )
				)
				( objectStatus "R4D25" )
				( pin "a"
					( attribute "PN" "1"
						( Origin gPackager )
					)
					( objectStatus "R4D25.1" )
				)
				( pin "b"
					( attribute "PN" "2"
						( Origin gPackager )
					)
					( objectStatus "R4D25.2" )
				)
			)
			( gate "@baseboard_fab2_lib.baseboard_fab2(sch_1):page103_i9"
				( attribute "BOM_COST" "SYS_CLOCK"
					( Origin gFrontEnd )
				)
				( attribute "CDS_LIB" "mstr_discrete"
					( Origin gPackager )
				)
				( attribute "CDS_LOCATION" "R4D23"
					( Origin gPackager )
				)
				( attribute "CDS_SEC" "1"
					( Origin gPackager )
				)
				( attribute "LOCATION" "R4D23"
					( Origin gFrontEnd )
				)
				( attribute "MATERIAL" "CHIP"
					( Origin gFrontEnd )
				)
				( attribute "PACK_TYPE" "0402"
					( Origin gFrontEnd )
				)
				( attribute "PART_NUMBER" "G21796-182"
					( Origin gFrontEnd )
				)
				( attribute "PHYS_PAGE" "103"
					( Origin gFrontEnd )
				)
				( attribute "ROOM" "DB1200Z"
					( Origin gFrontEnd )
				)
				( attribute "ROT" "0"
					( Origin gFrontEnd )
				)
				( attribute "SEC" "1"
					( Origin gFrontEnd )
				)
				( attribute "SEC_TYPE" "0402"
					( Origin gFrontEnd )
				)
				( attribute "TOLERANCE" "1%"
					( Origin gFrontEnd )
				)
				( attribute "VALUE" "27.4"
					( Origin gFrontEnd )
				)
				( attribute "VER" "1"
					( Origin gFrontEnd )
				)
				( attribute "WATTAGE" "1/16W"
					( Origin gFrontEnd )
				)
				( attribute "XY" "(-3925,4900)"
					( Origin gFrontEnd )
				)
				( attribute "CHIPS_PART_NAME" "RES"
					( Origin gPackager )
				)
				( attribute "CDS_PART_NAME" "RES_0402-27.4,1%,1/16W,CHIP,G2A"
					( Origin gPackager )
				)
				( objectStatus "R4D23" )
				( pin "a"
					( attribute "PN" "1"
						( Origin gPackager )
					)
					( objectStatus "R4D23.1" )
				)
				( pin "b"
					( attribute "PN" "2"
						( Origin gPackager )
					)
					( objectStatus "R4D23.2" )
				)
			)
			( gate "@baseboard_fab2_lib.baseboard_fab2(sch_1):page103_i14"
				( attribute "BOM_COST" "SYS_CLOCK"
					( Origin gFrontEnd )
				)
				( attribute "CDS_LIB" "mstr_discrete"
					( Origin gPackager )
				)
				( attribute "CDS_LOCATION" "R4D28"
					( Origin gPackager )
				)
				( attribute "CDS_SEC" "1"
					( Origin gPackager )
				)
				( attribute "LOCATION" "R4D28"
					( Origin gFrontEnd )
				)
				( attribute "MATERIAL" "CHIP"
					( Origin gFrontEnd )
				)
				( attribute "PACK_TYPE" "0402"
					( Origin gFrontEnd )
				)
				( attribute "PART_NUMBER" "G21796-182"
					( Origin gFrontEnd )
				)
				( attribute "PHYS_PAGE" "103"
					( Origin gFrontEnd )
				)
				( attribute "ROOM" "DB1200Z"
					( Origin gFrontEnd )
				)
				( attribute "ROT" "0"
					( Origin gFrontEnd )
				)
				( attribute "SEC" "1"
					( Origin gFrontEnd )
				)
				( attribute "SEC_TYPE" "0402"
					( Origin gFrontEnd )
				)
				( attribute "TOLERANCE" "1%"
					( Origin gFrontEnd )
				)
				( attribute "VALUE" "27.4"
					( Origin gFrontEnd )
				)
				( attribute "VER" "1"
					( Origin gFrontEnd )
				)
				( attribute "WATTAGE" "1/16W"
					( Origin gFrontEnd )
				)
				( attribute "XY" "(-3925,4525)"
					( Origin gFrontEnd )
				)
				( attribute "CHIPS_PART_NAME" "RES"
					( Origin gPackager )
				)
				( attribute "CDS_PART_NAME" "RES_0402-27.4,1%,1/16W,CHIP,G2A"
					( Origin gPackager )
				)
				( objectStatus "R4D28" )
				( pin "a"
					( attribute "PN" "1"
						( Origin gPackager )
					)
					( objectStatus "R4D28.1" )
				)
				( pin "b"
					( attribute "PN" "2"
						( Origin gPackager )
					)
					( objectStatus "R4D28.2" )
				)
			)
			( gate "@baseboard_fab2_lib.baseboard_fab2(sch_1):page103_i19"
				( attribute "BOM_COST" "SYS_CLOCK"
					( Origin gFrontEnd )
				)
				( attribute "CDS_LIB" "mstr_discrete"
					( Origin gPackager )
				)
				( attribute "CDS_LOCATION" "R4D19"
					( Origin gPackager )
				)
				( attribute "CDS_SEC" "1"
					( Origin gPackager )
				)
				( attribute "LOCATION" "R4D19"
					( Origin gFrontEnd )
				)
				( attribute "MATERIAL" "CHIP"
					( Origin gFrontEnd )
				)
				( attribute "PACK_TYPE" "0402"
					( Origin gFrontEnd )
				)
				( attribute "PART_NUMBER" "G21796-182"
					( Origin gFrontEnd )
				)
				( attribute "PHYS_PAGE" "103"
					( Origin gFrontEnd )
				)
				( attribute "ROOM" "DB1200Z"
					( Origin gFrontEnd )
				)
				( attribute "ROT" "0"
					( Origin gFrontEnd )
				)
				( attribute "SEC" "1"
					( Origin gFrontEnd )
				)
				( attribute "SEC_TYPE" "0402"
					( Origin gFrontEnd )
				)
				( attribute "TOLERANCE" "1%"
					( Origin gFrontEnd )
				)
				( attribute "VALUE" "27.4"
					( Origin gFrontEnd )
				)
				( attribute "VER" "1"
					( Origin gFrontEnd )
				)
				( attribute "WATTAGE" "1/16W"
					( Origin gFrontEnd )
				)
				( attribute "XY" "(-3925,4175)"
					( Origin gFrontEnd )
				)
				( attribute "CHIPS_PART_NAME" "RES"
					( Origin gPackager )
				)
				( attribute "CDS_PART_NAME" "RES_0402-27.4,1%,1/16W,CHIP,G2A"
					( Origin gPackager )
				)
				( objectStatus "R4D19" )
				( pin "a"
					( attribute "PN" "1"
						( Origin gPackager )
					)
					( objectStatus "R4D19.1" )
				)
				( pin "b"
					( attribute "PN" "2"
						( Origin gPackager )
					)
					( objectStatus "R4D19.2" )
				)
			)
			( gate "@baseboard_fab2_lib.baseboard_fab2(sch_1):page103_i24"
				( attribute "BOM_COST" "SYS_CLOCK"
					( Origin gFrontEnd )
				)
				( attribute "CDS_LIB" "mstr_discrete"
					( Origin gPackager )
				)
				( attribute "CDS_LOCATION" "R4D21"
					( Origin gPackager )
				)
				( attribute "CDS_SEC" "1"
					( Origin gPackager )
				)
				( attribute "LOCATION" "R4D21"
					( Origin gFrontEnd )
				)
				( attribute "MATERIAL" "CHIP"
					( Origin gFrontEnd )
				)
				( attribute "PACK_TYPE" "0402"
					( Origin gFrontEnd )
				)
				( attribute "PART_NUMBER" "G21796-182"
					( Origin gFrontEnd )
				)
				( attribute "PHYS_PAGE" "103"
					( Origin gFrontEnd )
				)
				( attribute "ROOM" "DB1200Z"
					( Origin gFrontEnd )
				)
				( attribute "ROT" "0"
					( Origin gFrontEnd )
				)
				( attribute "SEC" "1"
					( Origin gFrontEnd )
				)
				( attribute "SEC_TYPE" "0402"
					( Origin gFrontEnd )
				)
				( attribute "TOLERANCE" "1%"
					( Origin gFrontEnd )
				)
				( attribute "VALUE" "27.4"
					( Origin gFrontEnd )
				)
				( attribute "VER" "1"
					( Origin gFrontEnd )
				)
				( attribute "WATTAGE" "1/16W"
					( Origin gFrontEnd )
				)
				( attribute "XY" "(-3925,3850)"
					( Origin gFrontEnd )
				)
				( attribute "CHIPS_PART_NAME" "RES"
					( Origin gPackager )
				)
				( attribute "CDS_PART_NAME" "RES_0402-27.4,1%,1/16W,CHIP,G2A"
					( Origin gPackager )
				)
				( objectStatus "R4D21" )
				( pin "a"
					( attribute "PN" "1"
						( Origin gPackager )
					)
					( objectStatus "R4D21.1" )
				)
				( pin "b"
					( attribute "PN" "2"
						( Origin gPackager )
					)
					( objectStatus "R4D21.2" )
				)
			)
			( gate "@baseboard_fab2_lib.baseboard_fab2(sch_1):page103_i29"
				( attribute "BOM_COST" "SYS_CLOCK"
					( Origin gFrontEnd )
				)
				( attribute "CDS_LIB" "mstr_discrete"
					( Origin gPackager )
				)
				( attribute "CDS_LOCATION" "R4D13"
					( Origin gPackager )
				)
				( attribute "CDS_SEC" "1"
					( Origin gPackager )
				)
				( attribute "LOCATION" "R4D13"
					( Origin gFrontEnd )
				)
				( attribute "MATERIAL" "CHIP"
					( Origin gFrontEnd )
				)
				( attribute "PACK_TYPE" "0402"
					( Origin gFrontEnd )
				)
				( attribute "PART_NUMBER" "G21796-182"
					( Origin gFrontEnd )
				)
				( attribute "PHYS_PAGE" "103"
					( Origin gFrontEnd )
				)
				( attribute "ROOM" "DB1200Z"
					( Origin gFrontEnd )
				)
				( attribute "ROT" "0"
					( Origin gFrontEnd )
				)
				( attribute "SEC" "1"
					( Origin gFrontEnd )
				)
				( attribute "SEC_TYPE" "0402"
					( Origin gFrontEnd )
				)
				( attribute "TOLERANCE" "1%"
					( Origin gFrontEnd )
				)
				( attribute "VALUE" "27.4"
					( Origin gFrontEnd )
				)
				( attribute "VER" "1"
					( Origin gFrontEnd )
				)
				( attribute "WATTAGE" "1/16W"
					( Origin gFrontEnd )
				)
				( attribute "XY" "(-3925,3525)"
					( Origin gFrontEnd )
				)
				( attribute "CHIPS_PART_NAME" "RES"
					( Origin gPackager )
				)
				( attribute "CDS_PART_NAME" "RES_0402-27.4,1%,1/16W,CHIP,G2A"
					( Origin gPackager )
				)
				( objectStatus "R4D13" )
				( pin "a"
					( attribute "PN" "1"
						( Origin gPackager )
					)
					( objectStatus "R4D13.1" )
				)
				( pin "b"
					( attribute "PN" "2"
						( Origin gPackager )
					)
					( objectStatus "R4D13.2" )
				)
			)
			( gate "@baseboard_fab2_lib.baseboard_fab2(sch_1):page103_i34"
				( attribute "BOM_COST" "SYS_CLOCK"
					( Origin gFrontEnd )
				)
				( attribute "CDS_LIB" "mstr_discrete"
					( Origin gPackager )
				)
				( attribute "CDS_LOCATION" "R4D16"
					( Origin gPackager )
				)
				( attribute "CDS_SEC" "1"
					( Origin gPackager )
				)
				( attribute "LOCATION" "R4D16"
					( Origin gFrontEnd )
				)
				( attribute "MATERIAL" "CHIP"
					( Origin gFrontEnd )
				)
				( attribute "PACK_TYPE" "0402"
					( Origin gFrontEnd )
				)
				( attribute "PART_NUMBER" "G21796-182"
					( Origin gFrontEnd )
				)
				( attribute "PHYS_PAGE" "103"
					( Origin gFrontEnd )
				)
				( attribute "ROOM" "DB1200Z"
					( Origin gFrontEnd )
				)
				( attribute "ROT" "0"
					( Origin gFrontEnd )
				)
				( attribute "SEC" "1"
					( Origin gFrontEnd )
				)
				( attribute "SEC_TYPE" "0402"
					( Origin gFrontEnd )
				)
				( attribute "TOLERANCE" "1%"
					( Origin gFrontEnd )
				)
				( attribute "VALUE" "27.4"
					( Origin gFrontEnd )
				)
				( attribute "VER" "1"
					( Origin gFrontEnd )
				)
				( attribute "WATTAGE" "1/16W"
					( Origin gFrontEnd )
				)
				( attribute "XY" "(-3925,3200)"
					( Origin gFrontEnd )
				)
				( attribute "CHIPS_PART_NAME" "RES"
					( Origin gPackager )
				)
				( attribute "CDS_PART_NAME" "RES_0402-27.4,1%,1/16W,CHIP,G2A"
					( Origin gPackager )
				)
				( objectStatus "R4D16" )
				( pin "a"
					( attribute "PN" "1"
						( Origin gPackager )
					)
					( objectStatus "R4D16.1" )
				)
				( pin "b"
					( attribute "PN" "2"
						( Origin gPackager )
					)
					( objectStatus "R4D16.2" )
				)
			)
			( gate "@baseboard_fab2_lib.baseboard_fab2(sch_1):page103_i39"
				( attribute "BOM_COST" "SYS_CLOCK"
					( Origin gFrontEnd )
				)
				( attribute "CDS_LIB" "mstr_discrete"
					( Origin gPackager )
				)
				( attribute "CDS_LOCATION" "R4D9"
					( Origin gPackager )
				)
				( attribute "CDS_SEC" "1"
					( Origin gPackager )
				)
				( attribute "LOCATION" "R4D9"
					( Origin gFrontEnd )
				)
				( attribute "MATERIAL" "CHIP"
					( Origin gFrontEnd )
				)
				( attribute "PACK_TYPE" "0402"
					( Origin gFrontEnd )
				)
				( attribute "PART_NUMBER" "G21796-182"
					( Origin gFrontEnd )
				)
				( attribute "PHYS_PAGE" "103"
					( Origin gFrontEnd )
				)
				( attribute "ROOM" "DB1200Z"
					( Origin gFrontEnd )
				)
				( attribute "ROT" "0"
					( Origin gFrontEnd )
				)
				( attribute "SEC" "1"
					( Origin gFrontEnd )
				)
				( attribute "SEC_TYPE" "0402"
					( Origin gFrontEnd )
				)
				( attribute "TOLERANCE" "1%"
					( Origin gFrontEnd )
				)
				( attribute "VALUE" "27.4"
					( Origin gFrontEnd )
				)
				( attribute "VER" "1"
					( Origin gFrontEnd )
				)
				( attribute "WATTAGE" "1/16W"
					( Origin gFrontEnd )
				)
				( attribute "XY" "(-3925,2875)"
					( Origin gFrontEnd )
				)
				( attribute "CHIPS_PART_NAME" "RES"
					( Origin gPackager )
				)
				( attribute "CDS_PART_NAME" "RES_0402-27.4,1%,1/16W,CHIP,G2A"
					( Origin gPackager )
				)
				( objectStatus "R4D9" )
				( pin "a"
					( attribute "PN" "1"
						( Origin gPackager )
					)
					( objectStatus "R4D9.1" )
				)
				( pin "b"
					( attribute "PN" "2"
						( Origin gPackager )
					)
					( objectStatus "R4D9.2" )
				)
			)
			( gate "@baseboard_fab2_lib.baseboard_fab2(sch_1):page103_i44"
				( attribute "BOM_COST" "SYS_CLOCK"
					( Origin gFrontEnd )
				)
				( attribute "CDS_LIB" "mstr_discrete"
					( Origin gPackager )
				)
				( attribute "CDS_LOCATION" "R4D11"
					( Origin gPackager )
				)
				( attribute "CDS_SEC" "1"
					( Origin gPackager )
				)
				( attribute "LOCATION" "R4D11"
					( Origin gFrontEnd )
				)
				( attribute "MATERIAL" "CHIP"
					( Origin gFrontEnd )
				)
				( attribute "PACK_TYPE" "0402"
					( Origin gFrontEnd )
				)
				( attribute "PART_NUMBER" "G21796-182"
					( Origin gFrontEnd )
				)
				( attribute "PHYS_PAGE" "103"
					( Origin gFrontEnd )
				)
				( attribute "ROOM" "DB1200Z"
					( Origin gFrontEnd )
				)
				( attribute "ROT" "0"
					( Origin gFrontEnd )
				)
				( attribute "SEC" "1"
					( Origin gFrontEnd )
				)
				( attribute "SEC_TYPE" "0402"
					( Origin gFrontEnd )
				)
				( attribute "TOLERANCE" "1%"
					( Origin gFrontEnd )
				)
				( attribute "VALUE" "27.4"
					( Origin gFrontEnd )
				)
				( attribute "VER" "1"
					( Origin gFrontEnd )
				)
				( attribute "WATTAGE" "1/16W"
					( Origin gFrontEnd )
				)
				( attribute "XY" "(-3925,2550)"
					( Origin gFrontEnd )
				)
				( attribute "CHIPS_PART_NAME" "RES"
					( Origin gPackager )
				)
				( attribute "CDS_PART_NAME" "RES_0402-27.4,1%,1/16W,CHIP,G2A"
					( Origin gPackager )
				)
				( objectStatus "R4D11" )
				( pin "a"
					( attribute "PN" "1"
						( Origin gPackager )
					)
					( objectStatus "R4D11.1" )
				)
				( pin "b"
					( attribute "PN" "2"
						( Origin gPackager )
					)
					( objectStatus "R4D11.2" )
				)
			)
			( gate "@baseboard_fab2_lib.baseboard_fab2(sch_1):page103_i49"
				( attribute "BOM_COST" "SYS_CLOCK"
					( Origin gFrontEnd )
				)
				( attribute "CDS_LIB" "mstr_discrete"
					( Origin gPackager )
				)
				( attribute "CDS_LOCATION" "R4D2"
					( Origin gPackager )
				)
				( attribute "CDS_SEC" "1"
					( Origin gPackager )
				)
				( attribute "LOCATION" "R4D2"
					( Origin gFrontEnd )
				)
				( attribute "MATERIAL" "CHIP"
					( Origin gFrontEnd )
				)
				( attribute "PACK_TYPE" "0402"
					( Origin gFrontEnd )
				)
				( attribute "PART_NUMBER" "G21796-182"
					( Origin gFrontEnd )
				)
				( attribute "PHYS_PAGE" "103"
					( Origin gFrontEnd )
				)
				( attribute "ROOM" "DB1200Z"
					( Origin gFrontEnd )
				)
				( attribute "ROT" "0"
					( Origin gFrontEnd )
				)
				( attribute "SEC" "1"
					( Origin gPackager )
				)
				( attribute "TOLERANCE" "1%"
					( Origin gFrontEnd )
				)
				( attribute "VALUE" "27.4"
					( Origin gFrontEnd )
				)
				( attribute "VER" "1"
					( Origin gFrontEnd )
				)
				( attribute "WATTAGE" "1/16W"
					( Origin gFrontEnd )
				)
				( attribute "XY" "(-3925,2225)"
					( Origin gFrontEnd )
				)
				( attribute "CHIPS_PART_NAME" "RES"
					( Origin gPackager )
				)
				( attribute "CDS_PART_NAME" "RES_0402-27.4,1%,1/16W,CHIP,G2A"
					( Origin gPackager )
				)
				( objectStatus "R4D2" )
				( pin "a"
					( attribute "PN" "1"
						( Origin gPackager )
					)
					( objectStatus "R4D2.1" )
				)
				( pin "b"
					( attribute "PN" "2"
						( Origin gPackager )
					)
					( objectStatus "R4D2.2" )
				)
			)
			( gate "@baseboard_fab2_lib.baseboard_fab2(sch_1):page103_i54"
				( attribute "BOM_COST" "SYS_CLOCK"
					( Origin gFrontEnd )
				)
				( attribute "CDS_LIB" "mstr_discrete"
					( Origin gPackager )
				)
				( attribute "CDS_LOCATION" "R4D1"
					( Origin gPackager )
				)
				( attribute "CDS_SEC" "1"
					( Origin gPackager )
				)
				( attribute "LOCATION" "R4D1"
					( Origin gFrontEnd )
				)
				( attribute "MATERIAL" "CHIP"
					( Origin gFrontEnd )
				)
				( attribute "PACK_TYPE" "0402"
					( Origin gFrontEnd )
				)
				( attribute "PART_NUMBER" "G21796-182"
					( Origin gFrontEnd )
				)
				( attribute "PHYS_PAGE" "103"
					( Origin gFrontEnd )
				)
				( attribute "ROOM" "DB1200Z"
					( Origin gFrontEnd )
				)
				( attribute "ROT" "0"
					( Origin gFrontEnd )
				)
				( attribute "SEC" "1"
					( Origin gFrontEnd )
				)
				( attribute "SEC_TYPE" "0402"
					( Origin gFrontEnd )
				)
				( attribute "TOLERANCE" "1%"
					( Origin gFrontEnd )
				)
				( attribute "VALUE" "27.4"
					( Origin gFrontEnd )
				)
				( attribute "VER" "1"
					( Origin gFrontEnd )
				)
				( attribute "WATTAGE" "1/16W"
					( Origin gFrontEnd )
				)
				( attribute "XY" "(-3925,1900)"
					( Origin gFrontEnd )
				)
				( attribute "CHIPS_PART_NAME" "RES"
					( Origin gPackager )
				)
				( attribute "CDS_PART_NAME" "RES_0402-27.4,1%,1/16W,CHIP,G2A"
					( Origin gPackager )
				)
				( objectStatus "R4D1" )
				( pin "a"
					( attribute "PN" "1"
						( Origin gPackager )
					)
					( objectStatus "R4D1.1" )
				)
				( pin "b"
					( attribute "PN" "2"
						( Origin gPackager )
					)
					( objectStatus "R4D1.2" )
				)
			)
			( gate "@baseboard_fab2_lib.baseboard_fab2(sch_1):page103_i59"
				( attribute "BOM_COST" "SYS_CLOCK"
					( Origin gFrontEnd )
				)
				( attribute "CDS_LIB" "mstr_discrete"
					( Origin gPackager )
				)
				( attribute "CDS_LOCATION" "R4D4"
					( Origin gPackager )
				)
				( attribute "CDS_SEC" "1"
					( Origin gPackager )
				)
				( attribute "LOCATION" "R4D4"
					( Origin gFrontEnd )
				)
				( attribute "MATERIAL" "CHIP"
					( Origin gFrontEnd )
				)
				( attribute "PACK_TYPE" "0402"
					( Origin gFrontEnd )
				)
				( attribute "PART_NUMBER" "G21796-182"
					( Origin gFrontEnd )
				)
				( attribute "PHYS_PAGE" "103"
					( Origin gFrontEnd )
				)
				( attribute "ROOM" "DB1200Z"
					( Origin gFrontEnd )
				)
				( attribute "ROT" "0"
					( Origin gFrontEnd )
				)
				( attribute "SEC" "1"
					( Origin gFrontEnd )
				)
				( attribute "SEC_TYPE" "0402"
					( Origin gFrontEnd )
				)
				( attribute "TOLERANCE" "1%"
					( Origin gFrontEnd )
				)
				( attribute "VALUE" "27.4"
					( Origin gFrontEnd )
				)
				( attribute "VER" "1"
					( Origin gFrontEnd )
				)
				( attribute "WATTAGE" "1/16W"
					( Origin gFrontEnd )
				)
				( attribute "XY" "(-3925,1575)"
					( Origin gFrontEnd )
				)
				( attribute "CHIPS_PART_NAME" "RES"
					( Origin gPackager )
				)
				( attribute "CDS_PART_NAME" "RES_0402-27.4,1%,1/16W,CHIP,G2A"
					( Origin gPackager )
				)
				( objectStatus "R4D4" )
				( pin "a"
					( attribute "PN" "1"
						( Origin gPackager )
					)
					( objectStatus "R4D4.1" )
				)
				( pin "b"
					( attribute "PN" "2"
						( Origin gPackager )
					)
					( objectStatus "R4D4.2" )
				)
			)
			( gate "@baseboard_fab2_lib.baseboard_fab2(sch_1):page103_i64"
				( attribute "BOM_COST" "SYS_CLOCK"
					( Origin gFrontEnd )
				)
				( attribute "CDS_LIB" "mstr_discrete"
					( Origin gPackager )
				)
				( attribute "CDS_LOCATION" "R4D3"
					( Origin gPackager )
				)
				( attribute "CDS_SEC" "1"
					( Origin gPackager )
				)
				( attribute "LOCATION" "R4D3"
					( Origin gFrontEnd )
				)
				( attribute "MATERIAL" "CHIP"
					( Origin gFrontEnd )
				)
				( attribute "PACK_TYPE" "0402"
					( Origin gFrontEnd )
				)
				( attribute "PART_NUMBER" "G21796-182"
					( Origin gFrontEnd )
				)
				( attribute "PHYS_PAGE" "103"
					( Origin gFrontEnd )
				)
				( attribute "ROOM" "DB1200Z"
					( Origin gFrontEnd )
				)
				( attribute "ROT" "0"
					( Origin gFrontEnd )
				)
				( attribute "SEC" "1"
					( Origin gFrontEnd )
				)
				( attribute "SEC_TYPE" "0402"
					( Origin gFrontEnd )
				)
				( attribute "TOLERANCE" "1%"
					( Origin gFrontEnd )
				)
				( attribute "VALUE" "27.4"
					( Origin gFrontEnd )
				)
				( attribute "VER" "1"
					( Origin gFrontEnd )
				)
				( attribute "WATTAGE" "1/16W"
					( Origin gFrontEnd )
				)
				( attribute "XY" "(-3925,1250)"
					( Origin gFrontEnd )
				)
				( attribute "CHIPS_PART_NAME" "RES"
					( Origin gPackager )
				)
				( attribute "CDS_PART_NAME" "RES_0402-27.4,1%,1/16W,CHIP,G2A"
					( Origin gPackager )
				)
				( objectStatus "R4D3" )
				( pin "a"
					( attribute "PN" "1"
						( Origin gPackager )
					)
					( objectStatus "R4D3.1" )
				)
				( pin "b"
					( attribute "PN" "2"
						( Origin gPackager )
					)
					( objectStatus "R4D3.2" )
				)
			)
			( gate "@baseboard_fab2_lib.baseboard_fab2(sch_1):page103_i69"
				( attribute "BOM_COST" "SYS_CLOCK"
					( Origin gFrontEnd )
				)
				( attribute "CDS_LIB" "mstr_discrete"
					( Origin gPackager )
				)
				( attribute "CDS_LOCATION" "R4D29"
					( Origin gPackager )
				)
				( attribute "CDS_SEC" "1"
					( Origin gPackager )
				)
				( attribute "LOCATION" "R4D29"
					( Origin gFrontEnd )
				)
				( attribute "MATERIAL" "CHIP"
					( Origin gFrontEnd )
				)
				( attribute "PACK_TYPE" "0402"
					( Origin gFrontEnd )
				)
				( attribute "PART_NUMBER" "G21796-182"
					( Origin gFrontEnd )
				)
				( attribute "PHYS_PAGE" "103"
					( Origin gFrontEnd )
				)
				( attribute "ROOM" "DB1200Z"
					( Origin gFrontEnd )
				)
				( attribute "ROT" "0"
					( Origin gFrontEnd )
				)
				( attribute "SEC" "1"
					( Origin gFrontEnd )
				)
				( attribute "SEC_TYPE" "0402"
					( Origin gFrontEnd )
				)
				( attribute "TOLERANCE" "1%"
					( Origin gFrontEnd )
				)
				( attribute "VALUE" "27.4"
					( Origin gFrontEnd )
				)
				( attribute "VER" "1"
					( Origin gFrontEnd )
				)
				( attribute "WATTAGE" "1/16W"
					( Origin gFrontEnd )
				)
				( attribute "XY" "(300,1575)"
					( Origin gFrontEnd )
				)
				( attribute "CHIPS_PART_NAME" "RES"
					( Origin gPackager )
				)
				( attribute "CDS_PART_NAME" "RES_0402-27.4,1%,1/16W,CHIP,G2A"
					( Origin gPackager )
				)
				( objectStatus "R4D29" )
				( pin "a"
					( attribute "PN" "1"
						( Origin gPackager )
					)
					( objectStatus "R4D29.1" )
				)
				( pin "b"
					( attribute "PN" "2"
						( Origin gPackager )
					)
					( objectStatus "R4D29.2" )
				)
			)
			( gate "@baseboard_fab2_lib.baseboard_fab2(sch_1):page103_i74"
				( attribute "BOM_COST" "SYS_CLOCK"
					( Origin gFrontEnd )
				)
				( attribute "CDS_LIB" "mstr_discrete"
					( Origin gPackager )
				)
				( attribute "CDS_LOCATION" "R4D6"
					( Origin gPackager )
				)
				( attribute "CDS_SEC" "1"
					( Origin gPackager )
				)
				( attribute "LOCATION" "R4D6"
					( Origin gFrontEnd )
				)
				( attribute "MATERIAL" "CHIP"
					( Origin gFrontEnd )
				)
				( attribute "PACK_TYPE" "0402"
					( Origin gFrontEnd )
				)
				( attribute "PART_NUMBER" "G21796-182"
					( Origin gFrontEnd )
				)
				( attribute "PHYS_PAGE" "103"
					( Origin gFrontEnd )
				)
				( attribute "ROOM" "DB1200Z"
					( Origin gFrontEnd )
				)
				( attribute "ROT" "0"
					( Origin gFrontEnd )
				)
				( attribute "SEC" "1"
					( Origin gFrontEnd )
				)
				( attribute "SEC_TYPE" "0402"
					( Origin gFrontEnd )
				)
				( attribute "TOLERANCE" "1%"
					( Origin gFrontEnd )
				)
				( attribute "VALUE" "27.4"
					( Origin gFrontEnd )
				)
				( attribute "VER" "1"
					( Origin gFrontEnd )
				)
				( attribute "WATTAGE" "1/16W"
					( Origin gFrontEnd )
				)
				( attribute "XY" "(300,4825)"
					( Origin gFrontEnd )
				)
				( attribute "CHIPS_PART_NAME" "RES"
					( Origin gPackager )
				)
				( attribute "CDS_PART_NAME" "RES_0402-27.4,1%,1/16W,CHIP,G2A"
					( Origin gPackager )
				)
				( objectStatus "R4D6" )
				( pin "a"
					( attribute "PN" "1"
						( Origin gPackager )
					)
					( objectStatus "R4D6.1" )
				)
				( pin "b"
					( attribute "PN" "2"
						( Origin gPackager )
					)
					( objectStatus "R4D6.2" )
				)
			)
			( gate "@baseboard_fab2_lib.baseboard_fab2(sch_1):page103_i79"
				( attribute "BOM_COST" "SYS_CLOCK"
					( Origin gFrontEnd )
				)
				( attribute "CDS_LIB" "mstr_discrete"
					( Origin gPackager )
				)
				( attribute "CDS_LOCATION" "R4D5"
					( Origin gPackager )
				)
				( attribute "CDS_SEC" "1"
					( Origin gPackager )
				)
				( attribute "LOCATION" "R4D5"
					( Origin gFrontEnd )
				)
				( attribute "MATERIAL" "CHIP"
					( Origin gFrontEnd )
				)
				( attribute "PACK_TYPE" "0402"
					( Origin gFrontEnd )
				)
				( attribute "PART_NUMBER" "G21796-182"
					( Origin gFrontEnd )
				)
				( attribute "PHYS_PAGE" "103"
					( Origin gFrontEnd )
				)
				( attribute "ROOM" "DB1200Z"
					( Origin gFrontEnd )
				)
				( attribute "ROT" "0"
					( Origin gFrontEnd )
				)
				( attribute "SEC" "1"
					( Origin gFrontEnd )
				)
				( attribute "SEC_TYPE" "0402"
					( Origin gFrontEnd )
				)
				( attribute "TOLERANCE" "1%"
					( Origin gFrontEnd )
				)
				( attribute "VALUE" "27.4"
					( Origin gFrontEnd )
				)
				( attribute "VER" "1"
					( Origin gFrontEnd )
				)
				( attribute "WATTAGE" "1/16W"
					( Origin gFrontEnd )
				)
				( attribute "XY" "(300,4500)"
					( Origin gFrontEnd )
				)
				( attribute "CHIPS_PART_NAME" "RES"
					( Origin gPackager )
				)
				( attribute "CDS_PART_NAME" "RES_0402-27.4,1%,1/16W,CHIP,G2A"
					( Origin gPackager )
				)
				( objectStatus "R4D5" )
				( pin "a"
					( attribute "PN" "1"
						( Origin gPackager )
					)
					( objectStatus "R4D5.1" )
				)
				( pin "b"
					( attribute "PN" "2"
						( Origin gPackager )
					)
					( objectStatus "R4D5.2" )
				)
			)
			( gate "@baseboard_fab2_lib.baseboard_fab2(sch_1):page103_i84"
				( attribute "BOM_COST" "SYS_CLOCK"
					( Origin gFrontEnd )
				)
				( attribute "CDS_LIB" "mstr_discrete"
					( Origin gPackager )
				)
				( attribute "CDS_LOCATION" "R4D8"
					( Origin gPackager )
				)
				( attribute "CDS_SEC" "1"
					( Origin gPackager )
				)
				( attribute "LOCATION" "R4D8"
					( Origin gFrontEnd )
				)
				( attribute "MATERIAL" "CHIP"
					( Origin gFrontEnd )
				)
				( attribute "PACK_TYPE" "0402"
					( Origin gFrontEnd )
				)
				( attribute "PART_NUMBER" "G21796-182"
					( Origin gFrontEnd )
				)
				( attribute "PHYS_PAGE" "103"
					( Origin gFrontEnd )
				)
				( attribute "ROOM" "DB1200Z"
					( Origin gFrontEnd )
				)
				( attribute "ROT" "0"
					( Origin gFrontEnd )
				)
				( attribute "SEC" "1"
					( Origin gFrontEnd )
				)
				( attribute "SEC_TYPE" "0402"
					( Origin gFrontEnd )
				)
				( attribute "TOLERANCE" "1%"
					( Origin gFrontEnd )
				)
				( attribute "VALUE" "27.4"
					( Origin gFrontEnd )
				)
				( attribute "VER" "1"
					( Origin gFrontEnd )
				)
				( attribute "WATTAGE" "1/16W"
					( Origin gFrontEnd )
				)
				( attribute "XY" "(300,4175)"
					( Origin gFrontEnd )
				)
				( attribute "CHIPS_PART_NAME" "RES"
					( Origin gPackager )
				)
				( attribute "CDS_PART_NAME" "RES_0402-27.4,1%,1/16W,CHIP,G2A"
					( Origin gPackager )
				)
				( objectStatus "R4D8" )
				( pin "a"
					( attribute "PN" "1"
						( Origin gPackager )
					)
					( objectStatus "R4D8.1" )
				)
				( pin "b"
					( attribute "PN" "2"
						( Origin gPackager )
					)
					( objectStatus "R4D8.2" )
				)
			)
			( gate "@baseboard_fab2_lib.baseboard_fab2(sch_1):page103_i89"
				( attribute "BOM_COST" "SYS_CLOCK"
					( Origin gFrontEnd )
				)
				( attribute "CDS_LIB" "mstr_discrete"
					( Origin gPackager )
				)
				( attribute "CDS_LOCATION" "R4D7"
					( Origin gPackager )
				)
				( attribute "CDS_SEC" "1"
					( Origin gPackager )
				)
				( attribute "LOCATION" "R4D7"
					( Origin gFrontEnd )
				)
				( attribute "MATERIAL" "CHIP"
					( Origin gFrontEnd )
				)
				( attribute "PACK_TYPE" "0402"
					( Origin gFrontEnd )
				)
				( attribute "PART_NUMBER" "G21796-182"
					( Origin gFrontEnd )
				)
				( attribute "PHYS_PAGE" "103"
					( Origin gFrontEnd )
				)
				( attribute "ROOM" "DB1200Z"
					( Origin gFrontEnd )
				)
				( attribute "ROT" "0"
					( Origin gFrontEnd )
				)
				( attribute "SEC" "1"
					( Origin gFrontEnd )
				)
				( attribute "SEC_TYPE" "0402"
					( Origin gFrontEnd )
				)
				( attribute "TOLERANCE" "1%"
					( Origin gFrontEnd )
				)
				( attribute "VALUE" "27.4"
					( Origin gFrontEnd )
				)
				( attribute "VER" "1"
					( Origin gFrontEnd )
				)
				( attribute "WATTAGE" "1/16W"
					( Origin gFrontEnd )
				)
				( attribute "XY" "(300,3850)"
					( Origin gFrontEnd )
				)
				( attribute "CHIPS_PART_NAME" "RES"
					( Origin gPackager )
				)
				( attribute "CDS_PART_NAME" "RES_0402-27.4,1%,1/16W,CHIP,G2A"
					( Origin gPackager )
				)
				( objectStatus "R4D7" )
				( pin "a"
					( attribute "PN" "1"
						( Origin gPackager )
					)
					( objectStatus "R4D7.1" )
				)
				( pin "b"
					( attribute "PN" "2"
						( Origin gPackager )
					)
					( objectStatus "R4D7.2" )
				)
			)
			( gate "@baseboard_fab2_lib.baseboard_fab2(sch_1):page103_i94"
				( attribute "BOM_COST" "SYS_CLOCK"
					( Origin gFrontEnd )
				)
				( attribute "CDS_LIB" "mstr_discrete"
					( Origin gPackager )
				)
				( attribute "CDS_LOCATION" "R4D12"
					( Origin gPackager )
				)
				( attribute "CDS_SEC" "1"
					( Origin gPackager )
				)
				( attribute "LOCATION" "R4D12"
					( Origin gFrontEnd )
				)
				( attribute "MATERIAL" "CHIP"
					( Origin gFrontEnd )
				)
				( attribute "PACK_TYPE" "0402"
					( Origin gFrontEnd )
				)
				( attribute "PART_NUMBER" "G21796-182"
					( Origin gFrontEnd )
				)
				( attribute "PHYS_PAGE" "103"
					( Origin gFrontEnd )
				)
				( attribute "ROOM" "DB1200Z"
					( Origin gFrontEnd )
				)
				( attribute "ROT" "0"
					( Origin gFrontEnd )
				)
				( attribute "SEC" "1"
					( Origin gFrontEnd )
				)
				( attribute "SEC_TYPE" "0402"
					( Origin gFrontEnd )
				)
				( attribute "TOLERANCE" "1%"
					( Origin gFrontEnd )
				)
				( attribute "VALUE" "27.4"
					( Origin gFrontEnd )
				)
				( attribute "VER" "1"
					( Origin gFrontEnd )
				)
				( attribute "WATTAGE" "1/16W"
					( Origin gFrontEnd )
				)
				( attribute "XY" "(300,3525)"
					( Origin gFrontEnd )
				)
				( attribute "CHIPS_PART_NAME" "RES"
					( Origin gPackager )
				)
				( attribute "CDS_PART_NAME" "RES_0402-27.4,1%,1/16W,CHIP,G2A"
					( Origin gPackager )
				)
				( objectStatus "R4D12" )
				( pin "a"
					( attribute "PN" "1"
						( Origin gPackager )
					)
					( objectStatus "R4D12.1" )
				)
				( pin "b"
					( attribute "PN" "2"
						( Origin gPackager )
					)
					( objectStatus "R4D12.2" )
				)
			)
			( gate "@baseboard_fab2_lib.baseboard_fab2(sch_1):page103_i99"
				( attribute "BOM_COST" "SYS_CLOCK"
					( Origin gFrontEnd )
				)
				( attribute "CDS_LIB" "mstr_discrete"
					( Origin gPackager )
				)
				( attribute "CDS_LOCATION" "R4D10"
					( Origin gPackager )
				)
				( attribute "CDS_SEC" "1"
					( Origin gPackager )
				)
				( attribute "LOCATION" "R4D10"
					( Origin gFrontEnd )
				)
				( attribute "MATERIAL" "CHIP"
					( Origin gFrontEnd )
				)
				( attribute "PACK_TYPE" "0402"
					( Origin gFrontEnd )
				)
				( attribute "PART_NUMBER" "G21796-182"
					( Origin gFrontEnd )
				)
				( attribute "PHYS_PAGE" "103"
					( Origin gFrontEnd )
				)
				( attribute "ROOM" "DB1200Z"
					( Origin gFrontEnd )
				)
				( attribute "ROT" "0"
					( Origin gFrontEnd )
				)
				( attribute "SEC" "1"
					( Origin gFrontEnd )
				)
				( attribute "SEC_TYPE" "0402"
					( Origin gFrontEnd )
				)
				( attribute "TOLERANCE" "1%"
					( Origin gFrontEnd )
				)
				( attribute "VALUE" "27.4"
					( Origin gFrontEnd )
				)
				( attribute "VER" "1"
					( Origin gFrontEnd )
				)
				( attribute "WATTAGE" "1/16W"
					( Origin gFrontEnd )
				)
				( attribute "XY" "(300,3200)"
					( Origin gFrontEnd )
				)
				( attribute "CHIPS_PART_NAME" "RES"
					( Origin gPackager )
				)
				( attribute "CDS_PART_NAME" "RES_0402-27.4,1%,1/16W,CHIP,G2A"
					( Origin gPackager )
				)
				( objectStatus "R4D10" )
				( pin "a"
					( attribute "PN" "1"
						( Origin gPackager )
					)
					( objectStatus "R4D10.1" )
				)
				( pin "b"
					( attribute "PN" "2"
						( Origin gPackager )
					)
					( objectStatus "R4D10.2" )
				)
			)
			( gate "@baseboard_fab2_lib.baseboard_fab2(sch_1):page103_i104"
				( attribute "BOM_COST" "SYS_CLOCK"
					( Origin gFrontEnd )
				)
				( attribute "CDS_LIB" "mstr_discrete"
					( Origin gPackager )
				)
				( attribute "CDS_LOCATION" "R4D17"
					( Origin gPackager )
				)
				( attribute "CDS_SEC" "1"
					( Origin gPackager )
				)
				( attribute "LOCATION" "R4D17"
					( Origin gFrontEnd )
				)
				( attribute "MATERIAL" "CHIP"
					( Origin gFrontEnd )
				)
				( attribute "PACK_TYPE" "0402"
					( Origin gFrontEnd )
				)
				( attribute "PART_NUMBER" "G21796-182"
					( Origin gFrontEnd )
				)
				( attribute "PHYS_PAGE" "103"
					( Origin gFrontEnd )
				)
				( attribute "ROOM" "DB1200Z"
					( Origin gFrontEnd )
				)
				( attribute "ROT" "0"
					( Origin gFrontEnd )
				)
				( attribute "SEC" "1"
					( Origin gFrontEnd )
				)
				( attribute "SEC_TYPE" "0402"
					( Origin gFrontEnd )
				)
				( attribute "TOLERANCE" "1%"
					( Origin gFrontEnd )
				)
				( attribute "VALUE" "27.4"
					( Origin gFrontEnd )
				)
				( attribute "VER" "1"
					( Origin gFrontEnd )
				)
				( attribute "WATTAGE" "1/16W"
					( Origin gFrontEnd )
				)
				( attribute "XY" "(300,2875)"
					( Origin gFrontEnd )
				)
				( attribute "CHIPS_PART_NAME" "RES"
					( Origin gPackager )
				)
				( attribute "CDS_PART_NAME" "RES_0402-27.4,1%,1/16W,CHIP,G2A"
					( Origin gPackager )
				)
				( objectStatus "R4D17" )
				( pin "a"
					( attribute "PN" "1"
						( Origin gPackager )
					)
					( objectStatus "R4D17.1" )
				)
				( pin "b"
					( attribute "PN" "2"
						( Origin gPackager )
					)
					( objectStatus "R4D17.2" )
				)
			)
			( gate "@baseboard_fab2_lib.baseboard_fab2(sch_1):page103_i109"
				( attribute "BOM_COST" "SYS_CLOCK"
					( Origin gFrontEnd )
				)
				( attribute "CDS_LIB" "mstr_discrete"
					( Origin gPackager )
				)
				( attribute "CDS_LOCATION" "R4D14"
					( Origin gPackager )
				)
				( attribute "CDS_SEC" "1"
					( Origin gPackager )
				)
				( attribute "LOCATION" "R4D14"
					( Origin gFrontEnd )
				)
				( attribute "MATERIAL" "CHIP"
					( Origin gFrontEnd )
				)
				( attribute "PACK_TYPE" "0402"
					( Origin gFrontEnd )
				)
				( attribute "PART_NUMBER" "G21796-182"
					( Origin gFrontEnd )
				)
				( attribute "PHYS_PAGE" "103"
					( Origin gFrontEnd )
				)
				( attribute "ROOM" "DB1200Z"
					( Origin gFrontEnd )
				)
				( attribute "ROT" "0"
					( Origin gFrontEnd )
				)
				( attribute "SEC" "1"
					( Origin gFrontEnd )
				)
				( attribute "SEC_TYPE" "0402"
					( Origin gFrontEnd )
				)
				( attribute "TOLERANCE" "1%"
					( Origin gFrontEnd )
				)
				( attribute "VALUE" "27.4"
					( Origin gFrontEnd )
				)
				( attribute "VER" "1"
					( Origin gFrontEnd )
				)
				( attribute "WATTAGE" "1/16W"
					( Origin gFrontEnd )
				)
				( attribute "XY" "(300,2550)"
					( Origin gFrontEnd )
				)
				( attribute "CHIPS_PART_NAME" "RES"
					( Origin gPackager )
				)
				( attribute "CDS_PART_NAME" "RES_0402-27.4,1%,1/16W,CHIP,G2A"
					( Origin gPackager )
				)
				( objectStatus "R4D14" )
				( pin "a"
					( attribute "PN" "1"
						( Origin gPackager )
					)
					( objectStatus "R4D14.1" )
				)
				( pin "b"
					( attribute "PN" "2"
						( Origin gPackager )
					)
					( objectStatus "R4D14.2" )
				)
			)
			( gate "@baseboard_fab2_lib.baseboard_fab2(sch_1):page103_i114"
				( attribute "BOM_COST" "SYS_CLOCK"
					( Origin gFrontEnd )
				)
				( attribute "CDS_LIB" "mstr_discrete"
					( Origin gPackager )
				)
				( attribute "CDS_LOCATION" "R4D22"
					( Origin gPackager )
				)
				( attribute "CDS_SEC" "1"
					( Origin gPackager )
				)
				( attribute "LOCATION" "R4D22"
					( Origin gFrontEnd )
				)
				( attribute "MATERIAL" "CHIP"
					( Origin gFrontEnd )
				)
				( attribute "PACK_TYPE" "0402"
					( Origin gFrontEnd )
				)
				( attribute "PART_NUMBER" "G21796-182"
					( Origin gFrontEnd )
				)
				( attribute "PHYS_PAGE" "103"
					( Origin gFrontEnd )
				)
				( attribute "ROOM" "DB1200Z"
					( Origin gFrontEnd )
				)
				( attribute "ROT" "0"
					( Origin gFrontEnd )
				)
				( attribute "SEC" "1"
					( Origin gFrontEnd )
				)
				( attribute "SEC_TYPE" "0402"
					( Origin gFrontEnd )
				)
				( attribute "TOLERANCE" "1%"
					( Origin gFrontEnd )
				)
				( attribute "VALUE" "27.4"
					( Origin gFrontEnd )
				)
				( attribute "VER" "1"
					( Origin gFrontEnd )
				)
				( attribute "WATTAGE" "1/16W"
					( Origin gFrontEnd )
				)
				( attribute "XY" "(300,2225)"
					( Origin gFrontEnd )
				)
				( attribute "CHIPS_PART_NAME" "RES"
					( Origin gPackager )
				)
				( attribute "CDS_PART_NAME" "RES_0402-27.4,1%,1/16W,CHIP,G2A"
					( Origin gPackager )
				)
				( objectStatus "R4D22" )
				( pin "a"
					( attribute "PN" "1"
						( Origin gPackager )
					)
					( objectStatus "R4D22.1" )
				)
				( pin "b"
					( attribute "PN" "2"
						( Origin gPackager )
					)
					( objectStatus "R4D22.2" )
				)
			)
			( gate "@baseboard_fab2_lib.baseboard_fab2(sch_1):page103_i119"
				( attribute "BOM_COST" "SYS_CLOCK"
					( Origin gFrontEnd )
				)
				( attribute "CDS_LIB" "mstr_discrete"
					( Origin gPackager )
				)
				( attribute "CDS_LOCATION" "R4D20"
					( Origin gPackager )
				)
				( attribute "CDS_SEC" "1"
					( Origin gPackager )
				)
				( attribute "LOCATION" "R4D20"
					( Origin gFrontEnd )
				)
				( attribute "MATERIAL" "CHIP"
					( Origin gFrontEnd )
				)
				( attribute "PACK_TYPE" "0402"
					( Origin gFrontEnd )
				)
				( attribute "PART_NUMBER" "G21796-182"
					( Origin gFrontEnd )
				)
				( attribute "PHYS_PAGE" "103"
					( Origin gFrontEnd )
				)
				( attribute "ROOM" "DB1200Z"
					( Origin gFrontEnd )
				)
				( attribute "ROT" "0"
					( Origin gFrontEnd )
				)
				( attribute "SEC" "1"
					( Origin gFrontEnd )
				)
				( attribute "SEC_TYPE" "0402"
					( Origin gFrontEnd )
				)
				( attribute "TOLERANCE" "1%"
					( Origin gFrontEnd )
				)
				( attribute "VALUE" "27.4"
					( Origin gFrontEnd )
				)
				( attribute "VER" "1"
					( Origin gFrontEnd )
				)
				( attribute "WATTAGE" "1/16W"
					( Origin gFrontEnd )
				)
				( attribute "XY" "(300,1900)"
					( Origin gFrontEnd )
				)
				( attribute "CHIPS_PART_NAME" "RES"
					( Origin gPackager )
				)
				( attribute "CDS_PART_NAME" "RES_0402-27.4,1%,1/16W,CHIP,G2A"
					( Origin gPackager )
				)
				( objectStatus "R4D20" )
				( pin "a"
					( attribute "PN" "1"
						( Origin gPackager )
					)
					( objectStatus "R4D20.1" )
				)
				( pin "b"
					( attribute "PN" "2"
						( Origin gPackager )
					)
					( objectStatus "R4D20.2" )
				)
			)
			( gate "@baseboard_fab2_lib.baseboard_fab2(sch_1):page103_i121"
				( attribute "BOM_COST" "SYS_CLOCK"
					( Origin gFrontEnd )
				)
				( attribute "CDS_LIB" "mstr_discrete"
					( Origin gPackager )
				)
				( attribute "CDS_LOCATION" "R7P9"
					( Origin gPackager )
				)
				( attribute "CDS_SEC" "1"
					( Origin gPackager )
				)
				( attribute "LOCATION" "R7P9"
					( Origin gFrontEnd )
				)
				( attribute "MATERIAL" "EMPTY"
					( Origin gFrontEnd )
				)
				( attribute "PACK_TYPE" "0402"
					( Origin gFrontEnd )
				)
				( attribute "PART_NUMBER" "G21796-259"
					( Origin gFrontEnd )
				)
				( attribute "PHYS_PAGE" "103"
					( Origin gFrontEnd )
				)
				( attribute "ROOM" "DB1200Z"
					( Origin gFrontEnd )
				)
				( attribute "ROT" "0"
					( Origin gFrontEnd )
				)
				( attribute "SEC" "1"
					( Origin gFrontEnd )
				)
				( attribute "SEC_TYPE" "0402"
					( Origin gFrontEnd )
				)
				( attribute "TOLERANCE" "1.0%"
					( Origin gFrontEnd )
				)
				( attribute "VALUE" "42.2"
					( Origin gFrontEnd )
				)
				( attribute "VER" "1"
					( Origin gFrontEnd )
				)
				( attribute "WATTAGE" "1/16W"
					( Origin gFrontEnd )
				)
				( attribute "XY" "(-3325,4800)"
					( Origin gFrontEnd )
				)
				( attribute "CHIPS_PART_NAME" "RES"
					( Origin gPackager )
				)
				( attribute "CDS_PART_NAME" "RES_0402-42.2,1.0%,1/16W,EMPTYA"
					( Origin gPackager )
				)
				( objectStatus "R7P9" )
				( pin "a"
					( attribute "PN" "1"
						( Origin gPackager )
					)
					( objectStatus "R7P9.1" )
				)
				( pin "b"
					( attribute "PN" "2"
						( Origin gPackager )
					)
					( objectStatus "R7P9.2" )
				)
			)
			( gate "@baseboard_fab2_lib.baseboard_fab2(sch_1):page103_i123"
				( attribute "BOM_COST" "SYS_CLOCK"
					( Origin gFrontEnd )
				)
				( attribute "CDS_LIB" "mstr_discrete"
					( Origin gPackager )
				)
				( attribute "CDS_LOCATION" "R7P12"
					( Origin gPackager )
				)
				( attribute "CDS_SEC" "1"
					( Origin gPackager )
				)
				( attribute "LOCATION" "R7P12"
					( Origin gFrontEnd )
				)
				( attribute "MATERIAL" "EMPTY"
					( Origin gFrontEnd )
				)
				( attribute "PACK_TYPE" "0402"
					( Origin gFrontEnd )
				)
				( attribute "PART_NUMBER" "G21796-259"
					( Origin gFrontEnd )
				)
				( attribute "PHYS_PAGE" "103"
					( Origin gFrontEnd )
				)
				( attribute "ROOM" "DB1200Z"
					( Origin gFrontEnd )
				)
				( attribute "ROT" "0"
					( Origin gFrontEnd )
				)
				( attribute "SEC" "1"
					( Origin gFrontEnd )
				)
				( attribute "SEC_TYPE" "0402"
					( Origin gFrontEnd )
				)
				( attribute "TOLERANCE" "1.0%"
					( Origin gFrontEnd )
				)
				( attribute "VALUE" "42.2"
					( Origin gFrontEnd )
				)
				( attribute "VER" "1"
					( Origin gFrontEnd )
				)
				( attribute "WATTAGE" "1/16W"
					( Origin gFrontEnd )
				)
				( attribute "XY" "(-3300,4425)"
					( Origin gFrontEnd )
				)
				( attribute "CHIPS_PART_NAME" "RES"
					( Origin gPackager )
				)
				( attribute "CDS_PART_NAME" "RES_0402-42.2,1.0%,1/16W,EMPTYA"
					( Origin gPackager )
				)
				( objectStatus "R7P12" )
				( pin "a"
					( attribute "PN" "1"
						( Origin gPackager )
					)
					( objectStatus "R7P12.1" )
				)
				( pin "b"
					( attribute "PN" "2"
						( Origin gPackager )
					)
					( objectStatus "R7P12.2" )
				)
			)
			( gate "@baseboard_fab2_lib.baseboard_fab2(sch_1):page103_i125"
				( attribute "BOM_COST" "SYS_CLOCK"
					( Origin gFrontEnd )
				)
				( attribute "CDS_LIB" "mstr_discrete"
					( Origin gPackager )
				)
				( attribute "CDS_LOCATION" "R7P6"
					( Origin gPackager )
				)
				( attribute "CDS_SEC" "1"
					( Origin gPackager )
				)
				( attribute "LOCATION" "R7P6"
					( Origin gFrontEnd )
				)
				( attribute "MATERIAL" "EMPTY"
					( Origin gFrontEnd )
				)
				( attribute "PACK_TYPE" "0402"
					( Origin gFrontEnd )
				)
				( attribute "PART_NUMBER" "G21796-259"
					( Origin gFrontEnd )
				)
				( attribute "PHYS_PAGE" "103"
					( Origin gFrontEnd )
				)
				( attribute "ROOM" "DB1200Z"
					( Origin gFrontEnd )
				)
				( attribute "ROT" "0"
					( Origin gFrontEnd )
				)
				( attribute "SEC" "1"
					( Origin gFrontEnd )
				)
				( attribute "SEC_TYPE" "0402"
					( Origin gFrontEnd )
				)
				( attribute "TOLERANCE" "1.0%"
					( Origin gFrontEnd )
				)
				( attribute "VALUE" "42.2"
					( Origin gFrontEnd )
				)
				( attribute "VER" "1"
					( Origin gFrontEnd )
				)
				( attribute "WATTAGE" "1/16W"
					( Origin gFrontEnd )
				)
				( attribute "XY" "(-3325,4075)"
					( Origin gFrontEnd )
				)
				( attribute "CHIPS_PART_NAME" "RES"
					( Origin gPackager )
				)
				( attribute "CDS_PART_NAME" "RES_0402-42.2,1.0%,1/16W,EMPTYA"
					( Origin gPackager )
				)
				( objectStatus "R7P6" )
				( pin "a"
					( attribute "PN" "1"
						( Origin gPackager )
					)
					( objectStatus "R7P6.1" )
				)
				( pin "b"
					( attribute "PN" "2"
						( Origin gPackager )
					)
					( objectStatus "R7P6.2" )
				)
			)
			( gate "@baseboard_fab2_lib.baseboard_fab2(sch_1):page103_i127"
				( attribute "BOM_COST" "SYS_CLOCK"
					( Origin gFrontEnd )
				)
				( attribute "CDS_LIB" "mstr_discrete"
					( Origin gPackager )
				)
				( attribute "CDS_LOCATION" "R7P7"
					( Origin gPackager )
				)
				( attribute "CDS_SEC" "1"
					( Origin gPackager )
				)
				( attribute "LOCATION" "R7P7"
					( Origin gFrontEnd )
				)
				( attribute "MATERIAL" "EMPTY"
					( Origin gFrontEnd )
				)
				( attribute "PACK_TYPE" "0402"
					( Origin gFrontEnd )
				)
				( attribute "PART_NUMBER" "G21796-259"
					( Origin gFrontEnd )
				)
				( attribute "PHYS_PAGE" "103"
					( Origin gFrontEnd )
				)
				( attribute "ROOM" "DB1200Z"
					( Origin gFrontEnd )
				)
				( attribute "ROT" "0"
					( Origin gFrontEnd )
				)
				( attribute "SEC" "1"
					( Origin gPackager )
				)
				( attribute "TOLERANCE" "1.0%"
					( Origin gFrontEnd )
				)
				( attribute "VALUE" "42.2"
					( Origin gFrontEnd )
				)
				( attribute "VER" "1"
					( Origin gFrontEnd )
				)
				( attribute "WATTAGE" "1/16W"
					( Origin gFrontEnd )
				)
				( attribute "XY" "(-3325,3750)"
					( Origin gFrontEnd )
				)
				( attribute "CHIPS_PART_NAME" "RES"
					( Origin gPackager )
				)
				( attribute "CDS_PART_NAME" "RES_0402-42.2,1.0%,1/16W,EMPTYA"
					( Origin gPackager )
				)
				( objectStatus "R7P7" )
				( pin "a"
					( attribute "PN" "1"
						( Origin gPackager )
					)
					( objectStatus "R7P7.1" )
				)
				( pin "b"
					( attribute "PN" "2"
						( Origin gPackager )
					)
					( objectStatus "R7P7.2" )
				)
			)
			( gate "@baseboard_fab2_lib.baseboard_fab2(sch_1):page103_i129"
				( attribute "BOM_COST" "SYS_CLOCK"
					( Origin gFrontEnd )
				)
				( attribute "CDS_LIB" "mstr_discrete"
					( Origin gPackager )
				)
				( attribute "CDS_LOCATION" "R7P3"
					( Origin gPackager )
				)
				( attribute "CDS_SEC" "1"
					( Origin gPackager )
				)
				( attribute "LOCATION" "R7P3"
					( Origin gFrontEnd )
				)
				( attribute "MATERIAL" "EMPTY"
					( Origin gFrontEnd )
				)
				( attribute "PACK_TYPE" "0402"
					( Origin gFrontEnd )
				)
				( attribute "PART_NUMBER" "G21796-259"
					( Origin gFrontEnd )
				)
				( attribute "PHYS_PAGE" "103"
					( Origin gFrontEnd )
				)
				( attribute "ROOM" "DB1200Z"
					( Origin gFrontEnd )
				)
				( attribute "ROT" "0"
					( Origin gFrontEnd )
				)
				( attribute "SEC" "1"
					( Origin gFrontEnd )
				)
				( attribute "SEC_TYPE" "0402"
					( Origin gFrontEnd )
				)
				( attribute "TOLERANCE" "1.0%"
					( Origin gFrontEnd )
				)
				( attribute "VALUE" "42.2"
					( Origin gFrontEnd )
				)
				( attribute "VER" "1"
					( Origin gFrontEnd )
				)
				( attribute "WATTAGE" "1/16W"
					( Origin gFrontEnd )
				)
				( attribute "XY" "(-3325,3425)"
					( Origin gFrontEnd )
				)
				( attribute "CHIPS_PART_NAME" "RES"
					( Origin gPackager )
				)
				( attribute "CDS_PART_NAME" "RES_0402-42.2,1.0%,1/16W,EMPTYA"
					( Origin gPackager )
				)
				( objectStatus "R7P3" )
				( pin "a"
					( attribute "PN" "1"
						( Origin gPackager )
					)
					( objectStatus "R7P3.1" )
				)
				( pin "b"
					( attribute "PN" "2"
						( Origin gPackager )
					)
					( objectStatus "R7P3.2" )
				)
			)
			( gate "@baseboard_fab2_lib.baseboard_fab2(sch_1):page103_i131"
				( attribute "BOM_COST" "SYS_CLOCK"
					( Origin gFrontEnd )
				)
				( attribute "CDS_LIB" "mstr_discrete"
					( Origin gPackager )
				)
				( attribute "CDS_LOCATION" "R7P4"
					( Origin gPackager )
				)
				( attribute "CDS_SEC" "1"
					( Origin gPackager )
				)
				( attribute "LOCATION" "R7P4"
					( Origin gFrontEnd )
				)
				( attribute "MATERIAL" "EMPTY"
					( Origin gFrontEnd )
				)
				( attribute "PACK_TYPE" "0402"
					( Origin gFrontEnd )
				)
				( attribute "PART_NUMBER" "G21796-259"
					( Origin gFrontEnd )
				)
				( attribute "PHYS_PAGE" "103"
					( Origin gFrontEnd )
				)
				( attribute "ROOM" "DB1200Z"
					( Origin gFrontEnd )
				)
				( attribute "ROT" "0"
					( Origin gFrontEnd )
				)
				( attribute "SEC" "1"
					( Origin gFrontEnd )
				)
				( attribute "SEC_TYPE" "0402"
					( Origin gFrontEnd )
				)
				( attribute "TOLERANCE" "1.0%"
					( Origin gFrontEnd )
				)
				( attribute "VALUE" "42.2"
					( Origin gFrontEnd )
				)
				( attribute "VER" "1"
					( Origin gFrontEnd )
				)
				( attribute "WATTAGE" "1/16W"
					( Origin gFrontEnd )
				)
				( attribute "XY" "(-3325,3100)"
					( Origin gFrontEnd )
				)
				( attribute "CHIPS_PART_NAME" "RES"
					( Origin gPackager )
				)
				( attribute "CDS_PART_NAME" "RES_0402-42.2,1.0%,1/16W,EMPTYA"
					( Origin gPackager )
				)
				( objectStatus "R7P4" )
				( pin "a"
					( attribute "PN" "1"
						( Origin gPackager )
					)
					( objectStatus "R7P4.1" )
				)
				( pin "b"
					( attribute "PN" "2"
						( Origin gPackager )
					)
					( objectStatus "R7P4.2" )
				)
			)
			( gate "@baseboard_fab2_lib.baseboard_fab2(sch_1):page103_i133"
				( attribute "BOM_COST" "SYS_CLOCK"
					( Origin gFrontEnd )
				)
				( attribute "CDS_LIB" "mstr_discrete"
					( Origin gPackager )
				)
				( attribute "CDS_LOCATION" "R7P1"
					( Origin gPackager )
				)
				( attribute "CDS_SEC" "1"
					( Origin gPackager )
				)
				( attribute "LOCATION" "R7P1"
					( Origin gFrontEnd )
				)
				( attribute "MATERIAL" "EMPTY"
					( Origin gFrontEnd )
				)
				( attribute "PACK_TYPE" "0402"
					( Origin gFrontEnd )
				)
				( attribute "PART_NUMBER" "G21796-259"
					( Origin gFrontEnd )
				)
				( attribute "PHYS_PAGE" "103"
					( Origin gFrontEnd )
				)
				( attribute "ROOM" "DB1200Z"
					( Origin gFrontEnd )
				)
				( attribute "ROT" "0"
					( Origin gFrontEnd )
				)
				( attribute "SEC" "1"
					( Origin gFrontEnd )
				)
				( attribute "SEC_TYPE" "0402"
					( Origin gFrontEnd )
				)
				( attribute "TOLERANCE" "1.0%"
					( Origin gFrontEnd )
				)
				( attribute "VALUE" "42.2"
					( Origin gFrontEnd )
				)
				( attribute "VER" "1"
					( Origin gFrontEnd )
				)
				( attribute "WATTAGE" "1/16W"
					( Origin gFrontEnd )
				)
				( attribute "XY" "(-3325,2775)"
					( Origin gFrontEnd )
				)
				( attribute "CHIPS_PART_NAME" "RES"
					( Origin gPackager )
				)
				( attribute "CDS_PART_NAME" "RES_0402-42.2,1.0%,1/16W,EMPTYA"
					( Origin gPackager )
				)
				( objectStatus "R7P1" )
				( pin "a"
					( attribute "PN" "1"
						( Origin gPackager )
					)
					( objectStatus "R7P1.1" )
				)
				( pin "b"
					( attribute "PN" "2"
						( Origin gPackager )
					)
					( objectStatus "R7P1.2" )
				)
			)
			( gate "@baseboard_fab2_lib.baseboard_fab2(sch_1):page103_i135"
				( attribute "BOM_COST" "SYS_CLOCK"
					( Origin gFrontEnd )
				)
				( attribute "CDS_LIB" "mstr_discrete"
					( Origin gPackager )
				)
				( attribute "CDS_LOCATION" "R7P2"
					( Origin gPackager )
				)
				( attribute "CDS_SEC" "1"
					( Origin gPackager )
				)
				( attribute "LOCATION" "R7P2"
					( Origin gFrontEnd )
				)
				( attribute "MATERIAL" "EMPTY"
					( Origin gFrontEnd )
				)
				( attribute "PACK_TYPE" "0402"
					( Origin gFrontEnd )
				)
				( attribute "PART_NUMBER" "G21796-259"
					( Origin gFrontEnd )
				)
				( attribute "PHYS_PAGE" "103"
					( Origin gFrontEnd )
				)
				( attribute "ROOM" "DB1200Z"
					( Origin gFrontEnd )
				)
				( attribute "ROT" "0"
					( Origin gFrontEnd )
				)
				( attribute "SEC" "1"
					( Origin gFrontEnd )
				)
				( attribute "SEC_TYPE" "0402"
					( Origin gFrontEnd )
				)
				( attribute "TOLERANCE" "1.0%"
					( Origin gFrontEnd )
				)
				( attribute "VALUE" "42.2"
					( Origin gFrontEnd )
				)
				( attribute "VER" "1"
					( Origin gFrontEnd )
				)
				( attribute "WATTAGE" "1/16W"
					( Origin gFrontEnd )
				)
				( attribute "XY" "(-3325,2450)"
					( Origin gFrontEnd )
				)
				( attribute "CHIPS_PART_NAME" "RES"
					( Origin gPackager )
				)
				( attribute "CDS_PART_NAME" "RES_0402-42.2,1.0%,1/16W,EMPTYA"
					( Origin gPackager )
				)
				( objectStatus "R7P2" )
				( pin "a"
					( attribute "PN" "1"
						( Origin gPackager )
					)
					( objectStatus "R7P2.1" )
				)
				( pin "b"
					( attribute "PN" "2"
						( Origin gPackager )
					)
					( objectStatus "R7P2.2" )
				)
			)
			( gate "@baseboard_fab2_lib.baseboard_fab2(sch_1):page103_i137"
				( attribute "BOM_COST" "SYS_CLOCK"
					( Origin gFrontEnd )
				)
				( attribute "CDS_LIB" "mstr_discrete"
					( Origin gPackager )
				)
				( attribute "CDS_LOCATION" "R6P7"
					( Origin gPackager )
				)
				( attribute "CDS_SEC" "1"
					( Origin gPackager )
				)
				( attribute "LOCATION" "R6P7"
					( Origin gFrontEnd )
				)
				( attribute "MATERIAL" "EMPTY"
					( Origin gFrontEnd )
				)
				( attribute "PACK_TYPE" "0402"
					( Origin gFrontEnd )
				)
				( attribute "PART_NUMBER" "G21796-259"
					( Origin gFrontEnd )
				)
				( attribute "PHYS_PAGE" "103"
					( Origin gFrontEnd )
				)
				( attribute "ROOM" "DB1200Z"
					( Origin gFrontEnd )
				)
				( attribute "ROT" "0"
					( Origin gFrontEnd )
				)
				( attribute "SEC" "1"
					( Origin gFrontEnd )
				)
				( attribute "SEC_TYPE" "0402"
					( Origin gFrontEnd )
				)
				( attribute "TOLERANCE" "1.0%"
					( Origin gFrontEnd )
				)
				( attribute "VALUE" "42.2"
					( Origin gFrontEnd )
				)
				( attribute "VER" "1"
					( Origin gFrontEnd )
				)
				( attribute "WATTAGE" "1/16W"
					( Origin gFrontEnd )
				)
				( attribute "XY" "(-3325,2125)"
					( Origin gFrontEnd )
				)
				( attribute "CHIPS_PART_NAME" "RES"
					( Origin gPackager )
				)
				( attribute "CDS_PART_NAME" "RES_0402-42.2,1.0%,1/16W,EMPTYA"
					( Origin gPackager )
				)
				( objectStatus "R6P7" )
				( pin "a"
					( attribute "PN" "1"
						( Origin gPackager )
					)
					( objectStatus "R6P7.1" )
				)
				( pin "b"
					( attribute "PN" "2"
						( Origin gPackager )
					)
					( objectStatus "R6P7.2" )
				)
			)
			( gate "@baseboard_fab2_lib.baseboard_fab2(sch_1):page103_i139"
				( attribute "BOM_COST" "SYS_CLOCK"
					( Origin gFrontEnd )
				)
				( attribute "CDS_LIB" "mstr_discrete"
					( Origin gPackager )
				)
				( attribute "CDS_LOCATION" "R6P8"
					( Origin gPackager )
				)
				( attribute "CDS_SEC" "1"
					( Origin gPackager )
				)
				( attribute "LOCATION" "R6P8"
					( Origin gFrontEnd )
				)
				( attribute "MATERIAL" "EMPTY"
					( Origin gFrontEnd )
				)
				( attribute "PACK_TYPE" "0402"
					( Origin gFrontEnd )
				)
				( attribute "PART_NUMBER" "G21796-259"
					( Origin gFrontEnd )
				)
				( attribute "PHYS_PAGE" "103"
					( Origin gFrontEnd )
				)
				( attribute "ROOM" "DB1200Z"
					( Origin gFrontEnd )
				)
				( attribute "ROT" "0"
					( Origin gFrontEnd )
				)
				( attribute "SEC" "1"
					( Origin gFrontEnd )
				)
				( attribute "SEC_TYPE" "0402"
					( Origin gFrontEnd )
				)
				( attribute "TOLERANCE" "1.0%"
					( Origin gFrontEnd )
				)
				( attribute "VALUE" "42.2"
					( Origin gFrontEnd )
				)
				( attribute "VER" "1"
					( Origin gFrontEnd )
				)
				( attribute "WATTAGE" "1/16W"
					( Origin gFrontEnd )
				)
				( attribute "XY" "(-3325,1800)"
					( Origin gFrontEnd )
				)
				( attribute "CHIPS_PART_NAME" "RES"
					( Origin gPackager )
				)
				( attribute "CDS_PART_NAME" "RES_0402-42.2,1.0%,1/16W,EMPTYA"
					( Origin gPackager )
				)
				( objectStatus "R6P8" )
				( pin "a"
					( attribute "PN" "1"
						( Origin gPackager )
					)
					( objectStatus "R6P8.1" )
				)
				( pin "b"
					( attribute "PN" "2"
						( Origin gPackager )
					)
					( objectStatus "R6P8.2" )
				)
			)
			( gate "@baseboard_fab2_lib.baseboard_fab2(sch_1):page103_i141"
				( attribute "BOM_COST" "SYS_CLOCK"
					( Origin gFrontEnd )
				)
				( attribute "CDS_LIB" "mstr_discrete"
					( Origin gPackager )
				)
				( attribute "CDS_LOCATION" "R6P5"
					( Origin gPackager )
				)
				( attribute "CDS_SEC" "1"
					( Origin gPackager )
				)
				( attribute "LOCATION" "R6P5"
					( Origin gFrontEnd )
				)
				( attribute "MATERIAL" "EMPTY"
					( Origin gFrontEnd )
				)
				( attribute "PACK_TYPE" "0402"
					( Origin gFrontEnd )
				)
				( attribute "PART_NUMBER" "G21796-259"
					( Origin gFrontEnd )
				)
				( attribute "PHYS_PAGE" "103"
					( Origin gFrontEnd )
				)
				( attribute "ROOM" "DB1200Z"
					( Origin gFrontEnd )
				)
				( attribute "ROT" "0"
					( Origin gFrontEnd )
				)
				( attribute "SEC" "1"
					( Origin gFrontEnd )
				)
				( attribute "SEC_TYPE" "0402"
					( Origin gFrontEnd )
				)
				( attribute "TOLERANCE" "1.0%"
					( Origin gFrontEnd )
				)
				( attribute "VALUE" "42.2"
					( Origin gFrontEnd )
				)
				( attribute "VER" "1"
					( Origin gFrontEnd )
				)
				( attribute "WATTAGE" "1/16W"
					( Origin gFrontEnd )
				)
				( attribute "XY" "(-3325,1475)"
					( Origin gFrontEnd )
				)
				( attribute "CHIPS_PART_NAME" "RES"
					( Origin gPackager )
				)
				( attribute "CDS_PART_NAME" "RES_0402-42.2,1.0%,1/16W,EMPTYA"
					( Origin gPackager )
				)
				( objectStatus "R6P5" )
				( pin "a"
					( attribute "PN" "1"
						( Origin gPackager )
					)
					( objectStatus "R6P5.1" )
				)
				( pin "b"
					( attribute "PN" "2"
						( Origin gPackager )
					)
					( objectStatus "R6P5.2" )
				)
			)
			( gate "@baseboard_fab2_lib.baseboard_fab2(sch_1):page103_i143"
				( attribute "BOM_COST" "SYS_CLOCK"
					( Origin gFrontEnd )
				)
				( attribute "CDS_LIB" "mstr_discrete"
					( Origin gPackager )
				)
				( attribute "CDS_LOCATION" "R6P6"
					( Origin gPackager )
				)
				( attribute "CDS_SEC" "1"
					( Origin gPackager )
				)
				( attribute "LOCATION" "R6P6"
					( Origin gFrontEnd )
				)
				( attribute "MATERIAL" "EMPTY"
					( Origin gFrontEnd )
				)
				( attribute "PACK_TYPE" "0402"
					( Origin gFrontEnd )
				)
				( attribute "PART_NUMBER" "G21796-259"
					( Origin gFrontEnd )
				)
				( attribute "PHYS_PAGE" "103"
					( Origin gFrontEnd )
				)
				( attribute "ROOM" "DB1200Z"
					( Origin gFrontEnd )
				)
				( attribute "ROT" "0"
					( Origin gFrontEnd )
				)
				( attribute "SEC" "1"
					( Origin gFrontEnd )
				)
				( attribute "SEC_TYPE" "0402"
					( Origin gFrontEnd )
				)
				( attribute "TOLERANCE" "1.0%"
					( Origin gFrontEnd )
				)
				( attribute "VALUE" "42.2"
					( Origin gFrontEnd )
				)
				( attribute "VER" "1"
					( Origin gFrontEnd )
				)
				( attribute "WATTAGE" "1/16W"
					( Origin gFrontEnd )
				)
				( attribute "XY" "(-3325,1150)"
					( Origin gFrontEnd )
				)
				( attribute "CHIPS_PART_NAME" "RES"
					( Origin gPackager )
				)
				( attribute "CDS_PART_NAME" "RES_0402-42.2,1.0%,1/16W,EMPTYA"
					( Origin gPackager )
				)
				( objectStatus "R6P6" )
				( pin "a"
					( attribute "PN" "1"
						( Origin gPackager )
					)
					( objectStatus "R6P6.1" )
				)
				( pin "b"
					( attribute "PN" "2"
						( Origin gPackager )
					)
					( objectStatus "R6P6.2" )
				)
			)
			( gate "@baseboard_fab2_lib.baseboard_fab2(sch_1):page103_i145"
				( attribute "BOM_COST" "SYS_CLOCK"
					( Origin gFrontEnd )
				)
				( attribute "CDS_LIB" "mstr_discrete"
					( Origin gPackager )
				)
				( attribute "CDS_LOCATION" "R6P3"
					( Origin gPackager )
				)
				( attribute "CDS_SEC" "1"
					( Origin gPackager )
				)
				( attribute "LOCATION" "R6P3"
					( Origin gFrontEnd )
				)
				( attribute "MATERIAL" "EMPTY"
					( Origin gFrontEnd )
				)
				( attribute "PACK_TYPE" "0402"
					( Origin gFrontEnd )
				)
				( attribute "PART_NUMBER" "G21796-259"
					( Origin gFrontEnd )
				)
				( attribute "PHYS_PAGE" "103"
					( Origin gFrontEnd )
				)
				( attribute "ROOM" "DB1200Z"
					( Origin gFrontEnd )
				)
				( attribute "ROT" "0"
					( Origin gFrontEnd )
				)
				( attribute "SEC" "1"
					( Origin gFrontEnd )
				)
				( attribute "SEC_TYPE" "0402"
					( Origin gFrontEnd )
				)
				( attribute "TOLERANCE" "1.0%"
					( Origin gFrontEnd )
				)
				( attribute "VALUE" "42.2"
					( Origin gFrontEnd )
				)
				( attribute "VER" "1"
					( Origin gFrontEnd )
				)
				( attribute "WATTAGE" "1/16W"
					( Origin gFrontEnd )
				)
				( attribute "XY" "(1025,4725)"
					( Origin gFrontEnd )
				)
				( attribute "CHIPS_PART_NAME" "RES"
					( Origin gPackager )
				)
				( attribute "CDS_PART_NAME" "RES_0402-42.2,1.0%,1/16W,EMPTYA"
					( Origin gPackager )
				)
				( objectStatus "R6P3" )
				( pin "a"
					( attribute "PN" "1"
						( Origin gPackager )
					)
					( objectStatus "R6P3.1" )
				)
				( pin "b"
					( attribute "PN" "2"
						( Origin gPackager )
					)
					( objectStatus "R6P3.2" )
				)
			)
			( gate "@baseboard_fab2_lib.baseboard_fab2(sch_1):page103_i147"
				( attribute "BOM_COST" "SYS_CLOCK"
					( Origin gFrontEnd )
				)
				( attribute "CDS_LIB" "mstr_discrete"
					( Origin gPackager )
				)
				( attribute "CDS_LOCATION" "R6P4"
					( Origin gPackager )
				)
				( attribute "CDS_SEC" "1"
					( Origin gPackager )
				)
				( attribute "LOCATION" "R6P4"
					( Origin gFrontEnd )
				)
				( attribute "MATERIAL" "EMPTY"
					( Origin gFrontEnd )
				)
				( attribute "PACK_TYPE" "0402"
					( Origin gFrontEnd )
				)
				( attribute "PART_NUMBER" "G21796-259"
					( Origin gFrontEnd )
				)
				( attribute "PHYS_PAGE" "103"
					( Origin gFrontEnd )
				)
				( attribute "ROOM" "DB1200Z"
					( Origin gFrontEnd )
				)
				( attribute "ROT" "0"
					( Origin gFrontEnd )
				)
				( attribute "SEC" "1"
					( Origin gFrontEnd )
				)
				( attribute "SEC_TYPE" "0402"
					( Origin gFrontEnd )
				)
				( attribute "TOLERANCE" "1.0%"
					( Origin gFrontEnd )
				)
				( attribute "VALUE" "42.2"
					( Origin gFrontEnd )
				)
				( attribute "VER" "1"
					( Origin gFrontEnd )
				)
				( attribute "WATTAGE" "1/16W"
					( Origin gFrontEnd )
				)
				( attribute "XY" "(1050,4400)"
					( Origin gFrontEnd )
				)
				( attribute "CHIPS_PART_NAME" "RES"
					( Origin gPackager )
				)
				( attribute "CDS_PART_NAME" "RES_0402-42.2,1.0%,1/16W,EMPTYA"
					( Origin gPackager )
				)
				( objectStatus "R6P4" )
				( pin "a"
					( attribute "PN" "1"
						( Origin gPackager )
					)
					( objectStatus "R6P4.1" )
				)
				( pin "b"
					( attribute "PN" "2"
						( Origin gPackager )
					)
					( objectStatus "R6P4.2" )
				)
			)
			( gate "@baseboard_fab2_lib.baseboard_fab2(sch_1):page103_i149"
				( attribute "BOM_COST" "SYS_CLOCK"
					( Origin gFrontEnd )
				)
				( attribute "CDS_LIB" "mstr_discrete"
					( Origin gPackager )
				)
				( attribute "CDS_LOCATION" "R6P1"
					( Origin gPackager )
				)
				( attribute "CDS_SEC" "1"
					( Origin gPackager )
				)
				( attribute "LOCATION" "R6P1"
					( Origin gFrontEnd )
				)
				( attribute "MATERIAL" "EMPTY"
					( Origin gFrontEnd )
				)
				( attribute "PACK_TYPE" "0402"
					( Origin gFrontEnd )
				)
				( attribute "PART_NUMBER" "G21796-259"
					( Origin gFrontEnd )
				)
				( attribute "PHYS_PAGE" "103"
					( Origin gFrontEnd )
				)
				( attribute "ROOM" "DB1200Z"
					( Origin gFrontEnd )
				)
				( attribute "ROT" "0"
					( Origin gFrontEnd )
				)
				( attribute "SEC" "1"
					( Origin gFrontEnd )
				)
				( attribute "SEC_TYPE" "0402"
					( Origin gFrontEnd )
				)
				( attribute "TOLERANCE" "1.0%"
					( Origin gFrontEnd )
				)
				( attribute "VALUE" "42.2"
					( Origin gFrontEnd )
				)
				( attribute "VER" "1"
					( Origin gFrontEnd )
				)
				( attribute "WATTAGE" "1/16W"
					( Origin gFrontEnd )
				)
				( attribute "XY" "(1025,4075)"
					( Origin gFrontEnd )
				)
				( attribute "CHIPS_PART_NAME" "RES"
					( Origin gPackager )
				)
				( attribute "CDS_PART_NAME" "RES_0402-42.2,1.0%,1/16W,EMPTYA"
					( Origin gPackager )
				)
				( objectStatus "R6P1" )
				( pin "a"
					( attribute "PN" "1"
						( Origin gPackager )
					)
					( objectStatus "R6P1.1" )
				)
				( pin "b"
					( attribute "PN" "2"
						( Origin gPackager )
					)
					( objectStatus "R6P1.2" )
				)
			)
			( gate "@baseboard_fab2_lib.baseboard_fab2(sch_1):page103_i151"
				( attribute "BOM_COST" "SYS_CLOCK"
					( Origin gFrontEnd )
				)
				( attribute "CDS_LIB" "mstr_discrete"
					( Origin gPackager )
				)
				( attribute "CDS_LOCATION" "R6P2"
					( Origin gPackager )
				)
				( attribute "CDS_SEC" "1"
					( Origin gPackager )
				)
				( attribute "LOCATION" "R6P2"
					( Origin gFrontEnd )
				)
				( attribute "MATERIAL" "EMPTY"
					( Origin gFrontEnd )
				)
				( attribute "PACK_TYPE" "0402"
					( Origin gFrontEnd )
				)
				( attribute "PART_NUMBER" "G21796-259"
					( Origin gFrontEnd )
				)
				( attribute "PHYS_PAGE" "103"
					( Origin gFrontEnd )
				)
				( attribute "ROOM" "DB1200Z"
					( Origin gFrontEnd )
				)
				( attribute "ROT" "0"
					( Origin gFrontEnd )
				)
				( attribute "SEC" "1"
					( Origin gFrontEnd )
				)
				( attribute "SEC_TYPE" "0402"
					( Origin gFrontEnd )
				)
				( attribute "TOLERANCE" "1.0%"
					( Origin gFrontEnd )
				)
				( attribute "VALUE" "42.2"
					( Origin gFrontEnd )
				)
				( attribute "VER" "1"
					( Origin gFrontEnd )
				)
				( attribute "WATTAGE" "1/16W"
					( Origin gFrontEnd )
				)
				( attribute "XY" "(1050,3750)"
					( Origin gFrontEnd )
				)
				( attribute "CHIPS_PART_NAME" "RES"
					( Origin gPackager )
				)
				( attribute "CDS_PART_NAME" "RES_0402-42.2,1.0%,1/16W,EMPTYA"
					( Origin gPackager )
				)
				( objectStatus "R6P2" )
				( pin "a"
					( attribute "PN" "1"
						( Origin gPackager )
					)
					( objectStatus "R6P2.1" )
				)
				( pin "b"
					( attribute "PN" "2"
						( Origin gPackager )
					)
					( objectStatus "R6P2.2" )
				)
			)
			( gate "@baseboard_fab2_lib.baseboard_fab2(sch_1):page103_i153"
				( attribute "BOM_COST" "SYS_CLOCK"
					( Origin gFrontEnd )
				)
				( attribute "CDS_LIB" "mstr_discrete"
					( Origin gPackager )
				)
				( attribute "CDS_LOCATION" "R6P11"
					( Origin gPackager )
				)
				( attribute "CDS_SEC" "1"
					( Origin gPackager )
				)
				( attribute "LOCATION" "R6P11"
					( Origin gFrontEnd )
				)
				( attribute "MATERIAL" "EMPTY"
					( Origin gFrontEnd )
				)
				( attribute "PACK_TYPE" "0402"
					( Origin gFrontEnd )
				)
				( attribute "PART_NUMBER" "G21796-259"
					( Origin gFrontEnd )
				)
				( attribute "PHYS_PAGE" "103"
					( Origin gFrontEnd )
				)
				( attribute "ROOM" "DB1200Z"
					( Origin gFrontEnd )
				)
				( attribute "ROT" "0"
					( Origin gFrontEnd )
				)
				( attribute "SEC" "1"
					( Origin gFrontEnd )
				)
				( attribute "SEC_TYPE" "0402"
					( Origin gFrontEnd )
				)
				( attribute "TOLERANCE" "1.0%"
					( Origin gFrontEnd )
				)
				( attribute "VALUE" "42.2"
					( Origin gFrontEnd )
				)
				( attribute "VER" "1"
					( Origin gFrontEnd )
				)
				( attribute "WATTAGE" "1/16W"
					( Origin gFrontEnd )
				)
				( attribute "XY" "(1050,3425)"
					( Origin gFrontEnd )
				)
				( attribute "CHIPS_PART_NAME" "RES"
					( Origin gPackager )
				)
				( attribute "CDS_PART_NAME" "RES_0402-42.2,1.0%,1/16W,EMPTYA"
					( Origin gPackager )
				)
				( objectStatus "R6P11" )
				( pin "a"
					( attribute "PN" "1"
						( Origin gPackager )
					)
					( objectStatus "R6P11.1" )
				)
				( pin "b"
					( attribute "PN" "2"
						( Origin gPackager )
					)
					( objectStatus "R6P11.2" )
				)
			)
			( gate "@baseboard_fab2_lib.baseboard_fab2(sch_1):page103_i155"
				( attribute "BOM_COST" "SYS_CLOCK"
					( Origin gFrontEnd )
				)
				( attribute "CDS_LIB" "mstr_discrete"
					( Origin gPackager )
				)
				( attribute "CDS_LOCATION" "R6P9"
					( Origin gPackager )
				)
				( attribute "CDS_SEC" "1"
					( Origin gPackager )
				)
				( attribute "LOCATION" "R6P9"
					( Origin gFrontEnd )
				)
				( attribute "MATERIAL" "EMPTY"
					( Origin gFrontEnd )
				)
				( attribute "PACK_TYPE" "0402"
					( Origin gFrontEnd )
				)
				( attribute "PART_NUMBER" "G21796-259"
					( Origin gFrontEnd )
				)
				( attribute "PHYS_PAGE" "103"
					( Origin gFrontEnd )
				)
				( attribute "ROOM" "DB1200Z"
					( Origin gFrontEnd )
				)
				( attribute "ROT" "0"
					( Origin gFrontEnd )
				)
				( attribute "SEC" "1"
					( Origin gFrontEnd )
				)
				( attribute "SEC_TYPE" "0402"
					( Origin gFrontEnd )
				)
				( attribute "TOLERANCE" "1.0%"
					( Origin gFrontEnd )
				)
				( attribute "VALUE" "42.2"
					( Origin gFrontEnd )
				)
				( attribute "VER" "1"
					( Origin gFrontEnd )
				)
				( attribute "WATTAGE" "1/16W"
					( Origin gFrontEnd )
				)
				( attribute "XY" "(1075,3100)"
					( Origin gFrontEnd )
				)
				( attribute "CHIPS_PART_NAME" "RES"
					( Origin gPackager )
				)
				( attribute "CDS_PART_NAME" "RES_0402-42.2,1.0%,1/16W,EMPTYA"
					( Origin gPackager )
				)
				( objectStatus "R6P9" )
				( pin "a"
					( attribute "PN" "1"
						( Origin gPackager )
					)
					( objectStatus "R6P9.1" )
				)
				( pin "b"
					( attribute "PN" "2"
						( Origin gPackager )
					)
					( objectStatus "R6P9.2" )
				)
			)
			( gate "@baseboard_fab2_lib.baseboard_fab2(sch_1):page103_i157"
				( attribute "BOM_COST" "SYS_CLOCK"
					( Origin gFrontEnd )
				)
				( attribute "CDS_LIB" "mstr_discrete"
					( Origin gPackager )
				)
				( attribute "CDS_LOCATION" "R6P13"
					( Origin gPackager )
				)
				( attribute "CDS_SEC" "1"
					( Origin gPackager )
				)
				( attribute "LOCATION" "R6P13"
					( Origin gFrontEnd )
				)
				( attribute "MATERIAL" "EMPTY"
					( Origin gFrontEnd )
				)
				( attribute "PACK_TYPE" "0402"
					( Origin gFrontEnd )
				)
				( attribute "PART_NUMBER" "G21796-259"
					( Origin gFrontEnd )
				)
				( attribute "PHYS_PAGE" "103"
					( Origin gFrontEnd )
				)
				( attribute "ROOM" "DB1200Z"
					( Origin gFrontEnd )
				)
				( attribute "ROT" "0"
					( Origin gFrontEnd )
				)
				( attribute "SEC" "1"
					( Origin gFrontEnd )
				)
				( attribute "SEC_TYPE" "0402"
					( Origin gFrontEnd )
				)
				( attribute "TOLERANCE" "1.0%"
					( Origin gFrontEnd )
				)
				( attribute "VALUE" "42.2"
					( Origin gFrontEnd )
				)
				( attribute "VER" "1"
					( Origin gFrontEnd )
				)
				( attribute "WATTAGE" "1/16W"
					( Origin gFrontEnd )
				)
				( attribute "XY" "(1050,2775)"
					( Origin gFrontEnd )
				)
				( attribute "CHIPS_PART_NAME" "RES"
					( Origin gPackager )
				)
				( attribute "CDS_PART_NAME" "RES_0402-42.2,1.0%,1/16W,EMPTYA"
					( Origin gPackager )
				)
				( objectStatus "R6P13" )
				( pin "a"
					( attribute "PN" "1"
						( Origin gPackager )
					)
					( objectStatus "R6P13.1" )
				)
				( pin "b"
					( attribute "PN" "2"
						( Origin gPackager )
					)
					( objectStatus "R6P13.2" )
				)
			)
			( gate "@baseboard_fab2_lib.baseboard_fab2(sch_1):page103_i159"
				( attribute "BOM_COST" "SYS_CLOCK"
					( Origin gFrontEnd )
				)
				( attribute "CDS_LIB" "mstr_discrete"
					( Origin gPackager )
				)
				( attribute "CDS_LOCATION" "R6P12"
					( Origin gPackager )
				)
				( attribute "CDS_SEC" "1"
					( Origin gPackager )
				)
				( attribute "LOCATION" "R6P12"
					( Origin gFrontEnd )
				)
				( attribute "MATERIAL" "EMPTY"
					( Origin gFrontEnd )
				)
				( attribute "PACK_TYPE" "0402"
					( Origin gFrontEnd )
				)
				( attribute "PART_NUMBER" "G21796-259"
					( Origin gFrontEnd )
				)
				( attribute "PHYS_PAGE" "103"
					( Origin gFrontEnd )
				)
				( attribute "ROOM" "DB1200Z"
					( Origin gFrontEnd )
				)
				( attribute "ROT" "0"
					( Origin gFrontEnd )
				)
				( attribute "SEC" "1"
					( Origin gFrontEnd )
				)
				( attribute "SEC_TYPE" "0402"
					( Origin gFrontEnd )
				)
				( attribute "TOLERANCE" "1.0%"
					( Origin gFrontEnd )
				)
				( attribute "VALUE" "42.2"
					( Origin gFrontEnd )
				)
				( attribute "VER" "1"
					( Origin gFrontEnd )
				)
				( attribute "WATTAGE" "1/16W"
					( Origin gFrontEnd )
				)
				( attribute "XY" "(1050,2450)"
					( Origin gFrontEnd )
				)
				( attribute "CHIPS_PART_NAME" "RES"
					( Origin gPackager )
				)
				( attribute "CDS_PART_NAME" "RES_0402-42.2,1.0%,1/16W,EMPTYA"
					( Origin gPackager )
				)
				( objectStatus "R6P12" )
				( pin "a"
					( attribute "PN" "1"
						( Origin gPackager )
					)
					( objectStatus "R6P12.1" )
				)
				( pin "b"
					( attribute "PN" "2"
						( Origin gPackager )
					)
					( objectStatus "R6P12.2" )
				)
			)
			( gate "@baseboard_fab2_lib.baseboard_fab2(sch_1):page103_i161"
				( attribute "BOM_COST" "SYS_CLOCK"
					( Origin gFrontEnd )
				)
				( attribute "CDS_LIB" "mstr_discrete"
					( Origin gPackager )
				)
				( attribute "CDS_LOCATION" "R4D24"
					( Origin gPackager )
				)
				( attribute "CDS_SEC" "1"
					( Origin gPackager )
				)
				( attribute "LOCATION" "R4D24"
					( Origin gFrontEnd )
				)
				( attribute "MATERIAL" "EMPTY"
					( Origin gFrontEnd )
				)
				( attribute "PACK_TYPE" "0402"
					( Origin gFrontEnd )
				)
				( attribute "PART_NUMBER" "G21796-259"
					( Origin gFrontEnd )
				)
				( attribute "PHYS_PAGE" "103"
					( Origin gFrontEnd )
				)
				( attribute "ROOM" "DB1200Z"
					( Origin gFrontEnd )
				)
				( attribute "ROT" "0"
					( Origin gFrontEnd )
				)
				( attribute "SEC" "1"
					( Origin gFrontEnd )
				)
				( attribute "SEC_TYPE" "0402"
					( Origin gFrontEnd )
				)
				( attribute "TOLERANCE" "1.0%"
					( Origin gFrontEnd )
				)
				( attribute "VALUE" "42.2"
					( Origin gFrontEnd )
				)
				( attribute "VER" "1"
					( Origin gFrontEnd )
				)
				( attribute "WATTAGE" "1/16W"
					( Origin gFrontEnd )
				)
				( attribute "XY" "(1050,2125)"
					( Origin gFrontEnd )
				)
				( attribute "CHIPS_PART_NAME" "RES"
					( Origin gPackager )
				)
				( attribute "CDS_PART_NAME" "RES_0402-42.2,1.0%,1/16W,EMPTYA"
					( Origin gPackager )
				)
				( objectStatus "R4D24" )
				( pin "a"
					( attribute "PN" "1"
						( Origin gPackager )
					)
					( objectStatus "R4D24.1" )
				)
				( pin "b"
					( attribute "PN" "2"
						( Origin gPackager )
					)
					( objectStatus "R4D24.2" )
				)
			)
			( gate "@baseboard_fab2_lib.baseboard_fab2(sch_1):page103_i163"
				( attribute "BOM_COST" "SYS_CLOCK"
					( Origin gFrontEnd )
				)
				( attribute "CDS_LIB" "mstr_discrete"
					( Origin gPackager )
				)
				( attribute "CDS_LOCATION" "R4D18"
					( Origin gPackager )
				)
				( attribute "CDS_SEC" "1"
					( Origin gPackager )
				)
				( attribute "LOCATION" "R4D18"
					( Origin gFrontEnd )
				)
				( attribute "MATERIAL" "EMPTY"
					( Origin gFrontEnd )
				)
				( attribute "PACK_TYPE" "0402"
					( Origin gFrontEnd )
				)
				( attribute "PART_NUMBER" "G21796-259"
					( Origin gFrontEnd )
				)
				( attribute "PHYS_PAGE" "103"
					( Origin gFrontEnd )
				)
				( attribute "ROOM" "DB1200Z"
					( Origin gFrontEnd )
				)
				( attribute "ROT" "0"
					( Origin gFrontEnd )
				)
				( attribute "SEC" "1"
					( Origin gFrontEnd )
				)
				( attribute "SEC_TYPE" "0402"
					( Origin gFrontEnd )
				)
				( attribute "TOLERANCE" "1.0%"
					( Origin gFrontEnd )
				)
				( attribute "VALUE" "42.2"
					( Origin gFrontEnd )
				)
				( attribute "VER" "1"
					( Origin gFrontEnd )
				)
				( attribute "WATTAGE" "1/16W"
					( Origin gFrontEnd )
				)
				( attribute "XY" "(1050,1800)"
					( Origin gFrontEnd )
				)
				( attribute "CHIPS_PART_NAME" "RES"
					( Origin gPackager )
				)
				( attribute "CDS_PART_NAME" "RES_0402-42.2,1.0%,1/16W,EMPTYA"
					( Origin gPackager )
				)
				( objectStatus "R4D18" )
				( pin "a"
					( attribute "PN" "1"
						( Origin gPackager )
					)
					( objectStatus "R4D18.1" )
				)
				( pin "b"
					( attribute "PN" "2"
						( Origin gPackager )
					)
					( objectStatus "R4D18.2" )
				)
			)
			( gate "@baseboard_fab2_lib.baseboard_fab2(sch_1):page103_i165"
				( attribute "BOM_COST" "SYS_CLOCK"
					( Origin gFrontEnd )
				)
				( attribute "CDS_LIB" "mstr_discrete"
					( Origin gPackager )
				)
				( attribute "CDS_LOCATION" "R6P17"
					( Origin gPackager )
				)
				( attribute "CDS_SEC" "1"
					( Origin gPackager )
				)
				( attribute "LOCATION" "R6P17"
					( Origin gFrontEnd )
				)
				( attribute "MATERIAL" "EMPTY"
					( Origin gFrontEnd )
				)
				( attribute "PACK_TYPE" "0402"
					( Origin gFrontEnd )
				)
				( attribute "PART_NUMBER" "G21796-259"
					( Origin gFrontEnd )
				)
				( attribute "PHYS_PAGE" "103"
					( Origin gFrontEnd )
				)
				( attribute "ROOM" "DB1200Z"
					( Origin gFrontEnd )
				)
				( attribute "ROT" "0"
					( Origin gFrontEnd )
				)
				( attribute "SEC" "1"
					( Origin gFrontEnd )
				)
				( attribute "SEC_TYPE" "0402"
					( Origin gFrontEnd )
				)
				( attribute "TOLERANCE" "1.0%"
					( Origin gFrontEnd )
				)
				( attribute "VALUE" "42.2"
					( Origin gFrontEnd )
				)
				( attribute "VER" "1"
					( Origin gFrontEnd )
				)
				( attribute "WATTAGE" "1/16W"
					( Origin gFrontEnd )
				)
				( attribute "XY" "(1050,1475)"
					( Origin gFrontEnd )
				)
				( attribute "CHIPS_PART_NAME" "RES"
					( Origin gPackager )
				)
				( attribute "CDS_PART_NAME" "RES_0402-42.2,1.0%,1/16W,EMPTYA"
					( Origin gPackager )
				)
				( objectStatus "R6P17" )
				( pin "a"
					( attribute "PN" "1"
						( Origin gPackager )
					)
					( objectStatus "R6P17.1" )
				)
				( pin "b"
					( attribute "PN" "2"
						( Origin gPackager )
					)
					( objectStatus "R6P17.2" )
				)
			)
			( gate "@baseboard_fab2_lib.baseboard_fab2(sch_1):page103_i167"
				( attribute "BOM_COST" "SYS_CLOCK"
					( Origin gFrontEnd )
				)
				( attribute "CDS_LIB" "mstr_discrete"
					( Origin gPackager )
				)
				( attribute "CDS_LOCATION" "R6P15"
					( Origin gPackager )
				)
				( attribute "CDS_SEC" "1"
					( Origin gPackager )
				)
				( attribute "LOCATION" "R6P15"
					( Origin gFrontEnd )
				)
				( attribute "MATERIAL" "EMPTY"
					( Origin gFrontEnd )
				)
				( attribute "PACK_TYPE" "0402"
					( Origin gFrontEnd )
				)
				( attribute "PART_NUMBER" "G21796-259"
					( Origin gFrontEnd )
				)
				( attribute "PHYS_PAGE" "103"
					( Origin gFrontEnd )
				)
				( attribute "ROOM" "DB1200Z"
					( Origin gFrontEnd )
				)
				( attribute "ROT" "0"
					( Origin gFrontEnd )
				)
				( attribute "SEC" "1"
					( Origin gFrontEnd )
				)
				( attribute "SEC_TYPE" "0402"
					( Origin gFrontEnd )
				)
				( attribute "TOLERANCE" "1.0%"
					( Origin gFrontEnd )
				)
				( attribute "VALUE" "42.2"
					( Origin gFrontEnd )
				)
				( attribute "VER" "1"
					( Origin gFrontEnd )
				)
				( attribute "WATTAGE" "1/16W"
					( Origin gFrontEnd )
				)
				( attribute "XY" "(1050,1150)"
					( Origin gFrontEnd )
				)
				( attribute "CHIPS_PART_NAME" "RES"
					( Origin gPackager )
				)
				( attribute "CDS_PART_NAME" "RES_0402-42.2,1.0%,1/16W,EMPTYA"
					( Origin gPackager )
				)
				( objectStatus "R6P15" )
				( pin "a"
					( attribute "PN" "1"
						( Origin gPackager )
					)
					( objectStatus "R6P15.1" )
				)
				( pin "b"
					( attribute "PN" "2"
						( Origin gPackager )
					)
					( objectStatus "R6P15.2" )
				)
			)
			( gate "@baseboard_fab2_lib.baseboard_fab2(sch_1):page104_i25"
				( attribute "CDS_LIB" "dev_discrete"
					( Origin gPackager )
				)
				( attribute "CDS_LOCATION" "C6F1"
					( Origin gPackager )
				)
				( attribute "CDS_SEC" "1"
					( Origin gPackager )
				)
				( attribute "LOCATION" "C6F1"
					( Origin gFrontEnd )
				)
				( attribute "MATERIAL" "X7R"
					( Origin gFrontEnd )
				)
				( attribute "PACK_TYPE" "0402V"
					( Origin gFrontEnd )
				)
				( attribute "PART_NUMBER" "A36096-030"
					( Origin gFrontEnd )
				)
				( attribute "PHYS_PAGE" "104"
					( Origin gFrontEnd )
				)
				( attribute "ROOM" "CLOCK_CPU0_OSC"
					( Origin gFrontEnd )
				)
				( attribute "ROT" "0"
					( Origin gFrontEnd )
				)
				( attribute "SEC" "1"
					( Origin gFrontEnd )
				)
				( attribute "SEC_TYPE" "0402V"
					( Origin gFrontEnd )
				)
				( attribute "TOLERANCE" "10%"
					( Origin gFrontEnd )
				)
				( attribute "VALUE" "0.1UF"
					( Origin gFrontEnd )
				)
				( attribute "VER" "1"
					( Origin gFrontEnd )
				)
				( attribute "VOLTAGE" "16V"
					( Units "uVoltage" "V" 1.000000)
					( Origin gFrontEnd )
				)
				( attribute "XY" "(-4250,5100)"
					( Origin gFrontEnd )
				)
				( attribute "CHIPS_PART_NAME" "CAP_A"
					( Origin gPackager )
				)
				( attribute "CDS_PART_NAME" "CAP_A_0402V-0.1UF,16V,10%,X7R,A"
					( Origin gPackager )
				)
				( objectStatus "C6F1" )
				( pin "a"
					( attribute "PN" "1"
						( Origin gPackager )
					)
					( objectStatus "C6F1.1" )
				)
				( pin "b"
					( attribute "PN" "2"
						( Origin gPackager )
					)
					( objectStatus "C6F1.2" )
				)
			)
			( gate "@baseboard_fab2_lib.baseboard_fab2(sch_1):page104_i34"
				( attribute "CDS_LIB" "dev_discrete"
					( Origin gPackager )
				)
				( attribute "CDS_LOCATION" "C3F2"
					( Origin gPackager )
				)
				( attribute "CDS_SEC" "1"
					( Origin gPackager )
				)
				( attribute "LOCATION" "C3F2"
					( Origin gFrontEnd )
				)
				( attribute "MATERIAL" "X7R"
					( Origin gFrontEnd )
				)
				( attribute "PACK_TYPE" "0402V"
					( Origin gFrontEnd )
				)
				( attribute "PART_NUMBER" "A36096-030"
					( Origin gFrontEnd )
				)
				( attribute "PHYS_PAGE" "104"
					( Origin gFrontEnd )
				)
				( attribute "ROOM" "CLOCK_CPU1_OSC"
					( Origin gFrontEnd )
				)
				( attribute "ROT" "0"
					( Origin gFrontEnd )
				)
				( attribute "SEC" "1"
					( Origin gFrontEnd )
				)
				( attribute "SEC_TYPE" "0402V"
					( Origin gFrontEnd )
				)
				( attribute "TOLERANCE" "10%"
					( Origin gFrontEnd )
				)
				( attribute "VALUE" "0.1UF"
					( Origin gFrontEnd )
				)
				( attribute "VER" "1"
					( Origin gFrontEnd )
				)
				( attribute "VOLTAGE" "16V"
					( Units "uVoltage" "V" 1.000000)
					( Origin gFrontEnd )
				)
				( attribute "XY" "(-4575,4225)"
					( Origin gFrontEnd )
				)
				( attribute "CHIPS_PART_NAME" "CAP_A"
					( Origin gPackager )
				)
				( attribute "CDS_PART_NAME" "CAP_A_0402V-0.1UF,16V,10%,X7R,A"
					( Origin gPackager )
				)
				( objectStatus "C3F2" )
				( pin "a"
					( attribute "PN" "1"
						( Origin gPackager )
					)
					( objectStatus "C3F2.1" )
				)
				( pin "b"
					( attribute "PN" "2"
						( Origin gPackager )
					)
					( objectStatus "C3F2.2" )
				)
			)
			( gate "@baseboard_fab2_lib.baseboard_fab2(sch_1):page104_i37"
				( attribute "CDS_LIB" "mstr_discrete"
					( Origin gPackager )
				)
				( attribute "CDS_LOCATION" "R6F8"
					( Origin gPackager )
				)
				( attribute "CDS_SEC" "1"
					( Origin gPackager )
				)
				( attribute "LOCATION" "R6F8"
					( Origin gFrontEnd )
				)
				( attribute "MATERIAL" "EMPTY"
					( Origin gFrontEnd )
				)
				( attribute "NO_XNET_CONNECTION" "1"
					( Origin gFrontEnd )
				)
				( attribute "PACK_TYPE" "0402"
					( Origin gFrontEnd )
				)
				( attribute "PART_NUMBER" "G21497-005"
					( Origin gFrontEnd )
				)
				( attribute "PHYS_PAGE" "104"
					( Origin gFrontEnd )
				)
				( attribute "ROOM" "CLOCK_CPU0_OSC"
					( Origin gFrontEnd )
				)
				( attribute "ROT" "0"
					( Origin gFrontEnd )
				)
				( attribute "SEC" "1"
					( Origin gFrontEnd )
				)
				( attribute "SEC_TYPE" "0402"
					( Origin gFrontEnd )
				)
				( attribute "TOLERANCE" "5%"
					( Origin gFrontEnd )
				)
				( attribute "VALUE" "0.0"
					( Origin gFrontEnd )
				)
				( attribute "VER" "1"
					( Origin gFrontEnd )
				)
				( attribute "WATTAGE" "1/16W"
					( Origin gFrontEnd )
				)
				( attribute "XY" "(525,4300)"
					( Origin gFrontEnd )
				)
				( attribute "CHIPS_PART_NAME" "RES"
					( Origin gPackager )
				)
				( attribute "CDS_PART_NAME" "RES_0402-0.0,5%,1/16W,EMPTY,G2A"
					( Origin gPackager )
				)
				( objectStatus "R6F8" )
				( pin "a"
					( attribute "PN" "1"
						( Origin gPackager )
					)
					( objectStatus "R6F8.1" )
				)
				( pin "b"
					( attribute "PN" "2"
						( Origin gPackager )
					)
					( objectStatus "R6F8.2" )
				)
			)
			( gate "@baseboard_fab2_lib.baseboard_fab2(sch_1):page104_i41"
				( attribute "CDS_LIB" "mstr_discrete"
					( Origin gPackager )
				)
				( attribute "CDS_LOCATION" "R6F6"
					( Origin gPackager )
				)
				( attribute "CDS_SEC" "1"
					( Origin gPackager )
				)
				( attribute "LOCATION" "R6F6"
					( Origin gFrontEnd )
				)
				( attribute "MATERIAL" "EMPTY"
					( Origin gFrontEnd )
				)
				( attribute "NO_XNET_CONNECTION" "1"
					( Origin gFrontEnd )
				)
				( attribute "PACK_TYPE" "0402"
					( Origin gFrontEnd )
				)
				( attribute "PART_NUMBER" "G21497-005"
					( Origin gFrontEnd )
				)
				( attribute "PHYS_PAGE" "104"
					( Origin gFrontEnd )
				)
				( attribute "ROOM" "CLOCK_CPU0_OSC"
					( Origin gFrontEnd )
				)
				( attribute "ROT" "0"
					( Origin gFrontEnd )
				)
				( attribute "SEC" "1"
					( Origin gFrontEnd )
				)
				( attribute "SEC_TYPE" "0402"
					( Origin gFrontEnd )
				)
				( attribute "TOLERANCE" "5%"
					( Origin gFrontEnd )
				)
				( attribute "VALUE" "0.0"
					( Origin gFrontEnd )
				)
				( attribute "VER" "1"
					( Origin gFrontEnd )
				)
				( attribute "WATTAGE" "1/16W"
					( Origin gFrontEnd )
				)
				( attribute "XY" "(525,4950)"
					( Origin gFrontEnd )
				)
				( attribute "CHIPS_PART_NAME" "RES"
					( Origin gPackager )
				)
				( attribute "CDS_PART_NAME" "RES_0402-0.0,5%,1/16W,EMPTY,G2A"
					( Origin gPackager )
				)
				( objectStatus "R6F6" )
				( pin "a"
					( attribute "PN" "1"
						( Origin gPackager )
					)
					( objectStatus "R6F6.1" )
				)
				( pin "b"
					( attribute "PN" "2"
						( Origin gPackager )
					)
					( objectStatus "R6F6.2" )
				)
			)
			( gate "@baseboard_fab2_lib.baseboard_fab2(sch_1):page104_i51"
				( attribute "CDS_LIB" "mstr_discrete"
					( Origin gPackager )
				)
				( attribute "CDS_LOCATION" "R3F1"
					( Origin gPackager )
				)
				( attribute "CDS_SEC" "1"
					( Origin gPackager )
				)
				( attribute "LOCATION" "R3F1"
					( Origin gFrontEnd )
				)
				( attribute "MATERIAL" "EMPTY"
					( Origin gFrontEnd )
				)
				( attribute "NO_XNET_CONNECTION" "1"
					( Origin gFrontEnd )
				)
				( attribute "PACK_TYPE" "0402"
					( Origin gFrontEnd )
				)
				( attribute "PART_NUMBER" "G21497-005"
					( Origin gFrontEnd )
				)
				( attribute "PHYS_PAGE" "104"
					( Origin gFrontEnd )
				)
				( attribute "ROOM" "CLOCK_CPU1_OSC"
					( Origin gFrontEnd )
				)
				( attribute "ROT" "0"
					( Origin gFrontEnd )
				)
				( attribute "SEC" "1"
					( Origin gFrontEnd )
				)
				( attribute "SEC_TYPE" "0402"
					( Origin gFrontEnd )
				)
				( attribute "TOLERANCE" "5%"
					( Origin gFrontEnd )
				)
				( attribute "VALUE" "0.0"
					( Origin gFrontEnd )
				)
				( attribute "VER" "1"
					( Origin gFrontEnd )
				)
				( attribute "WATTAGE" "1/16W"
					( Origin gFrontEnd )
				)
				( attribute "XY" "(525,3575)"
					( Origin gFrontEnd )
				)
				( attribute "CHIPS_PART_NAME" "RES"
					( Origin gPackager )
				)
				( attribute "CDS_PART_NAME" "RES_0402-0.0,5%,1/16W,EMPTY,G2A"
					( Origin gPackager )
				)
				( objectStatus "R3F1" )
				( pin "a"
					( attribute "PN" "1"
						( Origin gPackager )
					)
					( objectStatus "R3F1.1" )
				)
				( pin "b"
					( attribute "PN" "2"
						( Origin gPackager )
					)
					( objectStatus "R3F1.2" )
				)
			)
			( gate "@baseboard_fab2_lib.baseboard_fab2(sch_1):page104_i53"
				( attribute "CDS_LIB" "mstr_discrete"
					( Origin gPackager )
				)
				( attribute "CDS_LOCATION" "R3F3"
					( Origin gPackager )
				)
				( attribute "CDS_SEC" "1"
					( Origin gPackager )
				)
				( attribute "LOCATION" "R3F3"
					( Origin gFrontEnd )
				)
				( attribute "MATERIAL" "EMPTY"
					( Origin gFrontEnd )
				)
				( attribute "NO_XNET_CONNECTION" "1"
					( Origin gFrontEnd )
				)
				( attribute "PACK_TYPE" "0402"
					( Origin gFrontEnd )
				)
				( attribute "PART_NUMBER" "G21497-005"
					( Origin gFrontEnd )
				)
				( attribute "PHYS_PAGE" "104"
					( Origin gFrontEnd )
				)
				( attribute "ROOM" "CLOCK_CPU1_OSC"
					( Origin gFrontEnd )
				)
				( attribute "ROT" "0"
					( Origin gFrontEnd )
				)
				( attribute "SEC" "1"
					( Origin gFrontEnd )
				)
				( attribute "SEC_TYPE" "0402"
					( Origin gFrontEnd )
				)
				( attribute "TOLERANCE" "5%"
					( Origin gFrontEnd )
				)
				( attribute "VALUE" "0.0"
					( Origin gFrontEnd )
				)
				( attribute "VER" "1"
					( Origin gFrontEnd )
				)
				( attribute "WATTAGE" "1/16W"
					( Origin gFrontEnd )
				)
				( attribute "XY" "(525,2875)"
					( Origin gFrontEnd )
				)
				( attribute "CHIPS_PART_NAME" "RES"
					( Origin gPackager )
				)
				( attribute "CDS_PART_NAME" "RES_0402-0.0,5%,1/16W,EMPTY,G2A"
					( Origin gPackager )
				)
				( objectStatus "R3F3" )
				( pin "a"
					( attribute "PN" "1"
						( Origin gPackager )
					)
					( objectStatus "R3F3.1" )
				)
				( pin "b"
					( attribute "PN" "2"
						( Origin gPackager )
					)
					( objectStatus "R3F3.2" )
				)
			)
			( gate "@baseboard_fab2_lib.baseboard_fab2(sch_1):page104_i67"
				( attribute "CDS_LIB" "mstr_discrete"
					( Origin gPackager )
				)
				( attribute "CDS_LOCATION" "R6F7"
					( Origin gPackager )
				)
				( attribute "CDS_SEC" "1"
					( Origin gPackager )
				)
				( attribute "LOCATION" "R6F7"
					( Origin gFrontEnd )
				)
				( attribute "MATERIAL" "CHIP"
					( Origin gFrontEnd )
				)
				( attribute "NO_XNET_CONNECTION" "1"
					( Origin gFrontEnd )
				)
				( attribute "PACK_TYPE" "0402"
					( Origin gFrontEnd )
				)
				( attribute "PART_NUMBER" "G21497-005"
					( Origin gFrontEnd )
				)
				( attribute "PHYS_PAGE" "104"
					( Origin gFrontEnd )
				)
				( attribute "ROOM" "CLOCK_CPU0_OSC"
					( Origin gFrontEnd )
				)
				( attribute "ROT" "0"
					( Origin gFrontEnd )
				)
				( attribute "SEC" "1"
					( Origin gFrontEnd )
				)
				( attribute "SEC_TYPE" "0402"
					( Origin gFrontEnd )
				)
				( attribute "TOLERANCE" "5%"
					( Origin gFrontEnd )
				)
				( attribute "VALUE" "0.0"
					( Origin gFrontEnd )
				)
				( attribute "VER" "1"
					( Origin gFrontEnd )
				)
				( attribute "WATTAGE" "1/16W"
					( Origin gFrontEnd )
				)
				( attribute "XY" "(525,5150)"
					( Origin gFrontEnd )
				)
				( attribute "CHIPS_PART_NAME" "RES"
					( Origin gPackager )
				)
				( attribute "CDS_PART_NAME" "RES_0402-0.0,5%,1/16W,CHIP,G21A"
					( Origin gPackager )
				)
				( objectStatus "R6F7" )
				( pin "a"
					( attribute "PN" "1"
						( Origin gPackager )
					)
					( objectStatus "R6F7.1" )
				)
				( pin "b"
					( attribute "PN" "2"
						( Origin gPackager )
					)
					( objectStatus "R6F7.2" )
				)
			)
			( gate "@baseboard_fab2_lib.baseboard_fab2(sch_1):page104_i68"
				( attribute "CDS_LIB" "mstr_discrete"
					( Origin gPackager )
				)
				( attribute "CDS_LOCATION" "R6F9"
					( Origin gPackager )
				)
				( attribute "CDS_SEC" "1"
					( Origin gPackager )
				)
				( attribute "LOCATION" "R6F9"
					( Origin gFrontEnd )
				)
				( attribute "MATERIAL" "CHIP"
					( Origin gFrontEnd )
				)
				( attribute "NO_XNET_CONNECTION" "1"
					( Origin gFrontEnd )
				)
				( attribute "PACK_TYPE" "0402"
					( Origin gFrontEnd )
				)
				( attribute "PART_NUMBER" "G21497-005"
					( Origin gFrontEnd )
				)
				( attribute "PHYS_PAGE" "104"
					( Origin gFrontEnd )
				)
				( attribute "ROOM" "CLOCK_CPU0_OSC"
					( Origin gFrontEnd )
				)
				( attribute "ROT" "0"
					( Origin gFrontEnd )
				)
				( attribute "SEC" "1"
					( Origin gFrontEnd )
				)
				( attribute "SEC_TYPE" "0402"
					( Origin gFrontEnd )
				)
				( attribute "TOLERANCE" "5%"
					( Origin gFrontEnd )
				)
				( attribute "VALUE" "0.0"
					( Origin gFrontEnd )
				)
				( attribute "VER" "1"
					( Origin gFrontEnd )
				)
				( attribute "WATTAGE" "1/16W"
					( Origin gFrontEnd )
				)
				( attribute "XY" "(525,4500)"
					( Origin gFrontEnd )
				)
				( attribute "CHIPS_PART_NAME" "RES"
					( Origin gPackager )
				)
				( attribute "CDS_PART_NAME" "RES_0402-0.0,5%,1/16W,CHIP,G21A"
					( Origin gPackager )
				)
				( objectStatus "R6F9" )
				( pin "a"
					( attribute "PN" "1"
						( Origin gPackager )
					)
					( objectStatus "R6F9.1" )
				)
				( pin "b"
					( attribute "PN" "2"
						( Origin gPackager )
					)
					( objectStatus "R6F9.2" )
				)
			)
			( gate "@baseboard_fab2_lib.baseboard_fab2(sch_1):page104_i69"
				( attribute "CDS_LIB" "mstr_discrete"
					( Origin gPackager )
				)
				( attribute "CDS_LOCATION" "R3F2"
					( Origin gPackager )
				)
				( attribute "CDS_SEC" "1"
					( Origin gPackager )
				)
				( attribute "LOCATION" "R3F2"
					( Origin gFrontEnd )
				)
				( attribute "MATERIAL" "CHIP"
					( Origin gFrontEnd )
				)
				( attribute "NO_XNET_CONNECTION" "1"
					( Origin gFrontEnd )
				)
				( attribute "PACK_TYPE" "0402"
					( Origin gFrontEnd )
				)
				( attribute "PART_NUMBER" "G21497-005"
					( Origin gFrontEnd )
				)
				( attribute "PHYS_PAGE" "104"
					( Origin gFrontEnd )
				)
				( attribute "ROOM" "CLOCK_CPU1_OSC"
					( Origin gFrontEnd )
				)
				( attribute "ROT" "0"
					( Origin gFrontEnd )
				)
				( attribute "SEC" "1"
					( Origin gFrontEnd )
				)
				( attribute "SEC_TYPE" "0402"
					( Origin gFrontEnd )
				)
				( attribute "TOLERANCE" "5%"
					( Origin gFrontEnd )
				)
				( attribute "VALUE" "0.0"
					( Origin gFrontEnd )
				)
				( attribute "VER" "1"
					( Origin gFrontEnd )
				)
				( attribute "WATTAGE" "1/16W"
					( Origin gFrontEnd )
				)
				( attribute "XY" "(525,3775)"
					( Origin gFrontEnd )
				)
				( attribute "CHIPS_PART_NAME" "RES"
					( Origin gPackager )
				)
				( attribute "CDS_PART_NAME" "RES_0402-0.0,5%,1/16W,CHIP,G21A"
					( Origin gPackager )
				)
				( objectStatus "R3F2" )
				( pin "a"
					( attribute "PN" "1"
						( Origin gPackager )
					)
					( objectStatus "R3F2.1" )
				)
				( pin "b"
					( attribute "PN" "2"
						( Origin gPackager )
					)
					( objectStatus "R3F2.2" )
				)
			)
			( gate "@baseboard_fab2_lib.baseboard_fab2(sch_1):page104_i70"
				( attribute "CDS_LIB" "mstr_discrete"
					( Origin gPackager )
				)
				( attribute "CDS_LOCATION" "R3F4"
					( Origin gPackager )
				)
				( attribute "CDS_SEC" "1"
					( Origin gPackager )
				)
				( attribute "LOCATION" "R3F4"
					( Origin gFrontEnd )
				)
				( attribute "MATERIAL" "CHIP"
					( Origin gFrontEnd )
				)
				( attribute "NO_XNET_CONNECTION" "1"
					( Origin gFrontEnd )
				)
				( attribute "PACK_TYPE" "0402"
					( Origin gFrontEnd )
				)
				( attribute "PART_NUMBER" "G21497-005"
					( Origin gFrontEnd )
				)
				( attribute "PHYS_PAGE" "104"
					( Origin gFrontEnd )
				)
				( attribute "ROOM" "CLOCK_CPU1_OSC"
					( Origin gFrontEnd )
				)
				( attribute "ROT" "0"
					( Origin gFrontEnd )
				)
				( attribute "SEC" "1"
					( Origin gFrontEnd )
				)
				( attribute "SEC_TYPE" "0402"
					( Origin gFrontEnd )
				)
				( attribute "TOLERANCE" "5%"
					( Origin gFrontEnd )
				)
				( attribute "VALUE" "0.0"
					( Origin gFrontEnd )
				)
				( attribute "VER" "1"
					( Origin gFrontEnd )
				)
				( attribute "WATTAGE" "1/16W"
					( Origin gFrontEnd )
				)
				( attribute "XY" "(525,3075)"
					( Origin gFrontEnd )
				)
				( attribute "CHIPS_PART_NAME" "RES"
					( Origin gPackager )
				)
				( attribute "CDS_PART_NAME" "RES_0402-0.0,5%,1/16W,CHIP,G21A"
					( Origin gPackager )
				)
				( objectStatus "R3F4" )
				( pin "a"
					( attribute "PN" "1"
						( Origin gPackager )
					)
					( objectStatus "R3F4.1" )
				)
				( pin "b"
					( attribute "PN" "2"
						( Origin gPackager )
					)
					( objectStatus "R3F4.2" )
				)
			)
			( gate "@baseboard_fab2_lib.baseboard_fab2(sch_1):page104_i71"
				( attribute "CDS_LIB" "mstr_discrete"
					( Origin gPackager )
				)
				( attribute "CDS_LMAN_SYM_OUTLINE" "-450,200,450,-200"
					( Origin gPackager )
				)
				( attribute "CDS_LOCATION" "Y6F1"
					( Origin gPackager )
				)
				( attribute "CDS_SEC" "1"
					( Origin gPackager )
				)
				( attribute "LOCATION" "Y6F1"
					( Origin gFrontEnd )
				)
				( attribute "MATERIAL" "OSC"
					( Origin gFrontEnd )
				)
				( attribute "PACK_TYPE" "6P10"
					( Origin gFrontEnd )
				)
				( attribute "PART_NUMBER" "G63831-004"
					( Origin gFrontEnd )
				)
				( attribute "PHYS_PAGE" "104"
					( Origin gFrontEnd )
				)
				( attribute "ROT" "0"
					( Origin gFrontEnd )
				)
				( attribute "SEC" "1"
					( Origin gFrontEnd )
				)
				( attribute "SEC_TYPE" "6P10"
					( Origin gFrontEnd )
				)
				( attribute "VALUE" "156.25MHZ"
					( Origin gFrontEnd )
				)
				( attribute "VER" "17"
					( Origin gFrontEnd )
				)
				( attribute "XY" "(-3400,4775)"
					( Origin gFrontEnd )
				)
				( attribute "CHIPS_PART_NAME" "OSC_C"
					( Origin gPackager )
				)
				( attribute "CDS_PART_NAME" "OSC_C_6P10-156.25MHZ,OSC,G6383A"
					( Origin gPackager )
				)
				( objectStatus "Y6F1" )
				( pin "enable_disable"
					( attribute "PN" "1"
						( Origin gPackager )
					)
					( objectStatus "Y6F1.1" )
				)
				( pin "gnd"
					( attribute "PN" "3"
						( Origin gPackager )
					)
					( objectStatus "Y6F1.3" )
				)
				( pin "nc_gnd"
					( attribute "PN" "2"
						( Origin gPackager )
					)
					( objectStatus "Y6F1.2" )
				)
				( pin "\out\"
					( attribute "PN" "4"
						( Origin gPackager )
					)
					( objectStatus "Y6F1.4" )
				)
				( pin "out_n"
					( attribute "PN" "5"
						( Origin gPackager )
					)
					( objectStatus "Y6F1.5" )
				)
				( pin "vcc"
					( attribute "PN" "6"
						( Origin gPackager )
					)
					( objectStatus "Y6F1.6" )
				)
			)
			( gate "@baseboard_fab2_lib.baseboard_fab2(sch_1):page104_i72"
				( attribute "CDS_LIB" "mstr_discrete"
					( Origin gPackager )
				)
				( attribute "CDS_LMAN_SYM_OUTLINE" "-450,200,450,-200"
					( Origin gPackager )
				)
				( attribute "CDS_LOCATION" "Y3F1"
					( Origin gPackager )
				)
				( attribute "CDS_SEC" "1"
					( Origin gPackager )
				)
				( attribute "LOCATION" "Y3F1"
					( Origin gFrontEnd )
				)
				( attribute "MATERIAL" "OSC"
					( Origin gFrontEnd )
				)
				( attribute "PACK_TYPE" "6P10"
					( Origin gFrontEnd )
				)
				( attribute "PART_NUMBER" "G63831-004"
					( Origin gFrontEnd )
				)
				( attribute "PHYS_PAGE" "104"
					( Origin gFrontEnd )
				)
				( attribute "ROT" "0"
					( Origin gFrontEnd )
				)
				( attribute "SEC" "1"
					( Origin gFrontEnd )
				)
				( attribute "SEC_TYPE" "6P10"
					( Origin gFrontEnd )
				)
				( attribute "VALUE" "156.25MHZ"
					( Origin gFrontEnd )
				)
				( attribute "VER" "17"
					( Origin gFrontEnd )
				)
				( attribute "XY" "(-3700,3925)"
					( Origin gFrontEnd )
				)
				( attribute "CHIPS_PART_NAME" "OSC_C"
					( Origin gPackager )
				)
				( attribute "CDS_PART_NAME" "OSC_C_6P10-156.25MHZ,OSC,G6383A"
					( Origin gPackager )
				)
				( objectStatus "Y3F1" )
				( pin "enable_disable"
					( attribute "PN" "1"
						( Origin gPackager )
					)
					( objectStatus "Y3F1.1" )
				)
				( pin "gnd"
					( attribute "PN" "3"
						( Origin gPackager )
					)
					( objectStatus "Y3F1.3" )
				)
				( pin "nc_gnd"
					( attribute "PN" "2"
						( Origin gPackager )
					)
					( objectStatus "Y3F1.2" )
				)
				( pin "\out\"
					( attribute "PN" "4"
						( Origin gPackager )
					)
					( objectStatus "Y3F1.4" )
				)
				( pin "out_n"
					( attribute "PN" "5"
						( Origin gPackager )
					)
					( objectStatus "Y3F1.5" )
				)
				( pin "vcc"
					( attribute "PN" "6"
						( Origin gPackager )
					)
					( objectStatus "Y3F1.6" )
				)
			)
			( gate "@baseboard_fab2_lib.baseboard_fab2(sch_1):page104_i78"
				( attribute "CDS_LIB" "mstr_discrete"
					( Origin gPackager )
				)
				( attribute "CDS_LOCATION" "R6F10"
					( Origin gPackager )
				)
				( attribute "CDS_SEC" "1"
					( Origin gPackager )
				)
				( attribute "LOCATION" "R6F10"
					( Origin gFrontEnd )
				)
				( attribute "MATERIAL" "EMPTY"
					( Origin gFrontEnd )
				)
				( attribute "PACK_TYPE" "0402"
					( Origin gFrontEnd )
				)
				( attribute "PART_NUMBER" "G21497-005"
					( Origin gFrontEnd )
				)
				( attribute "PHYS_PAGE" "104"
					( Origin gFrontEnd )
				)
				( attribute "ROT" "0"
					( Origin gFrontEnd )
				)
				( attribute "SEC" "1"
					( Origin gFrontEnd )
				)
				( attribute "SEC_TYPE" "0402"
					( Origin gFrontEnd )
				)
				( attribute "TOLERANCE" "5%"
					( Origin gFrontEnd )
				)
				( attribute "VALUE" "0.0"
					( Origin gFrontEnd )
				)
				( attribute "VER" "1"
					( Origin gFrontEnd )
				)
				( attribute "WATTAGE" "1/16W"
					( Origin gFrontEnd )
				)
				( attribute "XY" "(525,4750)"
					( Origin gFrontEnd )
				)
				( attribute "CHIPS_PART_NAME" "RES"
					( Origin gPackager )
				)
				( attribute "CDS_PART_NAME" "RES_0402-0.0,5%,1/16W,EMPTY,G2A"
					( Origin gPackager )
				)
				( objectStatus "R6F10" )
				( pin "a"
					( attribute "PN" "1"
						( Origin gPackager )
					)
					( objectStatus "R6F10.1" )
				)
				( pin "b"
					( attribute "PN" "2"
						( Origin gPackager )
					)
					( objectStatus "R6F10.2" )
				)
			)
			( gate "@baseboard_fab2_lib.baseboard_fab2(sch_1):page104_i79"
				( attribute "CDS_LIB" "mstr_discrete"
					( Origin gPackager )
				)
				( attribute "CDS_LOCATION" "R6F11"
					( Origin gPackager )
				)
				( attribute "CDS_SEC" "1"
					( Origin gPackager )
				)
				( attribute "LOCATION" "R6F11"
					( Origin gFrontEnd )
				)
				( attribute "MATERIAL" "EMPTY"
					( Origin gFrontEnd )
				)
				( attribute "PACK_TYPE" "0402"
					( Origin gFrontEnd )
				)
				( attribute "PART_NUMBER" "G21497-005"
					( Origin gFrontEnd )
				)
				( attribute "PHYS_PAGE" "104"
					( Origin gFrontEnd )
				)
				( attribute "ROT" "0"
					( Origin gFrontEnd )
				)
				( attribute "SEC" "1"
					( Origin gFrontEnd )
				)
				( attribute "SEC_TYPE" "0402"
					( Origin gFrontEnd )
				)
				( attribute "TOLERANCE" "5%"
					( Origin gFrontEnd )
				)
				( attribute "VALUE" "0.0"
					( Origin gFrontEnd )
				)
				( attribute "VER" "1"
					( Origin gFrontEnd )
				)
				( attribute "WATTAGE" "1/16W"
					( Origin gFrontEnd )
				)
				( attribute "XY" "(525,4100)"
					( Origin gFrontEnd )
				)
				( attribute "CHIPS_PART_NAME" "RES"
					( Origin gPackager )
				)
				( attribute "CDS_PART_NAME" "RES_0402-0.0,5%,1/16W,EMPTY,G2A"
					( Origin gPackager )
				)
				( objectStatus "R6F11" )
				( pin "a"
					( attribute "PN" "1"
						( Origin gPackager )
					)
					( objectStatus "R6F11.1" )
				)
				( pin "b"
					( attribute "PN" "2"
						( Origin gPackager )
					)
					( objectStatus "R6F11.2" )
				)
			)
			( gate "@baseboard_fab2_lib.baseboard_fab2(sch_1):page104_i84"
				( attribute "CDS_LIB" "mstr_discrete"
					( Origin gPackager )
				)
				( attribute "CDS_LOCATION" "R3F5"
					( Origin gPackager )
				)
				( attribute "CDS_SEC" "1"
					( Origin gPackager )
				)
				( attribute "LOCATION" "R3F5"
					( Origin gFrontEnd )
				)
				( attribute "MATERIAL" "EMPTY"
					( Origin gFrontEnd )
				)
				( attribute "PACK_TYPE" "0402"
					( Origin gFrontEnd )
				)
				( attribute "PART_NUMBER" "G21497-005"
					( Origin gFrontEnd )
				)
				( attribute "PHYS_PAGE" "104"
					( Origin gFrontEnd )
				)
				( attribute "ROT" "0"
					( Origin gFrontEnd )
				)
				( attribute "SEC" "1"
					( Origin gFrontEnd )
				)
				( attribute "SEC_TYPE" "0402"
					( Origin gFrontEnd )
				)
				( attribute "TOLERANCE" "5%"
					( Origin gFrontEnd )
				)
				( attribute "VALUE" "0.0"
					( Origin gFrontEnd )
				)
				( attribute "VER" "1"
					( Origin gFrontEnd )
				)
				( attribute "WATTAGE" "1/16W"
					( Origin gFrontEnd )
				)
				( attribute "XY" "(525,3375)"
					( Origin gFrontEnd )
				)
				( attribute "CHIPS_PART_NAME" "RES"
					( Origin gPackager )
				)
				( attribute "CDS_PART_NAME" "RES_0402-0.0,5%,1/16W,EMPTY,G2A"
					( Origin gPackager )
				)
				( objectStatus "R3F5" )
				( pin "a"
					( attribute "PN" "1"
						( Origin gPackager )
					)
					( objectStatus "R3F5.1" )
				)
				( pin "b"
					( attribute "PN" "2"
						( Origin gPackager )
					)
					( objectStatus "R3F5.2" )
				)
			)
			( gate "@baseboard_fab2_lib.baseboard_fab2(sch_1):page104_i88"
				( attribute "CDS_LIB" "mstr_discrete"
					( Origin gPackager )
				)
				( attribute "CDS_LOCATION" "R3F6"
					( Origin gPackager )
				)
				( attribute "CDS_SEC" "1"
					( Origin gPackager )
				)
				( attribute "LOCATION" "R3F6"
					( Origin gFrontEnd )
				)
				( attribute "MATERIAL" "EMPTY"
					( Origin gFrontEnd )
				)
				( attribute "PACK_TYPE" "0402"
					( Origin gFrontEnd )
				)
				( attribute "PART_NUMBER" "G21497-005"
					( Origin gFrontEnd )
				)
				( attribute "PHYS_PAGE" "104"
					( Origin gFrontEnd )
				)
				( attribute "ROT" "0"
					( Origin gFrontEnd )
				)
				( attribute "SEC" "1"
					( Origin gFrontEnd )
				)
				( attribute "SEC_TYPE" "0402"
					( Origin gFrontEnd )
				)
				( attribute "TOLERANCE" "5%"
					( Origin gFrontEnd )
				)
				( attribute "VALUE" "0.0"
					( Origin gFrontEnd )
				)
				( attribute "VER" "1"
					( Origin gFrontEnd )
				)
				( attribute "WATTAGE" "1/16W"
					( Origin gFrontEnd )
				)
				( attribute "XY" "(525,2675)"
					( Origin gFrontEnd )
				)
				( attribute "CHIPS_PART_NAME" "RES"
					( Origin gPackager )
				)
				( attribute "CDS_PART_NAME" "RES_0402-0.0,5%,1/16W,EMPTY,G2A"
					( Origin gPackager )
				)
				( objectStatus "R3F6" )
				( pin "a"
					( attribute "PN" "1"
						( Origin gPackager )
					)
					( objectStatus "R3F6.1" )
				)
				( pin "b"
					( attribute "PN" "2"
						( Origin gPackager )
					)
					( objectStatus "R3F6.2" )
				)
			)
			( gate "@baseboard_fab2_lib.baseboard_fab2(sch_1):page104_i93"
				( attribute "CDS_LIB" "mstr_discrete"
					( Origin gPackager )
				)
				( attribute "CDS_LOCATION" "R8D43"
					( Origin gPackager )
				)
				( attribute "CDS_SEC" "1"
					( Origin gPackager )
				)
				( attribute "LOCATION" "R8D43"
					( Origin gFrontEnd )
				)
				( attribute "MATERIAL" "CHIP"
					( Origin gFrontEnd )
				)
				( attribute "PACK_TYPE" "0402"
					( Origin gFrontEnd )
				)
				( attribute "PART_NUMBER" "G21497-005"
					( Origin gFrontEnd )
				)
				( attribute "PHYS_PAGE" "104"
					( Origin gFrontEnd )
				)
				( attribute "ROOM" "CLOCK_CPU1_OSC"
					( Origin gFrontEnd )
				)
				( attribute "ROT" "0"
					( Origin gFrontEnd )
				)
				( attribute "SEC" "1"
					( Origin gFrontEnd )
				)
				( attribute "SEC_TYPE" "0402"
					( Origin gFrontEnd )
				)
				( attribute "TOLERANCE" "5%"
					( Origin gFrontEnd )
				)
				( attribute "VALUE" "0.0"
					( Origin gFrontEnd )
				)
				( attribute "VER" "1"
					( Origin gFrontEnd )
				)
				( attribute "WATTAGE" "1/16W"
					( Origin gFrontEnd )
				)
				( attribute "XY" "(550,2200)"
					( Origin gFrontEnd )
				)
				( attribute "CHIPS_PART_NAME" "RES"
					( Origin gPackager )
				)
				( attribute "CDS_PART_NAME" "RES_0402-0.0,5%,1/16W,CHIP,G21A"
					( Origin gPackager )
				)
				( objectStatus "R8D43" )
				( pin "a"
					( attribute "PN" "1"
						( Origin gPackager )
					)
					( objectStatus "R8D43.1" )
				)
				( pin "b"
					( attribute "PN" "2"
						( Origin gPackager )
					)
					( objectStatus "R8D43.2" )
				)
			)
			( gate "@baseboard_fab2_lib.baseboard_fab2(sch_1):page104_i94"
				( attribute "CDS_LIB" "mstr_discrete"
					( Origin gPackager )
				)
				( attribute "CDS_LOCATION" "R7D40"
					( Origin gPackager )
				)
				( attribute "CDS_SEC" "1"
					( Origin gPackager )
				)
				( attribute "LOCATION" "R7D40"
					( Origin gFrontEnd )
				)
				( attribute "MATERIAL" "EMPTY"
					( Origin gFrontEnd )
				)
				( attribute "PACK_TYPE" "0402"
					( Origin gFrontEnd )
				)
				( attribute "PART_NUMBER" "G21497-005"
					( Origin gFrontEnd )
				)
				( attribute "PHYS_PAGE" "104"
					( Origin gFrontEnd )
				)
				( attribute "ROOM" "CLOCK_CPU1_OSC"
					( Origin gFrontEnd )
				)
				( attribute "ROT" "0"
					( Origin gFrontEnd )
				)
				( attribute "SEC" "1"
					( Origin gFrontEnd )
				)
				( attribute "SEC_TYPE" "0402"
					( Origin gFrontEnd )
				)
				( attribute "TOLERANCE" "5%"
					( Origin gFrontEnd )
				)
				( attribute "VALUE" "0.0"
					( Origin gFrontEnd )
				)
				( attribute "VER" "1"
					( Origin gFrontEnd )
				)
				( attribute "WATTAGE" "1/16W"
					( Origin gFrontEnd )
				)
				( attribute "XY" "(550,2000)"
					( Origin gFrontEnd )
				)
				( attribute "CHIPS_PART_NAME" "RES"
					( Origin gPackager )
				)
				( attribute "CDS_PART_NAME" "RES_0402-0.0,5%,1/16W,EMPTY,G2A"
					( Origin gPackager )
				)
				( objectStatus "R7D40" )
				( pin "a"
					( attribute "PN" "1"
						( Origin gPackager )
					)
					( objectStatus "R7D40.1" )
				)
				( pin "b"
					( attribute "PN" "2"
						( Origin gPackager )
					)
					( objectStatus "R7D40.2" )
				)
			)
			( gate "@baseboard_fab2_lib.baseboard_fab2(sch_1):page104_i95"
				( attribute "CDS_LIB" "mstr_discrete"
					( Origin gPackager )
				)
				( attribute "CDS_LOCATION" "R7D39"
					( Origin gPackager )
				)
				( attribute "CDS_SEC" "1"
					( Origin gPackager )
				)
				( attribute "LOCATION" "R7D39"
					( Origin gFrontEnd )
				)
				( attribute "MATERIAL" "EMPTY"
					( Origin gFrontEnd )
				)
				( attribute "PACK_TYPE" "0402"
					( Origin gFrontEnd )
				)
				( attribute "PART_NUMBER" "G21497-005"
					( Origin gFrontEnd )
				)
				( attribute "PHYS_PAGE" "104"
					( Origin gFrontEnd )
				)
				( attribute "ROT" "0"
					( Origin gFrontEnd )
				)
				( attribute "SEC" "1"
					( Origin gFrontEnd )
				)
				( attribute "SEC_TYPE" "0402"
					( Origin gFrontEnd )
				)
				( attribute "TOLERANCE" "5%"
					( Origin gFrontEnd )
				)
				( attribute "VALUE" "0.0"
					( Origin gFrontEnd )
				)
				( attribute "VER" "1"
					( Origin gFrontEnd )
				)
				( attribute "WATTAGE" "1/16W"
					( Origin gFrontEnd )
				)
				( attribute "XY" "(550,1800)"
					( Origin gFrontEnd )
				)
				( attribute "CHIPS_PART_NAME" "RES"
					( Origin gPackager )
				)
				( attribute "CDS_PART_NAME" "RES_0402-0.0,5%,1/16W,EMPTY,G2A"
					( Origin gPackager )
				)
				( objectStatus "R7D39" )
				( pin "a"
					( attribute "PN" "1"
						( Origin gPackager )
					)
					( objectStatus "R7D39.1" )
				)
				( pin "b"
					( attribute "PN" "2"
						( Origin gPackager )
					)
					( objectStatus "R7D39.2" )
				)
			)
			( gate "@baseboard_fab2_lib.baseboard_fab2(sch_1):page104_i96"
				( attribute "CDS_LIB" "mstr_discrete"
					( Origin gPackager )
				)
				( attribute "CDS_LOCATION" "R7D36"
					( Origin gPackager )
				)
				( attribute "CDS_SEC" "1"
					( Origin gPackager )
				)
				( attribute "LOCATION" "R7D36"
					( Origin gFrontEnd )
				)
				( attribute "MATERIAL" "CHIP"
					( Origin gFrontEnd )
				)
				( attribute "PACK_TYPE" "0402"
					( Origin gFrontEnd )
				)
				( attribute "PART_NUMBER" "G21497-005"
					( Origin gFrontEnd )
				)
				( attribute "PHYS_PAGE" "104"
					( Origin gFrontEnd )
				)
				( attribute "ROOM" "CLOCK_CPU1_OSC"
					( Origin gFrontEnd )
				)
				( attribute "ROT" "0"
					( Origin gFrontEnd )
				)
				( attribute "SEC" "1"
					( Origin gFrontEnd )
				)
				( attribute "SEC_TYPE" "0402"
					( Origin gFrontEnd )
				)
				( attribute "TOLERANCE" "5%"
					( Origin gFrontEnd )
				)
				( attribute "VALUE" "0.0"
					( Origin gFrontEnd )
				)
				( attribute "VER" "1"
					( Origin gFrontEnd )
				)
				( attribute "WATTAGE" "1/16W"
					( Origin gFrontEnd )
				)
				( attribute "XY" "(550,1500)"
					( Origin gFrontEnd )
				)
				( attribute "CHIPS_PART_NAME" "RES"
					( Origin gPackager )
				)
				( attribute "CDS_PART_NAME" "RES_0402-0.0,5%,1/16W,CHIP,G21A"
					( Origin gPackager )
				)
				( objectStatus "R7D36" )
				( pin "a"
					( attribute "PN" "1"
						( Origin gPackager )
					)
					( objectStatus "R7D36.1" )
				)
				( pin "b"
					( attribute "PN" "2"
						( Origin gPackager )
					)
					( objectStatus "R7D36.2" )
				)
			)
			( gate "@baseboard_fab2_lib.baseboard_fab2(sch_1):page104_i97"
				( attribute "CDS_LIB" "mstr_discrete"
					( Origin gPackager )
				)
				( attribute "CDS_LOCATION" "R7D38"
					( Origin gPackager )
				)
				( attribute "CDS_SEC" "1"
					( Origin gPackager )
				)
				( attribute "LOCATION" "R7D38"
					( Origin gFrontEnd )
				)
				( attribute "MATERIAL" "EMPTY"
					( Origin gFrontEnd )
				)
				( attribute "PACK_TYPE" "0402"
					( Origin gFrontEnd )
				)
				( attribute "PART_NUMBER" "G21497-005"
					( Origin gFrontEnd )
				)
				( attribute "PHYS_PAGE" "104"
					( Origin gFrontEnd )
				)
				( attribute "ROOM" "CLOCK_CPU1_OSC"
					( Origin gFrontEnd )
				)
				( attribute "ROT" "0"
					( Origin gFrontEnd )
				)
				( attribute "SEC" "1"
					( Origin gFrontEnd )
				)
				( attribute "SEC_TYPE" "0402"
					( Origin gFrontEnd )
				)
				( attribute "TOLERANCE" "5%"
					( Origin gFrontEnd )
				)
				( attribute "VALUE" "0.0"
					( Origin gFrontEnd )
				)
				( attribute "VER" "1"
					( Origin gFrontEnd )
				)
				( attribute "WATTAGE" "1/16W"
					( Origin gFrontEnd )
				)
				( attribute "XY" "(550,1300)"
					( Origin gFrontEnd )
				)
				( attribute "CHIPS_PART_NAME" "RES"
					( Origin gPackager )
				)
				( attribute "CDS_PART_NAME" "RES_0402-0.0,5%,1/16W,EMPTY,G2A"
					( Origin gPackager )
				)
				( objectStatus "R7D38" )
				( pin "a"
					( attribute "PN" "1"
						( Origin gPackager )
					)
					( objectStatus "R7D38.1" )
				)
				( pin "b"
					( attribute "PN" "2"
						( Origin gPackager )
					)
					( objectStatus "R7D38.2" )
				)
			)
			( gate "@baseboard_fab2_lib.baseboard_fab2(sch_1):page104_i98"
				( attribute "CDS_LIB" "mstr_discrete"
					( Origin gPackager )
				)
				( attribute "CDS_LOCATION" "R7D37"
					( Origin gPackager )
				)
				( attribute "CDS_SEC" "1"
					( Origin gPackager )
				)
				( attribute "LOCATION" "R7D37"
					( Origin gFrontEnd )
				)
				( attribute "MATERIAL" "EMPTY"
					( Origin gFrontEnd )
				)
				( attribute "PACK_TYPE" "0402"
					( Origin gFrontEnd )
				)
				( attribute "PART_NUMBER" "G21497-005"
					( Origin gFrontEnd )
				)
				( attribute "PHYS_PAGE" "104"
					( Origin gFrontEnd )
				)
				( attribute "ROT" "0"
					( Origin gFrontEnd )
				)
				( attribute "SEC" "1"
					( Origin gFrontEnd )
				)
				( attribute "SEC_TYPE" "0402"
					( Origin gFrontEnd )
				)
				( attribute "TOLERANCE" "5%"
					( Origin gFrontEnd )
				)
				( attribute "VALUE" "0.0"
					( Origin gFrontEnd )
				)
				( attribute "VER" "1"
					( Origin gFrontEnd )
				)
				( attribute "WATTAGE" "1/16W"
					( Origin gFrontEnd )
				)
				( attribute "XY" "(550,1100)"
					( Origin gFrontEnd )
				)
				( attribute "CHIPS_PART_NAME" "RES"
					( Origin gPackager )
				)
				( attribute "CDS_PART_NAME" "RES_0402-0.0,5%,1/16W,EMPTY,G2A"
					( Origin gPackager )
				)
				( objectStatus "R7D37" )
				( pin "a"
					( attribute "PN" "1"
						( Origin gPackager )
					)
					( objectStatus "R7D37.1" )
				)
				( pin "b"
					( attribute "PN" "2"
						( Origin gPackager )
					)
					( objectStatus "R7D37.2" )
				)
			)
			( gate "@baseboard_fab2_lib.baseboard_fab2(sch_1):page105_i1"
				( attribute "CDS_LIB" "mstr_discrete"
					( Origin gPackager )
				)
				( attribute "CDS_LOCATION" "C7G24"
					( Origin gPackager )
				)
				( attribute "CDS_SEC" "1"
					( Origin gPackager )
				)
				( attribute "LOCATION" "C7G24"
					( Origin gFrontEnd )
				)
				( attribute "MATERIAL" "X7R"
					( Origin gFrontEnd )
				)
				( attribute "PACK_TYPE" "0402"
					( Origin gFrontEnd )
				)
				( attribute "PART_NUMBER" "A36096-155"
					( Origin gFrontEnd )
				)
				( attribute "PHYS_PAGE" "105"
					( Origin gFrontEnd )
				)
				( attribute "ROOM" "OCP_STEERING"
					( Origin gFrontEnd )
				)
				( attribute "ROT" "2"
					( Origin gFrontEnd )
				)
				( attribute "SEC" "1"
					( Origin gFrontEnd )
				)
				( attribute "SEC_TYPE" "0402"
					( Origin gFrontEnd )
				)
				( attribute "TOLERANCE" "10%"
					( Origin gFrontEnd )
				)
				( attribute "VALUE" "0.22UF"
					( Origin gFrontEnd )
				)
				( attribute "VER" "1"
					( Origin gFrontEnd )
				)
				( attribute "VOLTAGE" "16V"
					( Units "uVoltage" "V" 1.000000)
					( Origin gFrontEnd )
				)
				( attribute "XY" "(1125,3650)"
					( Origin gFrontEnd )
				)
				( attribute "CHIPS_PART_NAME" "CAP"
					( Origin gPackager )
				)
				( attribute "CDS_PART_NAME" "CAP_0402-0.22UF,16V,10%,X7R,A3A"
					( Origin gPackager )
				)
				( objectStatus "C7G24" )
				( pin "a"
					( attribute "PN" "1"
						( Origin gPackager )
					)
					( objectStatus "C7G24.1" )
				)
				( pin "b"
					( attribute "PN" "2"
						( Origin gPackager )
					)
					( objectStatus "C7G24.2" )
				)
			)
			( gate "@baseboard_fab2_lib.baseboard_fab2(sch_1):page105_i6"
				( attribute "CDS_LIB" "mstr_discrete"
					( Origin gPackager )
				)
				( attribute "CDS_LOCATION" "C7G6"
					( Origin gPackager )
				)
				( attribute "CDS_SEC" "1"
					( Origin gPackager )
				)
				( attribute "LOCATION" "C7G6"
					( Origin gFrontEnd )
				)
				( attribute "MATERIAL" "X7R"
					( Origin gFrontEnd )
				)
				( attribute "PACK_TYPE" "0402"
					( Origin gFrontEnd )
				)
				( attribute "PART_NUMBER" "A36096-155"
					( Origin gFrontEnd )
				)
				( attribute "PHYS_PAGE" "105"
					( Origin gFrontEnd )
				)
				( attribute "ROOM" "OCP_STEERING"
					( Origin gFrontEnd )
				)
				( attribute "ROT" "2"
					( Origin gFrontEnd )
				)
				( attribute "SEC" "1"
					( Origin gPackager )
				)
				( attribute "TOLERANCE" "10%"
					( Origin gFrontEnd )
				)
				( attribute "VALUE" "0.22UF"
					( Origin gFrontEnd )
				)
				( attribute "VER" "1"
					( Origin gFrontEnd )
				)
				( attribute "VOLTAGE" "16V"
					( Units "uVoltage" "V" 1.000000)
					( Origin gFrontEnd )
				)
				( attribute "XY" "(-700,3350)"
					( Origin gFrontEnd )
				)
				( attribute "CHIPS_PART_NAME" "CAP"
					( Origin gPackager )
				)
				( attribute "CDS_PART_NAME" "CAP_0402-0.22UF,16V,10%,X7R,A3A"
					( Origin gPackager )
				)
				( objectStatus "C7G6" )
				( pin "a"
					( attribute "PN" "1"
						( Origin gPackager )
					)
					( objectStatus "C7G6.1" )
				)
				( pin "b"
					( attribute "PN" "2"
						( Origin gPackager )
					)
					( objectStatus "C7G6.2" )
				)
			)
			( gate "@baseboard_fab2_lib.baseboard_fab2(sch_1):page105_i7"
				( attribute "CDS_LIB" "mstr_discrete"
					( Origin gPackager )
				)
				( attribute "CDS_LOCATION" "C7G7"
					( Origin gPackager )
				)
				( attribute "CDS_SEC" "1"
					( Origin gPackager )
				)
				( attribute "LOCATION" "C7G7"
					( Origin gFrontEnd )
				)
				( attribute "MATERIAL" "X7R"
					( Origin gFrontEnd )
				)
				( attribute "PACK_TYPE" "0402"
					( Origin gFrontEnd )
				)
				( attribute "PART_NUMBER" "A36096-155"
					( Origin gFrontEnd )
				)
				( attribute "PHYS_PAGE" "105"
					( Origin gFrontEnd )
				)
				( attribute "ROOM" "OCP_STEERING"
					( Origin gFrontEnd )
				)
				( attribute "ROT" "2"
					( Origin gFrontEnd )
				)
				( attribute "SEC" "1"
					( Origin gFrontEnd )
				)
				( attribute "SEC_TYPE" "0402"
					( Origin gFrontEnd )
				)
				( attribute "TOLERANCE" "10%"
					( Origin gFrontEnd )
				)
				( attribute "VALUE" "0.22UF"
					( Origin gFrontEnd )
				)
				( attribute "VER" "1"
					( Origin gFrontEnd )
				)
				( attribute "VOLTAGE" "16V"
					( Units "uVoltage" "V" 1.000000)
					( Origin gFrontEnd )
				)
				( attribute "XY" "(-500,3650)"
					( Origin gFrontEnd )
				)
				( attribute "CHIPS_PART_NAME" "CAP"
					( Origin gPackager )
				)
				( attribute "CDS_PART_NAME" "CAP_0402-0.22UF,16V,10%,X7R,A3A"
					( Origin gPackager )
				)
				( objectStatus "C7G7" )
				( pin "a"
					( attribute "PN" "1"
						( Origin gPackager )
					)
					( objectStatus "C7G7.1" )
				)
				( pin "b"
					( attribute "PN" "2"
						( Origin gPackager )
					)
					( objectStatus "C7G7.2" )
				)
			)
			( gate "@baseboard_fab2_lib.baseboard_fab2(sch_1):page105_i8"
				( attribute "CDS_LIB" "mstr_discrete"
					( Origin gPackager )
				)
				( attribute "CDS_LOCATION" "C7G10"
					( Origin gPackager )
				)
				( attribute "CDS_SEC" "1"
					( Origin gPackager )
				)
				( attribute "LOCATION" "C7G10"
					( Origin gFrontEnd )
				)
				( attribute "MATERIAL" "X7R"
					( Origin gFrontEnd )
				)
				( attribute "PACK_TYPE" "0402"
					( Origin gFrontEnd )
				)
				( attribute "PART_NUMBER" "A36096-155"
					( Origin gFrontEnd )
				)
				( attribute "PHYS_PAGE" "105"
					( Origin gFrontEnd )
				)
				( attribute "ROOM" "OCP_STEERING"
					( Origin gFrontEnd )
				)
				( attribute "ROT" "2"
					( Origin gFrontEnd )
				)
				( attribute "SEC" "1"
					( Origin gFrontEnd )
				)
				( attribute "SEC_TYPE" "0402"
					( Origin gFrontEnd )
				)
				( attribute "TOLERANCE" "10%"
					( Origin gFrontEnd )
				)
				( attribute "VALUE" "0.22UF"
					( Origin gFrontEnd )
				)
				( attribute "VER" "1"
					( Origin gFrontEnd )
				)
				( attribute "VOLTAGE" "16V"
					( Units "uVoltage" "V" 1.000000)
					( Origin gFrontEnd )
				)
				( attribute "XY" "(-300,3350)"
					( Origin gFrontEnd )
				)
				( attribute "CHIPS_PART_NAME" "CAP"
					( Origin gPackager )
				)
				( attribute "CDS_PART_NAME" "CAP_0402-0.22UF,16V,10%,X7R,A3A"
					( Origin gPackager )
				)
				( objectStatus "C7G10" )
				( pin "a"
					( attribute "PN" "1"
						( Origin gPackager )
					)
					( objectStatus "C7G10.1" )
				)
				( pin "b"
					( attribute "PN" "2"
						( Origin gPackager )
					)
					( objectStatus "C7G10.2" )
				)
			)
			( gate "@baseboard_fab2_lib.baseboard_fab2(sch_1):page105_i12"
				( attribute "CDS_LIB" "mstr_discrete"
					( Origin gPackager )
				)
				( attribute "CDS_LOCATION" "C7G12"
					( Origin gPackager )
				)
				( attribute "CDS_SEC" "1"
					( Origin gPackager )
				)
				( attribute "LOCATION" "C7G12"
					( Origin gFrontEnd )
				)
				( attribute "MATERIAL" "X7R"
					( Origin gFrontEnd )
				)
				( attribute "PACK_TYPE" "0402"
					( Origin gFrontEnd )
				)
				( attribute "PART_NUMBER" "A36096-155"
					( Origin gFrontEnd )
				)
				( attribute "PHYS_PAGE" "105"
					( Origin gFrontEnd )
				)
				( attribute "ROOM" "OCP_STEERING"
					( Origin gFrontEnd )
				)
				( attribute "ROT" "2"
					( Origin gFrontEnd )
				)
				( attribute "SEC" "1"
					( Origin gFrontEnd )
				)
				( attribute "SEC_TYPE" "0402"
					( Origin gFrontEnd )
				)
				( attribute "TOLERANCE" "10%"
					( Origin gFrontEnd )
				)
				( attribute "VALUE" "0.22UF"
					( Origin gFrontEnd )
				)
				( attribute "VER" "1"
					( Origin gFrontEnd )
				)
				( attribute "VOLTAGE" "16V"
					( Units "uVoltage" "V" 1.000000)
					( Origin gFrontEnd )
				)
				( attribute "XY" "(-100,3650)"
					( Origin gFrontEnd )
				)
				( attribute "CHIPS_PART_NAME" "CAP"
					( Origin gPackager )
				)
				( attribute "CDS_PART_NAME" "CAP_0402-0.22UF,16V,10%,X7R,A3A"
					( Origin gPackager )
				)
				( objectStatus "C7G12" )
				( pin "a"
					( attribute "PN" "1"
						( Origin gPackager )
					)
					( objectStatus "C7G12.1" )
				)
				( pin "b"
					( attribute "PN" "2"
						( Origin gPackager )
					)
					( objectStatus "C7G12.2" )
				)
			)
			( gate "@baseboard_fab2_lib.baseboard_fab2(sch_1):page105_i13"
				( attribute "CDS_LIB" "mstr_discrete"
					( Origin gPackager )
				)
				( attribute "CDS_LOCATION" "C7G13"
					( Origin gPackager )
				)
				( attribute "CDS_SEC" "1"
					( Origin gPackager )
				)
				( attribute "LOCATION" "C7G13"
					( Origin gFrontEnd )
				)
				( attribute "MATERIAL" "X7R"
					( Origin gFrontEnd )
				)
				( attribute "PACK_TYPE" "0402"
					( Origin gFrontEnd )
				)
				( attribute "PART_NUMBER" "A36096-155"
					( Origin gFrontEnd )
				)
				( attribute "PHYS_PAGE" "105"
					( Origin gFrontEnd )
				)
				( attribute "ROOM" "OCP_STEERING"
					( Origin gFrontEnd )
				)
				( attribute "ROT" "2"
					( Origin gFrontEnd )
				)
				( attribute "SEC" "1"
					( Origin gFrontEnd )
				)
				( attribute "SEC_TYPE" "0402"
					( Origin gFrontEnd )
				)
				( attribute "TOLERANCE" "10%"
					( Origin gFrontEnd )
				)
				( attribute "VALUE" "0.22UF"
					( Origin gFrontEnd )
				)
				( attribute "VER" "1"
					( Origin gFrontEnd )
				)
				( attribute "VOLTAGE" "16V"
					( Units "uVoltage" "V" 1.000000)
					( Origin gFrontEnd )
				)
				( attribute "XY" "(100,3350)"
					( Origin gFrontEnd )
				)
				( attribute "CHIPS_PART_NAME" "CAP"
					( Origin gPackager )
				)
				( attribute "CDS_PART_NAME" "CAP_0402-0.22UF,16V,10%,X7R,A3A"
					( Origin gPackager )
				)
				( objectStatus "C7G13" )
				( pin "a"
					( attribute "PN" "1"
						( Origin gPackager )
					)
					( objectStatus "C7G13.1" )
				)
				( pin "b"
					( attribute "PN" "2"
						( Origin gPackager )
					)
					( objectStatus "C7G13.2" )
				)
			)
			( gate "@baseboard_fab2_lib.baseboard_fab2(sch_1):page105_i20"
				( attribute "CDS_LIB" "mstr_discrete"
					( Origin gPackager )
				)
				( attribute "CDS_LOCATION" "C7G5"
					( Origin gPackager )
				)
				( attribute "CDS_SEC" "1"
					( Origin gPackager )
				)
				( attribute "LOCATION" "C7G5"
					( Origin gFrontEnd )
				)
				( attribute "MATERIAL" "X7R"
					( Origin gFrontEnd )
				)
				( attribute "PACK_TYPE" "0402"
					( Origin gFrontEnd )
				)
				( attribute "PART_NUMBER" "A36096-155"
					( Origin gFrontEnd )
				)
				( attribute "PHYS_PAGE" "105"
					( Origin gFrontEnd )
				)
				( attribute "ROOM" "OCP_STEERING"
					( Origin gFrontEnd )
				)
				( attribute "ROT" "2"
					( Origin gFrontEnd )
				)
				( attribute "SEC" "1"
					( Origin gFrontEnd )
				)
				( attribute "SEC_TYPE" "0402"
					( Origin gFrontEnd )
				)
				( attribute "TOLERANCE" "10%"
					( Origin gFrontEnd )
				)
				( attribute "VALUE" "0.22UF"
					( Origin gFrontEnd )
				)
				( attribute "VER" "1"
					( Origin gFrontEnd )
				)
				( attribute "VOLTAGE" "16V"
					( Units "uVoltage" "V" 1.000000)
					( Origin gFrontEnd )
				)
				( attribute "XY" "(-750,4350)"
					( Origin gFrontEnd )
				)
				( attribute "CHIPS_PART_NAME" "CAP"
					( Origin gPackager )
				)
				( attribute "CDS_PART_NAME" "CAP_0402-0.22UF,16V,10%,X7R,A3A"
					( Origin gPackager )
				)
				( objectStatus "C7G5" )
				( pin "a"
					( attribute "PN" "1"
						( Origin gPackager )
					)
					( objectStatus "C7G5.1" )
				)
				( pin "b"
					( attribute "PN" "2"
						( Origin gPackager )
					)
					( objectStatus "C7G5.2" )
				)
			)
			( gate "@baseboard_fab2_lib.baseboard_fab2(sch_1):page105_i21"
				( attribute "CDS_LIB" "mstr_discrete"
					( Origin gPackager )
				)
				( attribute "CDS_LOCATION" "C7G9"
					( Origin gPackager )
				)
				( attribute "CDS_SEC" "1"
					( Origin gPackager )
				)
				( attribute "LOCATION" "C7G9"
					( Origin gFrontEnd )
				)
				( attribute "MATERIAL" "X7R"
					( Origin gFrontEnd )
				)
				( attribute "PACK_TYPE" "0402"
					( Origin gFrontEnd )
				)
				( attribute "PART_NUMBER" "A36096-155"
					( Origin gFrontEnd )
				)
				( attribute "PHYS_PAGE" "105"
					( Origin gFrontEnd )
				)
				( attribute "ROOM" "OCP_STEERING"
					( Origin gFrontEnd )
				)
				( attribute "ROT" "2"
					( Origin gFrontEnd )
				)
				( attribute "SEC" "1"
					( Origin gFrontEnd )
				)
				( attribute "SEC_TYPE" "0402"
					( Origin gFrontEnd )
				)
				( attribute "TOLERANCE" "10%"
					( Origin gFrontEnd )
				)
				( attribute "VALUE" "0.22UF"
					( Origin gFrontEnd )
				)
				( attribute "VER" "1"
					( Origin gFrontEnd )
				)
				( attribute "VOLTAGE" "16V"
					( Units "uVoltage" "V" 1.000000)
					( Origin gFrontEnd )
				)
				( attribute "XY" "(-350,4350)"
					( Origin gFrontEnd )
				)
				( attribute "CHIPS_PART_NAME" "CAP"
					( Origin gPackager )
				)
				( attribute "CDS_PART_NAME" "CAP_0402-0.22UF,16V,10%,X7R,A3A"
					( Origin gPackager )
				)
				( objectStatus "C7G9" )
				( pin "a"
					( attribute "PN" "1"
						( Origin gPackager )
					)
					( objectStatus "C7G9.1" )
				)
				( pin "b"
					( attribute "PN" "2"
						( Origin gPackager )
					)
					( objectStatus "C7G9.2" )
				)
			)
			( gate "@baseboard_fab2_lib.baseboard_fab2(sch_1):page105_i22"
				( attribute "CDS_LIB" "mstr_discrete"
					( Origin gPackager )
				)
				( attribute "CDS_LOCATION" "C7G8"
					( Origin gPackager )
				)
				( attribute "CDS_SEC" "1"
					( Origin gPackager )
				)
				( attribute "LOCATION" "C7G8"
					( Origin gFrontEnd )
				)
				( attribute "MATERIAL" "X7R"
					( Origin gFrontEnd )
				)
				( attribute "PACK_TYPE" "0402"
					( Origin gFrontEnd )
				)
				( attribute "PART_NUMBER" "A36096-155"
					( Origin gFrontEnd )
				)
				( attribute "PHYS_PAGE" "105"
					( Origin gFrontEnd )
				)
				( attribute "ROOM" "OCP_STEERING"
					( Origin gFrontEnd )
				)
				( attribute "ROT" "2"
					( Origin gFrontEnd )
				)
				( attribute "SEC" "1"
					( Origin gFrontEnd )
				)
				( attribute "SEC_TYPE" "0402"
					( Origin gFrontEnd )
				)
				( attribute "TOLERANCE" "10%"
					( Origin gFrontEnd )
				)
				( attribute "VALUE" "0.22UF"
					( Origin gFrontEnd )
				)
				( attribute "VER" "1"
					( Origin gFrontEnd )
				)
				( attribute "VOLTAGE" "16V"
					( Units "uVoltage" "V" 1.000000)
					( Origin gFrontEnd )
				)
				( attribute "XY" "(-550,4650)"
					( Origin gFrontEnd )
				)
				( attribute "CHIPS_PART_NAME" "CAP"
					( Origin gPackager )
				)
				( attribute "CDS_PART_NAME" "CAP_0402-0.22UF,16V,10%,X7R,A3A"
					( Origin gPackager )
				)
				( objectStatus "C7G8" )
				( pin "a"
					( attribute "PN" "1"
						( Origin gPackager )
					)
					( objectStatus "C7G8.1" )
				)
				( pin "b"
					( attribute "PN" "2"
						( Origin gPackager )
					)
					( objectStatus "C7G8.2" )
				)
			)
			( gate "@baseboard_fab2_lib.baseboard_fab2(sch_1):page105_i27"
				( attribute "CDS_LIB" "mstr_discrete"
					( Origin gPackager )
				)
				( attribute "CDS_LOCATION" "C7G11"
					( Origin gPackager )
				)
				( attribute "CDS_SEC" "1"
					( Origin gPackager )
				)
				( attribute "LOCATION" "C7G11"
					( Origin gFrontEnd )
				)
				( attribute "MATERIAL" "X7R"
					( Origin gFrontEnd )
				)
				( attribute "PACK_TYPE" "0402"
					( Origin gFrontEnd )
				)
				( attribute "PART_NUMBER" "A36096-155"
					( Origin gFrontEnd )
				)
				( attribute "PHYS_PAGE" "105"
					( Origin gFrontEnd )
				)
				( attribute "ROOM" "OCP_STEERING"
					( Origin gFrontEnd )
				)
				( attribute "ROT" "2"
					( Origin gFrontEnd )
				)
				( attribute "SEC" "1"
					( Origin gFrontEnd )
				)
				( attribute "SEC_TYPE" "0402"
					( Origin gFrontEnd )
				)
				( attribute "TOLERANCE" "10%"
					( Origin gFrontEnd )
				)
				( attribute "VALUE" "0.22UF"
					( Origin gFrontEnd )
				)
				( attribute "VER" "1"
					( Origin gFrontEnd )
				)
				( attribute "VOLTAGE" "16V"
					( Units "uVoltage" "V" 1.000000)
					( Origin gFrontEnd )
				)
				( attribute "XY" "(-150,4650)"
					( Origin gFrontEnd )
				)
				( attribute "CHIPS_PART_NAME" "CAP"
					( Origin gPackager )
				)
				( attribute "CDS_PART_NAME" "CAP_0402-0.22UF,16V,10%,X7R,A3A"
					( Origin gPackager )
				)
				( objectStatus "C7G11" )
				( pin "a"
					( attribute "PN" "1"
						( Origin gPackager )
					)
					( objectStatus "C7G11.1" )
				)
				( pin "b"
					( attribute "PN" "2"
						( Origin gPackager )
					)
					( objectStatus "C7G11.2" )
				)
			)
			( gate "@baseboard_fab2_lib.baseboard_fab2(sch_1):page105_i28"
				( attribute "CDS_LIB" "mstr_discrete"
					( Origin gPackager )
				)
				( attribute "CDS_LOCATION" "C7G14"
					( Origin gPackager )
				)
				( attribute "CDS_SEC" "1"
					( Origin gPackager )
				)
				( attribute "LOCATION" "C7G14"
					( Origin gFrontEnd )
				)
				( attribute "MATERIAL" "X7R"
					( Origin gFrontEnd )
				)
				( attribute "PACK_TYPE" "0402"
					( Origin gFrontEnd )
				)
				( attribute "PART_NUMBER" "A36096-155"
					( Origin gFrontEnd )
				)
				( attribute "PHYS_PAGE" "105"
					( Origin gFrontEnd )
				)
				( attribute "ROOM" "OCP_STEERING"
					( Origin gFrontEnd )
				)
				( attribute "ROT" "2"
					( Origin gFrontEnd )
				)
				( attribute "SEC" "1"
					( Origin gFrontEnd )
				)
				( attribute "SEC_TYPE" "0402"
					( Origin gFrontEnd )
				)
				( attribute "TOLERANCE" "10%"
					( Origin gFrontEnd )
				)
				( attribute "VALUE" "0.22UF"
					( Origin gFrontEnd )
				)
				( attribute "VER" "1"
					( Origin gFrontEnd )
				)
				( attribute "VOLTAGE" "16V"
					( Units "uVoltage" "V" 1.000000)
					( Origin gFrontEnd )
				)
				( attribute "XY" "(50,4350)"
					( Origin gFrontEnd )
				)
				( attribute "CHIPS_PART_NAME" "CAP"
					( Origin gPackager )
				)
				( attribute "CDS_PART_NAME" "CAP_0402-0.22UF,16V,10%,X7R,A3A"
					( Origin gPackager )
				)
				( objectStatus "C7G14" )
				( pin "a"
					( attribute "PN" "1"
						( Origin gPackager )
					)
					( objectStatus "C7G14.1" )
				)
				( pin "b"
					( attribute "PN" "2"
						( Origin gPackager )
					)
					( objectStatus "C7G14.2" )
				)
			)
			( gate "@baseboard_fab2_lib.baseboard_fab2(sch_1):page105_i31"
				( attribute "CDS_LIB" "mstr_discrete"
					( Origin gPackager )
				)
				( attribute "CDS_LOCATION" "C7G16"
					( Origin gPackager )
				)
				( attribute "CDS_SEC" "1"
					( Origin gPackager )
				)
				( attribute "LOCATION" "C7G16"
					( Origin gFrontEnd )
				)
				( attribute "MATERIAL" "X7R"
					( Origin gFrontEnd )
				)
				( attribute "PACK_TYPE" "0402"
					( Origin gFrontEnd )
				)
				( attribute "PART_NUMBER" "A36096-155"
					( Origin gFrontEnd )
				)
				( attribute "PHYS_PAGE" "105"
					( Origin gFrontEnd )
				)
				( attribute "ROOM" "OCP_STEERING"
					( Origin gFrontEnd )
				)
				( attribute "ROT" "2"
					( Origin gFrontEnd )
				)
				( attribute "SEC" "1"
					( Origin gFrontEnd )
				)
				( attribute "SEC_TYPE" "0402"
					( Origin gFrontEnd )
				)
				( attribute "TOLERANCE" "10%"
					( Origin gFrontEnd )
				)
				( attribute "VALUE" "0.22UF"
					( Origin gFrontEnd )
				)
				( attribute "VER" "1"
					( Origin gFrontEnd )
				)
				( attribute "VOLTAGE" "16V"
					( Units "uVoltage" "V" 1.000000)
					( Origin gFrontEnd )
				)
				( attribute "XY" "(300,3650)"
					( Origin gFrontEnd )
				)
				( attribute "CHIPS_PART_NAME" "CAP"
					( Origin gPackager )
				)
				( attribute "CDS_PART_NAME" "CAP_0402-0.22UF,16V,10%,X7R,A3A"
					( Origin gPackager )
				)
				( objectStatus "C7G16" )
				( pin "a"
					( attribute "PN" "1"
						( Origin gPackager )
					)
					( objectStatus "C7G16.1" )
				)
				( pin "b"
					( attribute "PN" "2"
						( Origin gPackager )
					)
					( objectStatus "C7G16.2" )
				)
			)
			( gate "@baseboard_fab2_lib.baseboard_fab2(sch_1):page105_i32"
				( attribute "CDS_LIB" "mstr_discrete"
					( Origin gPackager )
				)
				( attribute "CDS_LOCATION" "C7G18"
					( Origin gPackager )
				)
				( attribute "CDS_SEC" "1"
					( Origin gPackager )
				)
				( attribute "LOCATION" "C7G18"
					( Origin gFrontEnd )
				)
				( attribute "MATERIAL" "X7R"
					( Origin gFrontEnd )
				)
				( attribute "PACK_TYPE" "0402"
					( Origin gFrontEnd )
				)
				( attribute "PART_NUMBER" "A36096-155"
					( Origin gFrontEnd )
				)
				( attribute "PHYS_PAGE" "105"
					( Origin gFrontEnd )
				)
				( attribute "ROOM" "OCP_STEERING"
					( Origin gFrontEnd )
				)
				( attribute "ROT" "2"
					( Origin gFrontEnd )
				)
				( attribute "SEC" "1"
					( Origin gFrontEnd )
				)
				( attribute "SEC_TYPE" "0402"
					( Origin gFrontEnd )
				)
				( attribute "TOLERANCE" "10%"
					( Origin gFrontEnd )
				)
				( attribute "VALUE" "0.22UF"
					( Origin gFrontEnd )
				)
				( attribute "VER" "1"
					( Origin gFrontEnd )
				)
				( attribute "VOLTAGE" "16V"
					( Units "uVoltage" "V" 1.000000)
					( Origin gFrontEnd )
				)
				( attribute "XY" "(500,3350)"
					( Origin gFrontEnd )
				)
				( attribute "CHIPS_PART_NAME" "CAP"
					( Origin gPackager )
				)
				( attribute "CDS_PART_NAME" "CAP_0402-0.22UF,16V,10%,X7R,A3A"
					( Origin gPackager )
				)
				( objectStatus "C7G18" )
				( pin "a"
					( attribute "PN" "1"
						( Origin gPackager )
					)
					( objectStatus "C7G18.1" )
				)
				( pin "b"
					( attribute "PN" "2"
						( Origin gPackager )
					)
					( objectStatus "C7G18.2" )
				)
			)
			( gate "@baseboard_fab2_lib.baseboard_fab2(sch_1):page105_i34"
				( attribute "CDS_LIB" "mstr_discrete"
					( Origin gPackager )
				)
				( attribute "CDS_LOCATION" "C7G20"
					( Origin gPackager )
				)
				( attribute "CDS_SEC" "1"
					( Origin gPackager )
				)
				( attribute "LOCATION" "C7G20"
					( Origin gFrontEnd )
				)
				( attribute "MATERIAL" "X7R"
					( Origin gFrontEnd )
				)
				( attribute "PACK_TYPE" "0402"
					( Origin gFrontEnd )
				)
				( attribute "PART_NUMBER" "A36096-155"
					( Origin gFrontEnd )
				)
				( attribute "PHYS_PAGE" "105"
					( Origin gFrontEnd )
				)
				( attribute "ROOM" "OCP_STEERING"
					( Origin gFrontEnd )
				)
				( attribute "ROT" "2"
					( Origin gFrontEnd )
				)
				( attribute "SEC" "1"
					( Origin gFrontEnd )
				)
				( attribute "SEC_TYPE" "0402"
					( Origin gFrontEnd )
				)
				( attribute "TOLERANCE" "10%"
					( Origin gFrontEnd )
				)
				( attribute "VALUE" "0.22UF"
					( Origin gFrontEnd )
				)
				( attribute "VER" "1"
					( Origin gFrontEnd )
				)
				( attribute "VOLTAGE" "16V"
					( Units "uVoltage" "V" 1.000000)
					( Origin gFrontEnd )
				)
				( attribute "XY" "(700,3650)"
					( Origin gFrontEnd )
				)
				( attribute "CHIPS_PART_NAME" "CAP"
					( Origin gPackager )
				)
				( attribute "CDS_PART_NAME" "CAP_0402-0.22UF,16V,10%,X7R,A3A"
					( Origin gPackager )
				)
				( objectStatus "C7G20" )
				( pin "a"
					( attribute "PN" "1"
						( Origin gPackager )
					)
					( objectStatus "C7G20.1" )
				)
				( pin "b"
					( attribute "PN" "2"
						( Origin gPackager )
					)
					( objectStatus "C7G20.2" )
				)
			)
			( gate "@baseboard_fab2_lib.baseboard_fab2(sch_1):page105_i37"
				( attribute "CDS_LIB" "mstr_discrete"
					( Origin gPackager )
				)
				( attribute "CDS_LOCATION" "C7G22"
					( Origin gPackager )
				)
				( attribute "CDS_SEC" "1"
					( Origin gPackager )
				)
				( attribute "LOCATION" "C7G22"
					( Origin gFrontEnd )
				)
				( attribute "MATERIAL" "X7R"
					( Origin gFrontEnd )
				)
				( attribute "PACK_TYPE" "0402"
					( Origin gFrontEnd )
				)
				( attribute "PART_NUMBER" "A36096-155"
					( Origin gFrontEnd )
				)
				( attribute "PHYS_PAGE" "105"
					( Origin gFrontEnd )
				)
				( attribute "ROOM" "OCP_STEERING"
					( Origin gFrontEnd )
				)
				( attribute "ROT" "2"
					( Origin gFrontEnd )
				)
				( attribute "SEC" "1"
					( Origin gFrontEnd )
				)
				( attribute "SEC_TYPE" "0402"
					( Origin gFrontEnd )
				)
				( attribute "TOLERANCE" "10%"
					( Origin gFrontEnd )
				)
				( attribute "VALUE" "0.22UF"
					( Origin gFrontEnd )
				)
				( attribute "VER" "1"
					( Origin gFrontEnd )
				)
				( attribute "VOLTAGE" "16V"
					( Units "uVoltage" "V" 1.000000)
					( Origin gFrontEnd )
				)
				( attribute "XY" "(925,3350)"
					( Origin gFrontEnd )
				)
				( attribute "CHIPS_PART_NAME" "CAP"
					( Origin gPackager )
				)
				( attribute "CDS_PART_NAME" "CAP_0402-0.22UF,16V,10%,X7R,A3A"
					( Origin gPackager )
				)
				( objectStatus "C7G22" )
				( pin "a"
					( attribute "PN" "1"
						( Origin gPackager )
					)
					( objectStatus "C7G22.1" )
				)
				( pin "b"
					( attribute "PN" "2"
						( Origin gPackager )
					)
					( objectStatus "C7G22.2" )
				)
			)
			( gate "@baseboard_fab2_lib.baseboard_fab2(sch_1):page105_i44"
				( attribute "CDS_LIB" "mstr_discrete"
					( Origin gPackager )
				)
				( attribute "CDS_LOCATION" "C7G17"
					( Origin gPackager )
				)
				( attribute "CDS_SEC" "1"
					( Origin gPackager )
				)
				( attribute "LOCATION" "C7G17"
					( Origin gFrontEnd )
				)
				( attribute "MATERIAL" "X7R"
					( Origin gFrontEnd )
				)
				( attribute "PACK_TYPE" "0402"
					( Origin gFrontEnd )
				)
				( attribute "PART_NUMBER" "A36096-155"
					( Origin gFrontEnd )
				)
				( attribute "PHYS_PAGE" "105"
					( Origin gFrontEnd )
				)
				( attribute "ROOM" "OCP_STEERING"
					( Origin gFrontEnd )
				)
				( attribute "ROT" "2"
					( Origin gFrontEnd )
				)
				( attribute "SEC" "1"
					( Origin gFrontEnd )
				)
				( attribute "SEC_TYPE" "0402"
					( Origin gFrontEnd )
				)
				( attribute "TOLERANCE" "10%"
					( Origin gFrontEnd )
				)
				( attribute "VALUE" "0.22UF"
					( Origin gFrontEnd )
				)
				( attribute "VER" "1"
					( Origin gFrontEnd )
				)
				( attribute "VOLTAGE" "16V"
					( Units "uVoltage" "V" 1.000000)
					( Origin gFrontEnd )
				)
				( attribute "XY" "(450,4350)"
					( Origin gFrontEnd )
				)
				( attribute "CHIPS_PART_NAME" "CAP"
					( Origin gPackager )
				)
				( attribute "CDS_PART_NAME" "CAP_0402-0.22UF,16V,10%,X7R,A3A"
					( Origin gPackager )
				)
				( objectStatus "C7G17" )
				( pin "a"
					( attribute "PN" "1"
						( Origin gPackager )
					)
					( objectStatus "C7G17.1" )
				)
				( pin "b"
					( attribute "PN" "2"
						( Origin gPackager )
					)
					( objectStatus "C7G17.2" )
				)
			)
			( gate "@baseboard_fab2_lib.baseboard_fab2(sch_1):page105_i45"
				( attribute "CDS_LIB" "mstr_discrete"
					( Origin gPackager )
				)
				( attribute "CDS_LOCATION" "C7G15"
					( Origin gPackager )
				)
				( attribute "CDS_SEC" "1"
					( Origin gPackager )
				)
				( attribute "LOCATION" "C7G15"
					( Origin gFrontEnd )
				)
				( attribute "MATERIAL" "X7R"
					( Origin gFrontEnd )
				)
				( attribute "PACK_TYPE" "0402"
					( Origin gFrontEnd )
				)
				( attribute "PART_NUMBER" "A36096-155"
					( Origin gFrontEnd )
				)
				( attribute "PHYS_PAGE" "105"
					( Origin gFrontEnd )
				)
				( attribute "ROOM" "OCP_STEERING"
					( Origin gFrontEnd )
				)
				( attribute "ROT" "2"
					( Origin gFrontEnd )
				)
				( attribute "SEC" "1"
					( Origin gFrontEnd )
				)
				( attribute "SEC_TYPE" "0402"
					( Origin gFrontEnd )
				)
				( attribute "TOLERANCE" "10%"
					( Origin gFrontEnd )
				)
				( attribute "VALUE" "0.22UF"
					( Origin gFrontEnd )
				)
				( attribute "VER" "1"
					( Origin gFrontEnd )
				)
				( attribute "VOLTAGE" "16V"
					( Units "uVoltage" "V" 1.000000)
					( Origin gFrontEnd )
				)
				( attribute "XY" "(250,4650)"
					( Origin gFrontEnd )
				)
				( attribute "CHIPS_PART_NAME" "CAP"
					( Origin gPackager )
				)
				( attribute "CDS_PART_NAME" "CAP_0402-0.22UF,16V,10%,X7R,A3A"
					( Origin gPackager )
				)
				( objectStatus "C7G15" )
				( pin "a"
					( attribute "PN" "1"
						( Origin gPackager )
					)
					( objectStatus "C7G15.1" )
				)
				( pin "b"
					( attribute "PN" "2"
						( Origin gPackager )
					)
					( objectStatus "C7G15.2" )
				)
			)
			( gate "@baseboard_fab2_lib.baseboard_fab2(sch_1):page105_i46"
				( attribute "CDS_LIB" "mstr_discrete"
					( Origin gPackager )
				)
				( attribute "CDS_LOCATION" "C7G19"
					( Origin gPackager )
				)
				( attribute "CDS_SEC" "1"
					( Origin gPackager )
				)
				( attribute "LOCATION" "C7G19"
					( Origin gFrontEnd )
				)
				( attribute "MATERIAL" "X7R"
					( Origin gFrontEnd )
				)
				( attribute "PACK_TYPE" "0402"
					( Origin gFrontEnd )
				)
				( attribute "PART_NUMBER" "A36096-155"
					( Origin gFrontEnd )
				)
				( attribute "PHYS_PAGE" "105"
					( Origin gFrontEnd )
				)
				( attribute "ROOM" "OCP_STEERING"
					( Origin gFrontEnd )
				)
				( attribute "ROT" "2"
					( Origin gFrontEnd )
				)
				( attribute "SEC" "1"
					( Origin gFrontEnd )
				)
				( attribute "SEC_TYPE" "0402"
					( Origin gFrontEnd )
				)
				( attribute "TOLERANCE" "10%"
					( Origin gFrontEnd )
				)
				( attribute "VALUE" "0.22UF"
					( Origin gFrontEnd )
				)
				( attribute "VER" "1"
					( Origin gFrontEnd )
				)
				( attribute "VOLTAGE" "16V"
					( Units "uVoltage" "V" 1.000000)
					( Origin gFrontEnd )
				)
				( attribute "XY" "(650,4650)"
					( Origin gFrontEnd )
				)
				( attribute "CHIPS_PART_NAME" "CAP"
					( Origin gPackager )
				)
				( attribute "CDS_PART_NAME" "CAP_0402-0.22UF,16V,10%,X7R,A3A"
					( Origin gPackager )
				)
				( objectStatus "C7G19" )
				( pin "a"
					( attribute "PN" "1"
						( Origin gPackager )
					)
					( objectStatus "C7G19.1" )
				)
				( pin "b"
					( attribute "PN" "2"
						( Origin gPackager )
					)
					( objectStatus "C7G19.2" )
				)
			)
			( gate "@baseboard_fab2_lib.baseboard_fab2(sch_1):page105_i51"
				( attribute "CDS_LIB" "mstr_discrete"
					( Origin gPackager )
				)
				( attribute "CDS_LOCATION" "C7G21"
					( Origin gPackager )
				)
				( attribute "CDS_SEC" "1"
					( Origin gPackager )
				)
				( attribute "LOCATION" "C7G21"
					( Origin gFrontEnd )
				)
				( attribute "MATERIAL" "X7R"
					( Origin gFrontEnd )
				)
				( attribute "PACK_TYPE" "0402"
					( Origin gFrontEnd )
				)
				( attribute "PART_NUMBER" "A36096-155"
					( Origin gFrontEnd )
				)
				( attribute "PHYS_PAGE" "105"
					( Origin gFrontEnd )
				)
				( attribute "ROOM" "OCP_STEERING"
					( Origin gFrontEnd )
				)
				( attribute "ROT" "2"
					( Origin gFrontEnd )
				)
				( attribute "SEC" "1"
					( Origin gFrontEnd )
				)
				( attribute "SEC_TYPE" "0402"
					( Origin gFrontEnd )
				)
				( attribute "TOLERANCE" "10%"
					( Origin gFrontEnd )
				)
				( attribute "VALUE" "0.22UF"
					( Origin gFrontEnd )
				)
				( attribute "VER" "1"
					( Origin gFrontEnd )
				)
				( attribute "VOLTAGE" "16V"
					( Units "uVoltage" "V" 1.000000)
					( Origin gFrontEnd )
				)
				( attribute "XY" "(875,4350)"
					( Origin gFrontEnd )
				)
				( attribute "CHIPS_PART_NAME" "CAP"
					( Origin gPackager )
				)
				( attribute "CDS_PART_NAME" "CAP_0402-0.22UF,16V,10%,X7R,A3A"
					( Origin gPackager )
				)
				( objectStatus "C7G21" )
				( pin "a"
					( attribute "PN" "1"
						( Origin gPackager )
					)
					( objectStatus "C7G21.1" )
				)
				( pin "b"
					( attribute "PN" "2"
						( Origin gPackager )
					)
					( objectStatus "C7G21.2" )
				)
			)
			( gate "@baseboard_fab2_lib.baseboard_fab2(sch_1):page105_i52"
				( attribute "CDS_LIB" "mstr_discrete"
					( Origin gPackager )
				)
				( attribute "CDS_LOCATION" "C7G23"
					( Origin gPackager )
				)
				( attribute "CDS_SEC" "1"
					( Origin gPackager )
				)
				( attribute "LOCATION" "C7G23"
					( Origin gFrontEnd )
				)
				( attribute "MATERIAL" "X7R"
					( Origin gFrontEnd )
				)
				( attribute "PACK_TYPE" "0402"
					( Origin gFrontEnd )
				)
				( attribute "PART_NUMBER" "A36096-155"
					( Origin gFrontEnd )
				)
				( attribute "PHYS_PAGE" "105"
					( Origin gFrontEnd )
				)
				( attribute "ROOM" "OCP_STEERING"
					( Origin gFrontEnd )
				)
				( attribute "ROT" "2"
					( Origin gFrontEnd )
				)
				( attribute "SEC" "1"
					( Origin gFrontEnd )
				)
				( attribute "SEC_TYPE" "0402"
					( Origin gFrontEnd )
				)
				( attribute "TOLERANCE" "10%"
					( Origin gFrontEnd )
				)
				( attribute "VALUE" "0.22UF"
					( Origin gFrontEnd )
				)
				( attribute "VER" "1"
					( Origin gFrontEnd )
				)
				( attribute "VOLTAGE" "16V"
					( Units "uVoltage" "V" 1.000000)
					( Origin gFrontEnd )
				)
				( attribute "XY" "(1075,4650)"
					( Origin gFrontEnd )
				)
				( attribute "CHIPS_PART_NAME" "CAP"
					( Origin gPackager )
				)
				( attribute "CDS_PART_NAME" "CAP_0402-0.22UF,16V,10%,X7R,A3A"
					( Origin gPackager )
				)
				( objectStatus "C7G23" )
				( pin "a"
					( attribute "PN" "1"
						( Origin gPackager )
					)
					( objectStatus "C7G23.1" )
				)
				( pin "b"
					( attribute "PN" "2"
						( Origin gPackager )
					)
					( objectStatus "C7G23.2" )
				)
			)
			( gate "@baseboard_fab2_lib.baseboard_fab2(sch_1):page105_i55"
				( attribute "CDS_LIB" "mstr_discrete"
					( Origin gPackager )
				)
				( attribute "CDS_LOCATION" "C7G26"
					( Origin gPackager )
				)
				( attribute "CDS_SEC" "1"
					( Origin gPackager )
				)
				( attribute "LOCATION" "C7G26"
					( Origin gFrontEnd )
				)
				( attribute "MATERIAL" "X7R"
					( Origin gFrontEnd )
				)
				( attribute "PACK_TYPE" "0402"
					( Origin gFrontEnd )
				)
				( attribute "PART_NUMBER" "A36096-155"
					( Origin gFrontEnd )
				)
				( attribute "PHYS_PAGE" "105"
					( Origin gFrontEnd )
				)
				( attribute "ROOM" "OCP_STEERING"
					( Origin gFrontEnd )
				)
				( attribute "ROT" "2"
					( Origin gFrontEnd )
				)
				( attribute "SEC" "1"
					( Origin gFrontEnd )
				)
				( attribute "SEC_TYPE" "0402"
					( Origin gFrontEnd )
				)
				( attribute "TOLERANCE" "10%"
					( Origin gFrontEnd )
				)
				( attribute "VALUE" "0.22UF"
					( Origin gFrontEnd )
				)
				( attribute "VER" "1"
					( Origin gFrontEnd )
				)
				( attribute "VOLTAGE" "16V"
					( Units "uVoltage" "V" 1.000000)
					( Origin gFrontEnd )
				)
				( attribute "XY" "(1325,3350)"
					( Origin gFrontEnd )
				)
				( attribute "CHIPS_PART_NAME" "CAP"
					( Origin gPackager )
				)
				( attribute "CDS_PART_NAME" "CAP_0402-0.22UF,16V,10%,X7R,A3A"
					( Origin gPackager )
				)
				( objectStatus "C7G26" )
				( pin "a"
					( attribute "PN" "1"
						( Origin gPackager )
					)
					( objectStatus "C7G26.1" )
				)
				( pin "b"
					( attribute "PN" "2"
						( Origin gPackager )
					)
					( objectStatus "C7G26.2" )
				)
			)
			( gate "@baseboard_fab2_lib.baseboard_fab2(sch_1):page105_i56"
				( attribute "CDS_LIB" "mstr_discrete"
					( Origin gPackager )
				)
				( attribute "CDS_LOCATION" "C8G4"
					( Origin gPackager )
				)
				( attribute "CDS_SEC" "1"
					( Origin gPackager )
				)
				( attribute "LOCATION" "C8G4"
					( Origin gFrontEnd )
				)
				( attribute "MATERIAL" "X7R"
					( Origin gFrontEnd )
				)
				( attribute "PACK_TYPE" "0402"
					( Origin gFrontEnd )
				)
				( attribute "PART_NUMBER" "A36096-155"
					( Origin gFrontEnd )
				)
				( attribute "PHYS_PAGE" "105"
					( Origin gFrontEnd )
				)
				( attribute "ROOM" "OCP_STEERING"
					( Origin gFrontEnd )
				)
				( attribute "ROT" "2"
					( Origin gFrontEnd )
				)
				( attribute "SEC" "1"
					( Origin gFrontEnd )
				)
				( attribute "SEC_TYPE" "0402"
					( Origin gFrontEnd )
				)
				( attribute "TOLERANCE" "10%"
					( Origin gFrontEnd )
				)
				( attribute "VALUE" "0.22UF"
					( Origin gFrontEnd )
				)
				( attribute "VER" "1"
					( Origin gFrontEnd )
				)
				( attribute "VOLTAGE" "16V"
					( Units "uVoltage" "V" 1.000000)
					( Origin gFrontEnd )
				)
				( attribute "XY" "(1725,3350)"
					( Origin gFrontEnd )
				)
				( attribute "CHIPS_PART_NAME" "CAP"
					( Origin gPackager )
				)
				( attribute "CDS_PART_NAME" "CAP_0402-0.22UF,16V,10%,X7R,A3A"
					( Origin gPackager )
				)
				( objectStatus "C8G4" )
				( pin "a"
					( attribute "PN" "1"
						( Origin gPackager )
					)
					( objectStatus "C8G4.1" )
				)
				( pin "b"
					( attribute "PN" "2"
						( Origin gPackager )
					)
					( objectStatus "C8G4.2" )
				)
			)
			( gate "@baseboard_fab2_lib.baseboard_fab2(sch_1):page105_i58"
				( attribute "CDS_LIB" "mstr_discrete"
					( Origin gPackager )
				)
				( attribute "CDS_LOCATION" "C8G2"
					( Origin gPackager )
				)
				( attribute "CDS_SEC" "1"
					( Origin gPackager )
				)
				( attribute "LOCATION" "C8G2"
					( Origin gFrontEnd )
				)
				( attribute "MATERIAL" "X7R"
					( Origin gFrontEnd )
				)
				( attribute "PACK_TYPE" "0402"
					( Origin gFrontEnd )
				)
				( attribute "PART_NUMBER" "A36096-155"
					( Origin gFrontEnd )
				)
				( attribute "PHYS_PAGE" "105"
					( Origin gFrontEnd )
				)
				( attribute "ROOM" "OCP_STEERING"
					( Origin gFrontEnd )
				)
				( attribute "ROT" "2"
					( Origin gFrontEnd )
				)
				( attribute "SEC" "1"
					( Origin gFrontEnd )
				)
				( attribute "SEC_TYPE" "0402"
					( Origin gFrontEnd )
				)
				( attribute "TOLERANCE" "10%"
					( Origin gFrontEnd )
				)
				( attribute "VALUE" "0.22UF"
					( Origin gFrontEnd )
				)
				( attribute "VER" "1"
					( Origin gFrontEnd )
				)
				( attribute "VOLTAGE" "16V"
					( Units "uVoltage" "V" 1.000000)
					( Origin gFrontEnd )
				)
				( attribute "XY" "(1525,3650)"
					( Origin gFrontEnd )
				)
				( attribute "CHIPS_PART_NAME" "CAP"
					( Origin gPackager )
				)
				( attribute "CDS_PART_NAME" "CAP_0402-0.22UF,16V,10%,X7R,A3A"
					( Origin gPackager )
				)
				( objectStatus "C8G2" )
				( pin "a"
					( attribute "PN" "1"
						( Origin gPackager )
					)
					( objectStatus "C8G2.1" )
				)
				( pin "b"
					( attribute "PN" "2"
						( Origin gPackager )
					)
					( objectStatus "C8G2.2" )
				)
			)
			( gate "@baseboard_fab2_lib.baseboard_fab2(sch_1):page105_i61"
				( attribute "CDS_LIB" "mstr_discrete"
					( Origin gPackager )
				)
				( attribute "CDS_LOCATION" "C8G6"
					( Origin gPackager )
				)
				( attribute "CDS_SEC" "1"
					( Origin gPackager )
				)
				( attribute "LOCATION" "C8G6"
					( Origin gFrontEnd )
				)
				( attribute "MATERIAL" "X7R"
					( Origin gFrontEnd )
				)
				( attribute "PACK_TYPE" "0402"
					( Origin gFrontEnd )
				)
				( attribute "PART_NUMBER" "A36096-155"
					( Origin gFrontEnd )
				)
				( attribute "PHYS_PAGE" "105"
					( Origin gFrontEnd )
				)
				( attribute "ROOM" "OCP_STEERING"
					( Origin gFrontEnd )
				)
				( attribute "ROT" "2"
					( Origin gFrontEnd )
				)
				( attribute "SEC" "1"
					( Origin gFrontEnd )
				)
				( attribute "SEC_TYPE" "0402"
					( Origin gFrontEnd )
				)
				( attribute "TOLERANCE" "10%"
					( Origin gFrontEnd )
				)
				( attribute "VALUE" "0.22UF"
					( Origin gFrontEnd )
				)
				( attribute "VER" "1"
					( Origin gFrontEnd )
				)
				( attribute "VOLTAGE" "16V"
					( Units "uVoltage" "V" 1.000000)
					( Origin gFrontEnd )
				)
				( attribute "XY" "(1925,3650)"
					( Origin gFrontEnd )
				)
				( attribute "CHIPS_PART_NAME" "CAP"
					( Origin gPackager )
				)
				( attribute "CDS_PART_NAME" "CAP_0402-0.22UF,16V,10%,X7R,A3A"
					( Origin gPackager )
				)
				( objectStatus "C8G6" )
				( pin "a"
					( attribute "PN" "1"
						( Origin gPackager )
					)
					( objectStatus "C8G6.1" )
				)
				( pin "b"
					( attribute "PN" "2"
						( Origin gPackager )
					)
					( objectStatus "C8G6.2" )
				)
			)
			( gate "@baseboard_fab2_lib.baseboard_fab2(sch_1):page105_i62"
				( attribute "CDS_LIB" "mstr_discrete"
					( Origin gPackager )
				)
				( attribute "CDS_LOCATION" "C8G7"
					( Origin gPackager )
				)
				( attribute "CDS_SEC" "1"
					( Origin gPackager )
				)
				( attribute "LOCATION" "C8G7"
					( Origin gFrontEnd )
				)
				( attribute "MATERIAL" "X7R"
					( Origin gFrontEnd )
				)
				( attribute "PACK_TYPE" "0402"
					( Origin gFrontEnd )
				)
				( attribute "PART_NUMBER" "A36096-155"
					( Origin gFrontEnd )
				)
				( attribute "PHYS_PAGE" "105"
					( Origin gFrontEnd )
				)
				( attribute "ROOM" "OCP_STEERING"
					( Origin gFrontEnd )
				)
				( attribute "ROT" "2"
					( Origin gFrontEnd )
				)
				( attribute "SEC" "1"
					( Origin gFrontEnd )
				)
				( attribute "SEC_TYPE" "0402"
					( Origin gFrontEnd )
				)
				( attribute "TOLERANCE" "10%"
					( Origin gFrontEnd )
				)
				( attribute "VALUE" "0.22UF"
					( Origin gFrontEnd )
				)
				( attribute "VER" "1"
					( Origin gFrontEnd )
				)
				( attribute "VOLTAGE" "16V"
					( Units "uVoltage" "V" 1.000000)
					( Origin gFrontEnd )
				)
				( attribute "XY" "(2125,3350)"
					( Origin gFrontEnd )
				)
				( attribute "CHIPS_PART_NAME" "CAP"
					( Origin gPackager )
				)
				( attribute "CDS_PART_NAME" "CAP_0402-0.22UF,16V,10%,X7R,A3A"
					( Origin gPackager )
				)
				( objectStatus "C8G7" )
				( pin "a"
					( attribute "PN" "1"
						( Origin gPackager )
					)
					( objectStatus "C8G7.1" )
				)
				( pin "b"
					( attribute "PN" "2"
						( Origin gPackager )
					)
					( objectStatus "C8G7.2" )
				)
			)
			( gate "@baseboard_fab2_lib.baseboard_fab2(sch_1):page105_i69"
				( attribute "CDS_LIB" "mstr_discrete"
					( Origin gPackager )
				)
				( attribute "CDS_LOCATION" "C7G25"
					( Origin gPackager )
				)
				( attribute "CDS_SEC" "1"
					( Origin gPackager )
				)
				( attribute "LOCATION" "C7G25"
					( Origin gFrontEnd )
				)
				( attribute "MATERIAL" "X7R"
					( Origin gFrontEnd )
				)
				( attribute "PACK_TYPE" "0402"
					( Origin gFrontEnd )
				)
				( attribute "PART_NUMBER" "A36096-155"
					( Origin gFrontEnd )
				)
				( attribute "PHYS_PAGE" "105"
					( Origin gFrontEnd )
				)
				( attribute "ROOM" "OCP_STEERING"
					( Origin gFrontEnd )
				)
				( attribute "ROT" "2"
					( Origin gFrontEnd )
				)
				( attribute "SEC" "1"
					( Origin gFrontEnd )
				)
				( attribute "SEC_TYPE" "0402"
					( Origin gFrontEnd )
				)
				( attribute "TOLERANCE" "10%"
					( Origin gFrontEnd )
				)
				( attribute "VALUE" "0.22UF"
					( Origin gFrontEnd )
				)
				( attribute "VER" "1"
					( Origin gFrontEnd )
				)
				( attribute "VOLTAGE" "16V"
					( Units "uVoltage" "V" 1.000000)
					( Origin gFrontEnd )
				)
				( attribute "XY" "(1275,4350)"
					( Origin gFrontEnd )
				)
				( attribute "CHIPS_PART_NAME" "CAP"
					( Origin gPackager )
				)
				( attribute "CDS_PART_NAME" "CAP_0402-0.22UF,16V,10%,X7R,A3A"
					( Origin gPackager )
				)
				( objectStatus "C7G25" )
				( pin "a"
					( attribute "PN" "1"
						( Origin gPackager )
					)
					( objectStatus "C7G25.1" )
				)
				( pin "b"
					( attribute "PN" "2"
						( Origin gPackager )
					)
					( objectStatus "C7G25.2" )
				)
			)
			( gate "@baseboard_fab2_lib.baseboard_fab2(sch_1):page105_i70"
				( attribute "CDS_LIB" "mstr_discrete"
					( Origin gPackager )
				)
				( attribute "CDS_LOCATION" "C8G1"
					( Origin gPackager )
				)
				( attribute "CDS_SEC" "1"
					( Origin gPackager )
				)
				( attribute "LOCATION" "C8G1"
					( Origin gFrontEnd )
				)
				( attribute "MATERIAL" "X7R"
					( Origin gFrontEnd )
				)
				( attribute "PACK_TYPE" "0402"
					( Origin gFrontEnd )
				)
				( attribute "PART_NUMBER" "A36096-155"
					( Origin gFrontEnd )
				)
				( attribute "PHYS_PAGE" "105"
					( Origin gFrontEnd )
				)
				( attribute "ROOM" "OCP_STEERING"
					( Origin gFrontEnd )
				)
				( attribute "ROT" "2"
					( Origin gFrontEnd )
				)
				( attribute "SEC" "1"
					( Origin gFrontEnd )
				)
				( attribute "SEC_TYPE" "0402"
					( Origin gFrontEnd )
				)
				( attribute "TOLERANCE" "10%"
					( Origin gFrontEnd )
				)
				( attribute "VALUE" "0.22UF"
					( Origin gFrontEnd )
				)
				( attribute "VER" "1"
					( Origin gFrontEnd )
				)
				( attribute "VOLTAGE" "16V"
					( Units "uVoltage" "V" 1.000000)
					( Origin gFrontEnd )
				)
				( attribute "XY" "(1475,4650)"
					( Origin gFrontEnd )
				)
				( attribute "CHIPS_PART_NAME" "CAP"
					( Origin gPackager )
				)
				( attribute "CDS_PART_NAME" "CAP_0402-0.22UF,16V,10%,X7R,A3A"
					( Origin gPackager )
				)
				( objectStatus "C8G1" )
				( pin "a"
					( attribute "PN" "1"
						( Origin gPackager )
					)
					( objectStatus "C8G1.1" )
				)
				( pin "b"
					( attribute "PN" "2"
						( Origin gPackager )
					)
					( objectStatus "C8G1.2" )
				)
			)
			( gate "@baseboard_fab2_lib.baseboard_fab2(sch_1):page105_i71"
				( attribute "CDS_LIB" "mstr_discrete"
					( Origin gPackager )
				)
				( attribute "CDS_LOCATION" "C8G3"
					( Origin gPackager )
				)
				( attribute "CDS_SEC" "1"
					( Origin gPackager )
				)
				( attribute "LOCATION" "C8G3"
					( Origin gFrontEnd )
				)
				( attribute "MATERIAL" "X7R"
					( Origin gFrontEnd )
				)
				( attribute "PACK_TYPE" "0402"
					( Origin gFrontEnd )
				)
				( attribute "PART_NUMBER" "A36096-155"
					( Origin gFrontEnd )
				)
				( attribute "PHYS_PAGE" "105"
					( Origin gFrontEnd )
				)
				( attribute "ROOM" "OCP_STEERING"
					( Origin gFrontEnd )
				)
				( attribute "ROT" "2"
					( Origin gFrontEnd )
				)
				( attribute "SEC" "1"
					( Origin gFrontEnd )
				)
				( attribute "SEC_TYPE" "0402"
					( Origin gFrontEnd )
				)
				( attribute "TOLERANCE" "10%"
					( Origin gFrontEnd )
				)
				( attribute "VALUE" "0.22UF"
					( Origin gFrontEnd )
				)
				( attribute "VER" "1"
					( Origin gFrontEnd )
				)
				( attribute "VOLTAGE" "16V"
					( Units "uVoltage" "V" 1.000000)
					( Origin gFrontEnd )
				)
				( attribute "XY" "(1675,4350)"
					( Origin gFrontEnd )
				)
				( attribute "CHIPS_PART_NAME" "CAP"
					( Origin gPackager )
				)
				( attribute "CDS_PART_NAME" "CAP_0402-0.22UF,16V,10%,X7R,A3A"
					( Origin gPackager )
				)
				( objectStatus "C8G3" )
				( pin "a"
					( attribute "PN" "1"
						( Origin gPackager )
					)
					( objectStatus "C8G3.1" )
				)
				( pin "b"
					( attribute "PN" "2"
						( Origin gPackager )
					)
					( objectStatus "C8G3.2" )
				)
			)
			( gate "@baseboard_fab2_lib.baseboard_fab2(sch_1):page105_i75"
				( attribute "CDS_LIB" "mstr_discrete"
					( Origin gPackager )
				)
				( attribute "CDS_LOCATION" "C8G5"
					( Origin gPackager )
				)
				( attribute "CDS_SEC" "1"
					( Origin gPackager )
				)
				( attribute "LOCATION" "C8G5"
					( Origin gFrontEnd )
				)
				( attribute "MATERIAL" "X7R"
					( Origin gFrontEnd )
				)
				( attribute "PACK_TYPE" "0402"
					( Origin gFrontEnd )
				)
				( attribute "PART_NUMBER" "A36096-155"
					( Origin gFrontEnd )
				)
				( attribute "PHYS_PAGE" "105"
					( Origin gFrontEnd )
				)
				( attribute "ROOM" "OCP_STEERING"
					( Origin gFrontEnd )
				)
				( attribute "ROT" "2"
					( Origin gFrontEnd )
				)
				( attribute "SEC" "1"
					( Origin gFrontEnd )
				)
				( attribute "SEC_TYPE" "0402"
					( Origin gFrontEnd )
				)
				( attribute "TOLERANCE" "10%"
					( Origin gFrontEnd )
				)
				( attribute "VALUE" "0.22UF"
					( Origin gFrontEnd )
				)
				( attribute "VER" "1"
					( Origin gFrontEnd )
				)
				( attribute "VOLTAGE" "16V"
					( Units "uVoltage" "V" 1.000000)
					( Origin gFrontEnd )
				)
				( attribute "XY" "(1875,4650)"
					( Origin gFrontEnd )
				)
				( attribute "CHIPS_PART_NAME" "CAP"
					( Origin gPackager )
				)
				( attribute "CDS_PART_NAME" "CAP_0402-0.22UF,16V,10%,X7R,A3A"
					( Origin gPackager )
				)
				( objectStatus "C8G5" )
				( pin "a"
					( attribute "PN" "1"
						( Origin gPackager )
					)
					( objectStatus "C8G5.1" )
				)
				( pin "b"
					( attribute "PN" "2"
						( Origin gPackager )
					)
					( objectStatus "C8G5.2" )
				)
			)
			( gate "@baseboard_fab2_lib.baseboard_fab2(sch_1):page105_i76"
				( attribute "CDS_LIB" "mstr_discrete"
					( Origin gPackager )
				)
				( attribute "CDS_LOCATION" "C8G8"
					( Origin gPackager )
				)
				( attribute "CDS_SEC" "1"
					( Origin gPackager )
				)
				( attribute "LOCATION" "C8G8"
					( Origin gFrontEnd )
				)
				( attribute "MATERIAL" "X7R"
					( Origin gFrontEnd )
				)
				( attribute "PACK_TYPE" "0402"
					( Origin gFrontEnd )
				)
				( attribute "PART_NUMBER" "A36096-155"
					( Origin gFrontEnd )
				)
				( attribute "PHYS_PAGE" "105"
					( Origin gFrontEnd )
				)
				( attribute "ROOM" "OCP_STEERING"
					( Origin gFrontEnd )
				)
				( attribute "ROT" "2"
					( Origin gFrontEnd )
				)
				( attribute "SEC" "1"
					( Origin gFrontEnd )
				)
				( attribute "SEC_TYPE" "0402"
					( Origin gFrontEnd )
				)
				( attribute "TOLERANCE" "10%"
					( Origin gFrontEnd )
				)
				( attribute "VALUE" "0.22UF"
					( Origin gFrontEnd )
				)
				( attribute "VER" "1"
					( Origin gFrontEnd )
				)
				( attribute "VOLTAGE" "16V"
					( Units "uVoltage" "V" 1.000000)
					( Origin gFrontEnd )
				)
				( attribute "XY" "(2075,4350)"
					( Origin gFrontEnd )
				)
				( attribute "CHIPS_PART_NAME" "CAP"
					( Origin gPackager )
				)
				( attribute "CDS_PART_NAME" "CAP_0402-0.22UF,16V,10%,X7R,A3A"
					( Origin gPackager )
				)
				( objectStatus "C8G8" )
				( pin "a"
					( attribute "PN" "1"
						( Origin gPackager )
					)
					( objectStatus "C8G8.1" )
				)
				( pin "b"
					( attribute "PN" "2"
						( Origin gPackager )
					)
					( objectStatus "C8G8.2" )
				)
			)
			( gate "@baseboard_fab2_lib.baseboard_fab2(sch_1):page105_i93"
				( attribute "CDS_LIB" "mstr_discrete"
					( Origin gPackager )
				)
				( attribute "CDS_LOCATION" "C8G9"
					( Origin gPackager )
				)
				( attribute "CDS_SEC" "1"
					( Origin gPackager )
				)
				( attribute "LOCATION" "C8G9"
					( Origin gFrontEnd )
				)
				( attribute "MATERIAL" "X7R"
					( Origin gFrontEnd )
				)
				( attribute "PACK_TYPE" "0402"
					( Origin gFrontEnd )
				)
				( attribute "PART_NUMBER" "A36096-155"
					( Origin gFrontEnd )
				)
				( attribute "PHYS_PAGE" "105"
					( Origin gFrontEnd )
				)
				( attribute "ROOM" "OCP_STEERING"
					( Origin gFrontEnd )
				)
				( attribute "ROT" "2"
					( Origin gFrontEnd )
				)
				( attribute "SEC" "1"
					( Origin gFrontEnd )
				)
				( attribute "SEC_TYPE" "0402"
					( Origin gFrontEnd )
				)
				( attribute "TOLERANCE" "10%"
					( Origin gFrontEnd )
				)
				( attribute "VALUE" "0.22UF"
					( Origin gFrontEnd )
				)
				( attribute "VER" "1"
					( Origin gFrontEnd )
				)
				( attribute "VOLTAGE" "16V"
					( Units "uVoltage" "V" 1.000000)
					( Origin gFrontEnd )
				)
				( attribute "XY" "(2275,4650)"
					( Origin gFrontEnd )
				)
				( attribute "CHIPS_PART_NAME" "CAP"
					( Origin gPackager )
				)
				( attribute "CDS_PART_NAME" "CAP_0402-0.22UF,16V,10%,X7R,A3A"
					( Origin gPackager )
				)
				( objectStatus "C8G9" )
				( pin "a"
					( attribute "PN" "1"
						( Origin gPackager )
					)
					( objectStatus "C8G9.1" )
				)
				( pin "b"
					( attribute "PN" "2"
						( Origin gPackager )
					)
					( objectStatus "C8G9.2" )
				)
			)
			( gate "@baseboard_fab2_lib.baseboard_fab2(sch_1):page105_i96"
				( attribute "CDS_LIB" "mstr_discrete"
					( Origin gPackager )
				)
				( attribute "CDS_LOCATION" "C8G10"
					( Origin gPackager )
				)
				( attribute "CDS_SEC" "1"
					( Origin gPackager )
				)
				( attribute "LOCATION" "C8G10"
					( Origin gFrontEnd )
				)
				( attribute "MATERIAL" "X7R"
					( Origin gFrontEnd )
				)
				( attribute "PACK_TYPE" "0402"
					( Origin gFrontEnd )
				)
				( attribute "PART_NUMBER" "A36096-155"
					( Origin gFrontEnd )
				)
				( attribute "PHYS_PAGE" "105"
					( Origin gFrontEnd )
				)
				( attribute "ROOM" "OCP_STEERING"
					( Origin gFrontEnd )
				)
				( attribute "ROT" "2"
					( Origin gFrontEnd )
				)
				( attribute "SEC" "1"
					( Origin gFrontEnd )
				)
				( attribute "SEC_TYPE" "0402"
					( Origin gFrontEnd )
				)
				( attribute "TOLERANCE" "10%"
					( Origin gFrontEnd )
				)
				( attribute "VALUE" "0.22UF"
					( Origin gFrontEnd )
				)
				( attribute "VER" "1"
					( Origin gFrontEnd )
				)
				( attribute "VOLTAGE" "16V"
					( Units "uVoltage" "V" 1.000000)
					( Origin gFrontEnd )
				)
				( attribute "XY" "(2325,3650)"
					( Origin gFrontEnd )
				)
				( attribute "CHIPS_PART_NAME" "CAP"
					( Origin gPackager )
				)
				( attribute "CDS_PART_NAME" "CAP_0402-0.22UF,16V,10%,X7R,A3A"
					( Origin gPackager )
				)
				( objectStatus "C8G10" )
				( pin "a"
					( attribute "PN" "1"
						( Origin gPackager )
					)
					( objectStatus "C8G10.1" )
				)
				( pin "b"
					( attribute "PN" "2"
						( Origin gPackager )
					)
					( objectStatus "C8G10.2" )
				)
			)
			( gate "@baseboard_fab2_lib.baseboard_fab2(sch_1):page105_i153"
				( attribute "CDS_LIB" "mstr_discrete"
					( Origin gPackager )
				)
				( attribute "CDS_LOCATION" "C6B18"
					( Origin gPackager )
				)
				( attribute "CDS_SEC" "1"
					( Origin gPackager )
				)
				( attribute "LOCATION" "C6B18"
					( Origin gFrontEnd )
				)
				( attribute "MATERIAL" "X7R"
					( Origin gFrontEnd )
				)
				( attribute "PACK_TYPE" "0402"
					( Origin gFrontEnd )
				)
				( attribute "PART_NUMBER" "A36096-155"
					( Origin gFrontEnd )
				)
				( attribute "PHYS_PAGE" "105"
					( Origin gFrontEnd )
				)
				( attribute "ROOM" "OCP_STEERING"
					( Origin gFrontEnd )
				)
				( attribute "ROT" "2"
					( Origin gFrontEnd )
				)
				( attribute "SEC" "1"
					( Origin gFrontEnd )
				)
				( attribute "SEC_TYPE" "0402"
					( Origin gFrontEnd )
				)
				( attribute "TOLERANCE" "10%"
					( Origin gFrontEnd )
				)
				( attribute "VALUE" "0.22UF"
					( Origin gFrontEnd )
				)
				( attribute "VER" "1"
					( Origin gFrontEnd )
				)
				( attribute "VOLTAGE" "16V"
					( Units "uVoltage" "V" 1.000000)
					( Origin gFrontEnd )
				)
				( attribute "XY" "(-1500,975)"
					( Origin gFrontEnd )
				)
				( attribute "CHIPS_PART_NAME" "CAP"
					( Origin gPackager )
				)
				( attribute "CDS_PART_NAME" "CAP_0402-0.22UF,16V,10%,X7R,A3A"
					( Origin gPackager )
				)
				( objectStatus "C6B18" )
				( pin "a"
					( attribute "PN" "1"
						( Origin gPackager )
					)
					( objectStatus "C6B18.1" )
				)
				( pin "b"
					( attribute "PN" "2"
						( Origin gPackager )
					)
					( objectStatus "C6B18.2" )
				)
			)
			( gate "@baseboard_fab2_lib.baseboard_fab2(sch_1):page105_i160"
				( attribute "CDS_LIB" "mstr_discrete"
					( Origin gPackager )
				)
				( attribute "CDS_LOCATION" "C6B19"
					( Origin gPackager )
				)
				( attribute "CDS_SEC" "1"
					( Origin gPackager )
				)
				( attribute "LOCATION" "C6B19"
					( Origin gFrontEnd )
				)
				( attribute "MATERIAL" "X7R"
					( Origin gFrontEnd )
				)
				( attribute "PACK_TYPE" "0402"
					( Origin gFrontEnd )
				)
				( attribute "PART_NUMBER" "A36096-155"
					( Origin gFrontEnd )
				)
				( attribute "PHYS_PAGE" "105"
					( Origin gFrontEnd )
				)
				( attribute "ROOM" "OCP_STEERING"
					( Origin gFrontEnd )
				)
				( attribute "ROT" "2"
					( Origin gFrontEnd )
				)
				( attribute "SEC" "1"
					( Origin gFrontEnd )
				)
				( attribute "SEC_TYPE" "0402"
					( Origin gFrontEnd )
				)
				( attribute "TOLERANCE" "10%"
					( Origin gFrontEnd )
				)
				( attribute "VALUE" "0.22UF"
					( Origin gFrontEnd )
				)
				( attribute "VER" "1"
					( Origin gFrontEnd )
				)
				( attribute "VOLTAGE" "16V"
					( Units "uVoltage" "V" 1.000000)
					( Origin gFrontEnd )
				)
				( attribute "XY" "(-1350,2275)"
					( Origin gFrontEnd )
				)
				( attribute "CHIPS_PART_NAME" "CAP"
					( Origin gPackager )
				)
				( attribute "CDS_PART_NAME" "CAP_0402-0.22UF,16V,10%,X7R,A3A"
					( Origin gPackager )
				)
				( objectStatus "C6B19" )
				( pin "a"
					( attribute "PN" "1"
						( Origin gPackager )
					)
					( objectStatus "C6B19.1" )
				)
				( pin "b"
					( attribute "PN" "2"
						( Origin gPackager )
					)
					( objectStatus "C6B19.2" )
				)
			)
			( gate "@baseboard_fab2_lib.baseboard_fab2(sch_1):page105_i163"
				( attribute "CDS_LIB" "mstr_discrete"
					( Origin gPackager )
				)
				( attribute "CDS_LOCATION" "C6B15"
					( Origin gPackager )
				)
				( attribute "CDS_SEC" "1"
					( Origin gPackager )
				)
				( attribute "LOCATION" "C6B15"
					( Origin gFrontEnd )
				)
				( attribute "MATERIAL" "X7R"
					( Origin gFrontEnd )
				)
				( attribute "PACK_TYPE" "0402"
					( Origin gFrontEnd )
				)
				( attribute "PART_NUMBER" "A36096-155"
					( Origin gFrontEnd )
				)
				( attribute "PHYS_PAGE" "105"
					( Origin gFrontEnd )
				)
				( attribute "ROOM" "OCP_STEERING"
					( Origin gFrontEnd )
				)
				( attribute "ROT" "2"
					( Origin gFrontEnd )
				)
				( attribute "SEC" "1"
					( Origin gFrontEnd )
				)
				( attribute "SEC_TYPE" "0402"
					( Origin gFrontEnd )
				)
				( attribute "TOLERANCE" "10%"
					( Origin gFrontEnd )
				)
				( attribute "VALUE" "0.22UF"
					( Origin gFrontEnd )
				)
				( attribute "VER" "1"
					( Origin gFrontEnd )
				)
				( attribute "VOLTAGE" "16V"
					( Units "uVoltage" "V" 1.000000)
					( Origin gFrontEnd )
				)
				( attribute "XY" "(-1750,2275)"
					( Origin gFrontEnd )
				)
				( attribute "CHIPS_PART_NAME" "CAP"
					( Origin gPackager )
				)
				( attribute "CDS_PART_NAME" "CAP_0402-0.22UF,16V,10%,X7R,A3A"
					( Origin gPackager )
				)
				( objectStatus "C6B15" )
				( pin "a"
					( attribute "PN" "1"
						( Origin gPackager )
					)
					( objectStatus "C6B15.1" )
				)
				( pin "b"
					( attribute "PN" "2"
						( Origin gPackager )
					)
					( objectStatus "C6B15.2" )
				)
			)
			( gate "@baseboard_fab2_lib.baseboard_fab2(sch_1):page105_i166"
				( attribute "CDS_LIB" "mstr_discrete"
					( Origin gPackager )
				)
				( attribute "CDS_LOCATION" "C6B11"
					( Origin gPackager )
				)
				( attribute "CDS_SEC" "1"
					( Origin gPackager )
				)
				( attribute "LOCATION" "C6B11"
					( Origin gFrontEnd )
				)
				( attribute "MATERIAL" "X7R"
					( Origin gFrontEnd )
				)
				( attribute "PACK_TYPE" "0402"
					( Origin gFrontEnd )
				)
				( attribute "PART_NUMBER" "A36096-155"
					( Origin gFrontEnd )
				)
				( attribute "PHYS_PAGE" "105"
					( Origin gFrontEnd )
				)
				( attribute "ROOM" "OCP_STEERING"
					( Origin gFrontEnd )
				)
				( attribute "ROT" "2"
					( Origin gFrontEnd )
				)
				( attribute "SEC" "1"
					( Origin gFrontEnd )
				)
				( attribute "SEC_TYPE" "0402"
					( Origin gFrontEnd )
				)
				( attribute "TOLERANCE" "10%"
					( Origin gFrontEnd )
				)
				( attribute "VALUE" "0.22UF"
					( Origin gFrontEnd )
				)
				( attribute "VER" "1"
					( Origin gFrontEnd )
				)
				( attribute "VOLTAGE" "16V"
					( Units "uVoltage" "V" 1.000000)
					( Origin gFrontEnd )
				)
				( attribute "XY" "(-2150,2275)"
					( Origin gFrontEnd )
				)
				( attribute "CHIPS_PART_NAME" "CAP"
					( Origin gPackager )
				)
				( attribute "CDS_PART_NAME" "CAP_0402-0.22UF,16V,10%,X7R,A3A"
					( Origin gPackager )
				)
				( objectStatus "C6B11" )
				( pin "a"
					( attribute "PN" "1"
						( Origin gPackager )
					)
					( objectStatus "C6B11.1" )
				)
				( pin "b"
					( attribute "PN" "2"
						( Origin gPackager )
					)
					( objectStatus "C6B11.2" )
				)
			)
			( gate "@baseboard_fab2_lib.baseboard_fab2(sch_1):page105_i169"
				( attribute "CDS_LIB" "mstr_discrete"
					( Origin gPackager )
				)
				( attribute "CDS_LOCATION" "C6B6"
					( Origin gPackager )
				)
				( attribute "CDS_SEC" "1"
					( Origin gPackager )
				)
				( attribute "LOCATION" "C6B6"
					( Origin gFrontEnd )
				)
				( attribute "MATERIAL" "X7R"
					( Origin gFrontEnd )
				)
				( attribute "PACK_TYPE" "0402"
					( Origin gFrontEnd )
				)
				( attribute "PART_NUMBER" "A36096-155"
					( Origin gFrontEnd )
				)
				( attribute "PHYS_PAGE" "105"
					( Origin gFrontEnd )
				)
				( attribute "ROOM" "OCP_STEERING"
					( Origin gFrontEnd )
				)
				( attribute "ROT" "2"
					( Origin gFrontEnd )
				)
				( attribute "SEC" "1"
					( Origin gFrontEnd )
				)
				( attribute "SEC_TYPE" "0402"
					( Origin gFrontEnd )
				)
				( attribute "TOLERANCE" "10%"
					( Origin gFrontEnd )
				)
				( attribute "VALUE" "0.22UF"
					( Origin gFrontEnd )
				)
				( attribute "VER" "1"
					( Origin gFrontEnd )
				)
				( attribute "VOLTAGE" "16V"
					( Units "uVoltage" "V" 1.000000)
					( Origin gFrontEnd )
				)
				( attribute "XY" "(-2550,2275)"
					( Origin gFrontEnd )
				)
				( attribute "CHIPS_PART_NAME" "CAP"
					( Origin gPackager )
				)
				( attribute "CDS_PART_NAME" "CAP_0402-0.22UF,16V,10%,X7R,A3A"
					( Origin gPackager )
				)
				( objectStatus "C6B6" )
				( pin "a"
					( attribute "PN" "1"
						( Origin gPackager )
					)
					( objectStatus "C6B6.1" )
				)
				( pin "b"
					( attribute "PN" "2"
						( Origin gPackager )
					)
					( objectStatus "C6B6.2" )
				)
			)
			( gate "@baseboard_fab2_lib.baseboard_fab2(sch_1):page105_i173"
				( attribute "CDS_LIB" "mstr_discrete"
					( Origin gPackager )
				)
				( attribute "CDS_LOCATION" "C6B20"
					( Origin gPackager )
				)
				( attribute "CDS_SEC" "1"
					( Origin gPackager )
				)
				( attribute "LOCATION" "C6B20"
					( Origin gFrontEnd )
				)
				( attribute "MATERIAL" "X7R"
					( Origin gFrontEnd )
				)
				( attribute "PACK_TYPE" "0402"
					( Origin gFrontEnd )
				)
				( attribute "PART_NUMBER" "A36096-155"
					( Origin gFrontEnd )
				)
				( attribute "PHYS_PAGE" "105"
					( Origin gFrontEnd )
				)
				( attribute "ROOM" "OCP_STEERING"
					( Origin gFrontEnd )
				)
				( attribute "ROT" "2"
					( Origin gFrontEnd )
				)
				( attribute "SEC" "1"
					( Origin gFrontEnd )
				)
				( attribute "SEC_TYPE" "0402"
					( Origin gFrontEnd )
				)
				( attribute "TOLERANCE" "10%"
					( Origin gFrontEnd )
				)
				( attribute "VALUE" "0.22UF"
					( Origin gFrontEnd )
				)
				( attribute "VER" "1"
					( Origin gFrontEnd )
				)
				( attribute "VOLTAGE" "16V"
					( Units "uVoltage" "V" 1.000000)
					( Origin gFrontEnd )
				)
				( attribute "XY" "(-1300,1275)"
					( Origin gFrontEnd )
				)
				( attribute "CHIPS_PART_NAME" "CAP"
					( Origin gPackager )
				)
				( attribute "CDS_PART_NAME" "CAP_0402-0.22UF,16V,10%,X7R,A3A"
					( Origin gPackager )
				)
				( objectStatus "C6B20" )
				( pin "a"
					( attribute "PN" "1"
						( Origin gPackager )
					)
					( objectStatus "C6B20.1" )
				)
				( pin "b"
					( attribute "PN" "2"
						( Origin gPackager )
					)
					( objectStatus "C6B20.2" )
				)
			)
			( gate "@baseboard_fab2_lib.baseboard_fab2(sch_1):page105_i175"
				( attribute "CDS_LIB" "mstr_discrete"
					( Origin gPackager )
				)
				( attribute "CDS_LOCATION" "C6B17"
					( Origin gPackager )
				)
				( attribute "CDS_SEC" "1"
					( Origin gPackager )
				)
				( attribute "LOCATION" "C6B17"
					( Origin gFrontEnd )
				)
				( attribute "MATERIAL" "X7R"
					( Origin gFrontEnd )
				)
				( attribute "PACK_TYPE" "0402"
					( Origin gFrontEnd )
				)
				( attribute "PART_NUMBER" "A36096-155"
					( Origin gFrontEnd )
				)
				( attribute "PHYS_PAGE" "105"
					( Origin gFrontEnd )
				)
				( attribute "ROOM" "OCP_STEERING"
					( Origin gFrontEnd )
				)
				( attribute "ROT" "2"
					( Origin gFrontEnd )
				)
				( attribute "SEC" "1"
					( Origin gFrontEnd )
				)
				( attribute "SEC_TYPE" "0402"
					( Origin gFrontEnd )
				)
				( attribute "TOLERANCE" "10%"
					( Origin gFrontEnd )
				)
				( attribute "VALUE" "0.22UF"
					( Origin gFrontEnd )
				)
				( attribute "VER" "1"
					( Origin gFrontEnd )
				)
				( attribute "VOLTAGE" "16V"
					( Units "uVoltage" "V" 1.000000)
					( Origin gFrontEnd )
				)
				( attribute "XY" "(-1550,1975)"
					( Origin gFrontEnd )
				)
				( attribute "CHIPS_PART_NAME" "CAP"
					( Origin gPackager )
				)
				( attribute "CDS_PART_NAME" "CAP_0402-0.22UF,16V,10%,X7R,A3A"
					( Origin gPackager )
				)
				( objectStatus "C6B17" )
				( pin "a"
					( attribute "PN" "1"
						( Origin gPackager )
					)
					( objectStatus "C6B17.1" )
				)
				( pin "b"
					( attribute "PN" "2"
						( Origin gPackager )
					)
					( objectStatus "C6B17.2" )
				)
			)
			( gate "@baseboard_fab2_lib.baseboard_fab2(sch_1):page105_i180"
				( attribute "CDS_LIB" "mstr_discrete"
					( Origin gPackager )
				)
				( attribute "CDS_LOCATION" "C6B16"
					( Origin gPackager )
				)
				( attribute "CDS_SEC" "1"
					( Origin gPackager )
				)
				( attribute "LOCATION" "C6B16"
					( Origin gFrontEnd )
				)
				( attribute "MATERIAL" "X7R"
					( Origin gFrontEnd )
				)
				( attribute "PACK_TYPE" "0402"
					( Origin gFrontEnd )
				)
				( attribute "PART_NUMBER" "A36096-155"
					( Origin gFrontEnd )
				)
				( attribute "PHYS_PAGE" "105"
					( Origin gFrontEnd )
				)
				( attribute "ROOM" "OCP_STEERING"
					( Origin gFrontEnd )
				)
				( attribute "ROT" "2"
					( Origin gFrontEnd )
				)
				( attribute "SEC" "1"
					( Origin gFrontEnd )
				)
				( attribute "SEC_TYPE" "0402"
					( Origin gFrontEnd )
				)
				( attribute "TOLERANCE" "10%"
					( Origin gFrontEnd )
				)
				( attribute "VALUE" "0.22UF"
					( Origin gFrontEnd )
				)
				( attribute "VER" "1"
					( Origin gFrontEnd )
				)
				( attribute "VOLTAGE" "16V"
					( Units "uVoltage" "V" 1.000000)
					( Origin gFrontEnd )
				)
				( attribute "XY" "(-1700,1275)"
					( Origin gFrontEnd )
				)
				( attribute "CHIPS_PART_NAME" "CAP"
					( Origin gPackager )
				)
				( attribute "CDS_PART_NAME" "CAP_0402-0.22UF,16V,10%,X7R,A3A"
					( Origin gPackager )
				)
				( objectStatus "C6B16" )
				( pin "a"
					( attribute "PN" "1"
						( Origin gPackager )
					)
					( objectStatus "C6B16.1" )
				)
				( pin "b"
					( attribute "PN" "2"
						( Origin gPackager )
					)
					( objectStatus "C6B16.2" )
				)
			)
			( gate "@baseboard_fab2_lib.baseboard_fab2(sch_1):page105_i181"
				( attribute "CDS_LIB" "mstr_discrete"
					( Origin gPackager )
				)
				( attribute "CDS_LOCATION" "C6B14"
					( Origin gPackager )
				)
				( attribute "CDS_SEC" "1"
					( Origin gPackager )
				)
				( attribute "LOCATION" "C6B14"
					( Origin gFrontEnd )
				)
				( attribute "MATERIAL" "X7R"
					( Origin gFrontEnd )
				)
				( attribute "PACK_TYPE" "0402"
					( Origin gFrontEnd )
				)
				( attribute "PART_NUMBER" "A36096-155"
					( Origin gFrontEnd )
				)
				( attribute "PHYS_PAGE" "105"
					( Origin gFrontEnd )
				)
				( attribute "ROOM" "OCP_STEERING"
					( Origin gFrontEnd )
				)
				( attribute "ROT" "2"
					( Origin gFrontEnd )
				)
				( attribute "SEC" "1"
					( Origin gFrontEnd )
				)
				( attribute "SEC_TYPE" "0402"
					( Origin gFrontEnd )
				)
				( attribute "TOLERANCE" "10%"
					( Origin gFrontEnd )
				)
				( attribute "VALUE" "0.22UF"
					( Origin gFrontEnd )
				)
				( attribute "VER" "1"
					( Origin gFrontEnd )
				)
				( attribute "VOLTAGE" "16V"
					( Units "uVoltage" "V" 1.000000)
					( Origin gFrontEnd )
				)
				( attribute "XY" "(-1950,1975)"
					( Origin gFrontEnd )
				)
				( attribute "CHIPS_PART_NAME" "CAP"
					( Origin gPackager )
				)
				( attribute "CDS_PART_NAME" "CAP_0402-0.22UF,16V,10%,X7R,A3A"
					( Origin gPackager )
				)
				( objectStatus "C6B14" )
				( pin "a"
					( attribute "PN" "1"
						( Origin gPackager )
					)
					( objectStatus "C6B14.1" )
				)
				( pin "b"
					( attribute "PN" "2"
						( Origin gPackager )
					)
					( objectStatus "C6B14.2" )
				)
			)
			( gate "@baseboard_fab2_lib.baseboard_fab2(sch_1):page105_i185"
				( attribute "CDS_LIB" "mstr_discrete"
					( Origin gPackager )
				)
				( attribute "CDS_LOCATION" "C6B9"
					( Origin gPackager )
				)
				( attribute "CDS_SEC" "1"
					( Origin gPackager )
				)
				( attribute "LOCATION" "C6B9"
					( Origin gFrontEnd )
				)
				( attribute "MATERIAL" "X7R"
					( Origin gFrontEnd )
				)
				( attribute "PACK_TYPE" "0402"
					( Origin gFrontEnd )
				)
				( attribute "PART_NUMBER" "A36096-155"
					( Origin gFrontEnd )
				)
				( attribute "PHYS_PAGE" "105"
					( Origin gFrontEnd )
				)
				( attribute "ROOM" "OCP_STEERING"
					( Origin gFrontEnd )
				)
				( attribute "ROT" "2"
					( Origin gFrontEnd )
				)
				( attribute "SEC" "1"
					( Origin gFrontEnd )
				)
				( attribute "SEC_TYPE" "0402"
					( Origin gFrontEnd )
				)
				( attribute "TOLERANCE" "10%"
					( Origin gFrontEnd )
				)
				( attribute "VALUE" "0.22UF"
					( Origin gFrontEnd )
				)
				( attribute "VER" "1"
					( Origin gFrontEnd )
				)
				( attribute "VOLTAGE" "16V"
					( Units "uVoltage" "V" 1.000000)
					( Origin gFrontEnd )
				)
				( attribute "XY" "(-2350,1975)"
					( Origin gFrontEnd )
				)
				( attribute "CHIPS_PART_NAME" "CAP"
					( Origin gPackager )
				)
				( attribute "CDS_PART_NAME" "CAP_0402-0.22UF,16V,10%,X7R,A3A"
					( Origin gPackager )
				)
				( objectStatus "C6B9" )
				( pin "a"
					( attribute "PN" "1"
						( Origin gPackager )
					)
					( objectStatus "C6B9.1" )
				)
				( pin "b"
					( attribute "PN" "2"
						( Origin gPackager )
					)
					( objectStatus "C6B9.2" )
				)
			)
			( gate "@baseboard_fab2_lib.baseboard_fab2(sch_1):page105_i187"
				( attribute "CDS_LIB" "mstr_discrete"
					( Origin gPackager )
				)
				( attribute "CDS_LOCATION" "C6B12"
					( Origin gPackager )
				)
				( attribute "CDS_SEC" "1"
					( Origin gPackager )
				)
				( attribute "LOCATION" "C6B12"
					( Origin gFrontEnd )
				)
				( attribute "MATERIAL" "X7R"
					( Origin gFrontEnd )
				)
				( attribute "PACK_TYPE" "0402"
					( Origin gFrontEnd )
				)
				( attribute "PART_NUMBER" "A36096-155"
					( Origin gFrontEnd )
				)
				( attribute "PHYS_PAGE" "105"
					( Origin gFrontEnd )
				)
				( attribute "ROOM" "OCP_STEERING"
					( Origin gFrontEnd )
				)
				( attribute "ROT" "2"
					( Origin gFrontEnd )
				)
				( attribute "SEC" "1"
					( Origin gFrontEnd )
				)
				( attribute "SEC_TYPE" "0402"
					( Origin gFrontEnd )
				)
				( attribute "TOLERANCE" "10%"
					( Origin gFrontEnd )
				)
				( attribute "VALUE" "0.22UF"
					( Origin gFrontEnd )
				)
				( attribute "VER" "1"
					( Origin gFrontEnd )
				)
				( attribute "VOLTAGE" "16V"
					( Units "uVoltage" "V" 1.000000)
					( Origin gFrontEnd )
				)
				( attribute "XY" "(-2100,1275)"
					( Origin gFrontEnd )
				)
				( attribute "CHIPS_PART_NAME" "CAP"
					( Origin gPackager )
				)
				( attribute "CDS_PART_NAME" "CAP_0402-0.22UF,16V,10%,X7R,A3A"
					( Origin gPackager )
				)
				( objectStatus "C6B12" )
				( pin "a"
					( attribute "PN" "1"
						( Origin gPackager )
					)
					( objectStatus "C6B12.1" )
				)
				( pin "b"
					( attribute "PN" "2"
						( Origin gPackager )
					)
					( objectStatus "C6B12.2" )
				)
			)
			( gate "@baseboard_fab2_lib.baseboard_fab2(sch_1):page105_i189"
				( attribute "CDS_LIB" "mstr_discrete"
					( Origin gPackager )
				)
				( attribute "CDS_LOCATION" "C6B13"
					( Origin gPackager )
				)
				( attribute "CDS_SEC" "1"
					( Origin gPackager )
				)
				( attribute "LOCATION" "C6B13"
					( Origin gFrontEnd )
				)
				( attribute "MATERIAL" "X7R"
					( Origin gFrontEnd )
				)
				( attribute "PACK_TYPE" "0402"
					( Origin gFrontEnd )
				)
				( attribute "PART_NUMBER" "A36096-155"
					( Origin gFrontEnd )
				)
				( attribute "PHYS_PAGE" "105"
					( Origin gFrontEnd )
				)
				( attribute "ROOM" "OCP_STEERING"
					( Origin gFrontEnd )
				)
				( attribute "ROT" "2"
					( Origin gFrontEnd )
				)
				( attribute "SEC" "1"
					( Origin gFrontEnd )
				)
				( attribute "SEC_TYPE" "0402"
					( Origin gFrontEnd )
				)
				( attribute "TOLERANCE" "10%"
					( Origin gFrontEnd )
				)
				( attribute "VALUE" "0.22UF"
					( Origin gFrontEnd )
				)
				( attribute "VER" "1"
					( Origin gFrontEnd )
				)
				( attribute "VOLTAGE" "16V"
					( Units "uVoltage" "V" 1.000000)
					( Origin gFrontEnd )
				)
				( attribute "XY" "(-1900,975)"
					( Origin gFrontEnd )
				)
				( attribute "CHIPS_PART_NAME" "CAP"
					( Origin gPackager )
				)
				( attribute "CDS_PART_NAME" "CAP_0402-0.22UF,16V,10%,X7R,A3A"
					( Origin gPackager )
				)
				( objectStatus "C6B13" )
				( pin "a"
					( attribute "PN" "1"
						( Origin gPackager )
					)
					( objectStatus "C6B13.1" )
				)
				( pin "b"
					( attribute "PN" "2"
						( Origin gPackager )
					)
					( objectStatus "C6B13.2" )
				)
			)
			( gate "@baseboard_fab2_lib.baseboard_fab2(sch_1):page105_i193"
				( attribute "CDS_LIB" "mstr_discrete"
					( Origin gPackager )
				)
				( attribute "CDS_LOCATION" "C6B10"
					( Origin gPackager )
				)
				( attribute "CDS_SEC" "1"
					( Origin gPackager )
				)
				( attribute "LOCATION" "C6B10"
					( Origin gFrontEnd )
				)
				( attribute "MATERIAL" "X7R"
					( Origin gFrontEnd )
				)
				( attribute "PACK_TYPE" "0402"
					( Origin gFrontEnd )
				)
				( attribute "PART_NUMBER" "A36096-155"
					( Origin gFrontEnd )
				)
				( attribute "PHYS_PAGE" "105"
					( Origin gFrontEnd )
				)
				( attribute "ROOM" "OCP_STEERING"
					( Origin gFrontEnd )
				)
				( attribute "ROT" "2"
					( Origin gFrontEnd )
				)
				( attribute "SEC" "1"
					( Origin gFrontEnd )
				)
				( attribute "SEC_TYPE" "0402"
					( Origin gFrontEnd )
				)
				( attribute "TOLERANCE" "10%"
					( Origin gFrontEnd )
				)
				( attribute "VALUE" "0.22UF"
					( Origin gFrontEnd )
				)
				( attribute "VER" "1"
					( Origin gFrontEnd )
				)
				( attribute "VOLTAGE" "16V"
					( Units "uVoltage" "V" 1.000000)
					( Origin gFrontEnd )
				)
				( attribute "XY" "(-2300,975)"
					( Origin gFrontEnd )
				)
				( attribute "CHIPS_PART_NAME" "CAP"
					( Origin gPackager )
				)
				( attribute "CDS_PART_NAME" "CAP_0402-0.22UF,16V,10%,X7R,A3A"
					( Origin gPackager )
				)
				( objectStatus "C6B10" )
				( pin "a"
					( attribute "PN" "1"
						( Origin gPackager )
					)
					( objectStatus "C6B10.1" )
				)
				( pin "b"
					( attribute "PN" "2"
						( Origin gPackager )
					)
					( objectStatus "C6B10.2" )
				)
			)
			( gate "@baseboard_fab2_lib.baseboard_fab2(sch_1):page105_i196"
				( attribute "CDS_LIB" "mstr_discrete"
					( Origin gPackager )
				)
				( attribute "CDS_LOCATION" "C6B4"
					( Origin gPackager )
				)
				( attribute "CDS_SEC" "1"
					( Origin gPackager )
				)
				( attribute "LOCATION" "C6B4"
					( Origin gFrontEnd )
				)
				( attribute "MATERIAL" "X7R"
					( Origin gFrontEnd )
				)
				( attribute "PACK_TYPE" "0402"
					( Origin gFrontEnd )
				)
				( attribute "PART_NUMBER" "A36096-155"
					( Origin gFrontEnd )
				)
				( attribute "PHYS_PAGE" "105"
					( Origin gFrontEnd )
				)
				( attribute "ROOM" "OCP_STEERING"
					( Origin gFrontEnd )
				)
				( attribute "ROT" "2"
					( Origin gFrontEnd )
				)
				( attribute "SEC" "1"
					( Origin gFrontEnd )
				)
				( attribute "SEC_TYPE" "0402"
					( Origin gFrontEnd )
				)
				( attribute "TOLERANCE" "10%"
					( Origin gFrontEnd )
				)
				( attribute "VALUE" "0.22UF"
					( Origin gFrontEnd )
				)
				( attribute "VER" "1"
					( Origin gFrontEnd )
				)
				( attribute "VOLTAGE" "16V"
					( Units "uVoltage" "V" 1.000000)
					( Origin gFrontEnd )
				)
				( attribute "XY" "(-2750,1975)"
					( Origin gFrontEnd )
				)
				( attribute "CHIPS_PART_NAME" "CAP"
					( Origin gPackager )
				)
				( attribute "CDS_PART_NAME" "CAP_0402-0.22UF,16V,10%,X7R,A3A"
					( Origin gPackager )
				)
				( objectStatus "C6B4" )
				( pin "a"
					( attribute "PN" "1"
						( Origin gPackager )
					)
					( objectStatus "C6B4.1" )
				)
				( pin "b"
					( attribute "PN" "2"
						( Origin gPackager )
					)
					( objectStatus "C6B4.2" )
				)
			)
			( gate "@baseboard_fab2_lib.baseboard_fab2(sch_1):page105_i198"
				( attribute "CDS_LIB" "mstr_discrete"
					( Origin gPackager )
				)
				( attribute "CDS_LOCATION" "C6B8"
					( Origin gPackager )
				)
				( attribute "CDS_SEC" "1"
					( Origin gPackager )
				)
				( attribute "LOCATION" "C6B8"
					( Origin gFrontEnd )
				)
				( attribute "MATERIAL" "X7R"
					( Origin gFrontEnd )
				)
				( attribute "PACK_TYPE" "0402"
					( Origin gFrontEnd )
				)
				( attribute "PART_NUMBER" "A36096-155"
					( Origin gFrontEnd )
				)
				( attribute "PHYS_PAGE" "105"
					( Origin gFrontEnd )
				)
				( attribute "ROOM" "OCP_STEERING"
					( Origin gFrontEnd )
				)
				( attribute "ROT" "2"
					( Origin gFrontEnd )
				)
				( attribute "SEC" "1"
					( Origin gFrontEnd )
				)
				( attribute "SEC_TYPE" "0402"
					( Origin gFrontEnd )
				)
				( attribute "TOLERANCE" "10%"
					( Origin gFrontEnd )
				)
				( attribute "VALUE" "0.22UF"
					( Origin gFrontEnd )
				)
				( attribute "VER" "1"
					( Origin gFrontEnd )
				)
				( attribute "VOLTAGE" "16V"
					( Units "uVoltage" "V" 1.000000)
					( Origin gFrontEnd )
				)
				( attribute "XY" "(-2500,1275)"
					( Origin gFrontEnd )
				)
				( attribute "CHIPS_PART_NAME" "CAP"
					( Origin gPackager )
				)
				( attribute "CDS_PART_NAME" "CAP_0402-0.22UF,16V,10%,X7R,A3A"
					( Origin gPackager )
				)
				( objectStatus "C6B8" )
				( pin "a"
					( attribute "PN" "1"
						( Origin gPackager )
					)
					( objectStatus "C6B8.1" )
				)
				( pin "b"
					( attribute "PN" "2"
						( Origin gPackager )
					)
					( objectStatus "C6B8.2" )
				)
			)
			( gate "@baseboard_fab2_lib.baseboard_fab2(sch_1):page105_i201"
				( attribute "CDS_LIB" "mstr_discrete"
					( Origin gPackager )
				)
				( attribute "CDS_LOCATION" "C6B5"
					( Origin gPackager )
				)
				( attribute "CDS_SEC" "1"
					( Origin gPackager )
				)
				( attribute "LOCATION" "C6B5"
					( Origin gFrontEnd )
				)
				( attribute "MATERIAL" "X7R"
					( Origin gFrontEnd )
				)
				( attribute "PACK_TYPE" "0402"
					( Origin gFrontEnd )
				)
				( attribute "PART_NUMBER" "A36096-155"
					( Origin gFrontEnd )
				)
				( attribute "PHYS_PAGE" "105"
					( Origin gFrontEnd )
				)
				( attribute "ROOM" "OCP_STEERING"
					( Origin gFrontEnd )
				)
				( attribute "ROT" "2"
					( Origin gFrontEnd )
				)
				( attribute "SEC" "1"
					( Origin gFrontEnd )
				)
				( attribute "SEC_TYPE" "0402"
					( Origin gFrontEnd )
				)
				( attribute "TOLERANCE" "10%"
					( Origin gFrontEnd )
				)
				( attribute "VALUE" "0.22UF"
					( Origin gFrontEnd )
				)
				( attribute "VER" "1"
					( Origin gFrontEnd )
				)
				( attribute "VOLTAGE" "16V"
					( Units "uVoltage" "V" 1.000000)
					( Origin gFrontEnd )
				)
				( attribute "XY" "(-2700,975)"
					( Origin gFrontEnd )
				)
				( attribute "CHIPS_PART_NAME" "CAP"
					( Origin gPackager )
				)
				( attribute "CDS_PART_NAME" "CAP_0402-0.22UF,16V,10%,X7R,A3A"
					( Origin gPackager )
				)
				( objectStatus "C6B5" )
				( pin "a"
					( attribute "PN" "1"
						( Origin gPackager )
					)
					( objectStatus "C6B5.1" )
				)
				( pin "b"
					( attribute "PN" "2"
						( Origin gPackager )
					)
					( objectStatus "C6B5.2" )
				)
			)
			( gate "@baseboard_fab2_lib.baseboard_fab2(sch_1):page105_i205"
				( attribute "CDS_LIB" "mstr_discrete"
					( Origin gPackager )
				)
				( attribute "CDS_LOCATION" "C3M25"
					( Origin gPackager )
				)
				( attribute "CDS_SEC" "1"
					( Origin gPackager )
				)
				( attribute "LOCATION" "C3M25"
					( Origin gFrontEnd )
				)
				( attribute "MATERIAL" "X7R"
					( Origin gFrontEnd )
				)
				( attribute "PACK_TYPE" "0402"
					( Origin gFrontEnd )
				)
				( attribute "PART_NUMBER" "A36096-155"
					( Origin gFrontEnd )
				)
				( attribute "PHYS_PAGE" "105"
					( Origin gFrontEnd )
				)
				( attribute "ROOM" "OCP_STEERING"
					( Origin gFrontEnd )
				)
				( attribute "ROT" "2"
					( Origin gFrontEnd )
				)
				( attribute "SEC" "1"
					( Origin gPackager )
				)
				( attribute "TOLERANCE" "10%"
					( Origin gFrontEnd )
				)
				( attribute "VALUE" "0.22UF"
					( Origin gFrontEnd )
				)
				( attribute "VER" "1"
					( Origin gFrontEnd )
				)
				( attribute "VOLTAGE" "16V"
					( Units "uVoltage" "V" 1.000000)
					( Origin gFrontEnd )
				)
				( attribute "XY" "(1800,2025)"
					( Origin gFrontEnd )
				)
				( attribute "CHIPS_PART_NAME" "CAP"
					( Origin gPackager )
				)
				( attribute "CDS_PART_NAME" "CAP_0402-0.22UF,16V,10%,X7R,A3A"
					( Origin gPackager )
				)
				( objectStatus "C3M25" )
				( pin "a"
					( attribute "PN" "1"
						( Origin gPackager )
					)
					( objectStatus "C3M25.1" )
				)
				( pin "b"
					( attribute "PN" "2"
						( Origin gPackager )
					)
					( objectStatus "C3M25.2" )
				)
			)
			( gate "@baseboard_fab2_lib.baseboard_fab2(sch_1):page105_i206"
				( attribute "CDS_LIB" "mstr_discrete"
					( Origin gPackager )
				)
				( attribute "CDS_LOCATION" "C3M34"
					( Origin gPackager )
				)
				( attribute "CDS_SEC" "1"
					( Origin gPackager )
				)
				( attribute "LOCATION" "C3M34"
					( Origin gFrontEnd )
				)
				( attribute "MATERIAL" "X7R"
					( Origin gFrontEnd )
				)
				( attribute "PACK_TYPE" "0402"
					( Origin gFrontEnd )
				)
				( attribute "PART_NUMBER" "A36096-155"
					( Origin gFrontEnd )
				)
				( attribute "PHYS_PAGE" "105"
					( Origin gFrontEnd )
				)
				( attribute "ROOM" "OCP_STEERING"
					( Origin gFrontEnd )
				)
				( attribute "ROT" "2"
					( Origin gFrontEnd )
				)
				( attribute "SEC" "1"
					( Origin gPackager )
				)
				( attribute "TOLERANCE" "10%"
					( Origin gFrontEnd )
				)
				( attribute "VALUE" "0.22UF"
					( Origin gFrontEnd )
				)
				( attribute "VER" "1"
					( Origin gFrontEnd )
				)
				( attribute "VOLTAGE" "16V"
					( Units "uVoltage" "V" 1.000000)
					( Origin gFrontEnd )
				)
				( attribute "XY" "(2400,2325)"
					( Origin gFrontEnd )
				)
				( attribute "CHIPS_PART_NAME" "CAP"
					( Origin gPackager )
				)
				( attribute "CDS_PART_NAME" "CAP_0402-0.22UF,16V,10%,X7R,A3A"
					( Origin gPackager )
				)
				( objectStatus "C3M34" )
				( pin "a"
					( attribute "PN" "1"
						( Origin gPackager )
					)
					( objectStatus "C3M34.1" )
				)
				( pin "b"
					( attribute "PN" "2"
						( Origin gPackager )
					)
					( objectStatus "C3M34.2" )
				)
			)
			( gate "@baseboard_fab2_lib.baseboard_fab2(sch_1):page105_i212"
				( attribute "CDS_LIB" "mstr_discrete"
					( Origin gPackager )
				)
				( attribute "CDS_LOCATION" "C3M28"
					( Origin gPackager )
				)
				( attribute "CDS_SEC" "1"
					( Origin gPackager )
				)
				( attribute "LOCATION" "C3M28"
					( Origin gFrontEnd )
				)
				( attribute "MATERIAL" "X7R"
					( Origin gFrontEnd )
				)
				( attribute "PACK_TYPE" "0402"
					( Origin gFrontEnd )
				)
				( attribute "PART_NUMBER" "A36096-155"
					( Origin gFrontEnd )
				)
				( attribute "PHYS_PAGE" "105"
					( Origin gFrontEnd )
				)
				( attribute "ROOM" "OCP_STEERING"
					( Origin gFrontEnd )
				)
				( attribute "ROT" "2"
					( Origin gFrontEnd )
				)
				( attribute "SEC" "1"
					( Origin gPackager )
				)
				( attribute "TOLERANCE" "10%"
					( Origin gFrontEnd )
				)
				( attribute "VALUE" "0.22UF"
					( Origin gFrontEnd )
				)
				( attribute "VER" "1"
					( Origin gFrontEnd )
				)
				( attribute "VOLTAGE" "16V"
					( Units "uVoltage" "V" 1.000000)
					( Origin gFrontEnd )
				)
				( attribute "XY" "(2000,2325)"
					( Origin gFrontEnd )
				)
				( attribute "CHIPS_PART_NAME" "CAP"
					( Origin gPackager )
				)
				( attribute "CDS_PART_NAME" "CAP_0402-0.22UF,16V,10%,X7R,A3A"
					( Origin gPackager )
				)
				( objectStatus "C3M28" )
				( pin "a"
					( attribute "PN" "1"
						( Origin gPackager )
					)
					( objectStatus "C3M28.1" )
				)
				( pin "b"
					( attribute "PN" "2"
						( Origin gPackager )
					)
					( objectStatus "C3M28.2" )
				)
			)
			( gate "@baseboard_fab2_lib.baseboard_fab2(sch_1):page105_i217"
				( attribute "CDS_LIB" "mstr_discrete"
					( Origin gPackager )
				)
				( attribute "CDS_LOCATION" "C3M33"
					( Origin gPackager )
				)
				( attribute "CDS_SEC" "1"
					( Origin gPackager )
				)
				( attribute "LOCATION" "C3M33"
					( Origin gFrontEnd )
				)
				( attribute "MATERIAL" "X7R"
					( Origin gFrontEnd )
				)
				( attribute "PACK_TYPE" "0402"
					( Origin gFrontEnd )
				)
				( attribute "PART_NUMBER" "A36096-155"
					( Origin gFrontEnd )
				)
				( attribute "PHYS_PAGE" "105"
					( Origin gFrontEnd )
				)
				( attribute "ROOM" "OCP_STEERING"
					( Origin gFrontEnd )
				)
				( attribute "ROT" "2"
					( Origin gFrontEnd )
				)
				( attribute "SEC" "1"
					( Origin gPackager )
				)
				( attribute "TOLERANCE" "10%"
					( Origin gFrontEnd )
				)
				( attribute "VALUE" "0.22UF"
					( Origin gFrontEnd )
				)
				( attribute "VER" "1"
					( Origin gFrontEnd )
				)
				( attribute "VOLTAGE" "16V"
					( Units "uVoltage" "V" 1.000000)
					( Origin gFrontEnd )
				)
				( attribute "XY" "(2450,1325)"
					( Origin gFrontEnd )
				)
				( attribute "CHIPS_PART_NAME" "CAP"
					( Origin gPackager )
				)
				( attribute "CDS_PART_NAME" "CAP_0402-0.22UF,16V,10%,X7R,A3A"
					( Origin gPackager )
				)
				( objectStatus "C3M33" )
				( pin "a"
					( attribute "PN" "1"
						( Origin gPackager )
					)
					( objectStatus "C3M33.1" )
				)
				( pin "b"
					( attribute "PN" "2"
						( Origin gPackager )
					)
					( objectStatus "C3M33.2" )
				)
			)
			( gate "@baseboard_fab2_lib.baseboard_fab2(sch_1):page105_i218"
				( attribute "CDS_LIB" "mstr_discrete"
					( Origin gPackager )
				)
				( attribute "CDS_LOCATION" "C3M36"
					( Origin gPackager )
				)
				( attribute "CDS_SEC" "1"
					( Origin gPackager )
				)
				( attribute "LOCATION" "C3M36"
					( Origin gFrontEnd )
				)
				( attribute "MATERIAL" "X7R"
					( Origin gFrontEnd )
				)
				( attribute "PACK_TYPE" "0402"
					( Origin gFrontEnd )
				)
				( attribute "PART_NUMBER" "A36096-155"
					( Origin gFrontEnd )
				)
				( attribute "PHYS_PAGE" "105"
					( Origin gFrontEnd )
				)
				( attribute "ROOM" "OCP_STEERING"
					( Origin gFrontEnd )
				)
				( attribute "ROT" "2"
					( Origin gFrontEnd )
				)
				( attribute "SEC" "1"
					( Origin gPackager )
				)
				( attribute "TOLERANCE" "10%"
					( Origin gFrontEnd )
				)
				( attribute "VALUE" "0.22UF"
					( Origin gFrontEnd )
				)
				( attribute "VER" "1"
					( Origin gFrontEnd )
				)
				( attribute "VOLTAGE" "16V"
					( Units "uVoltage" "V" 1.000000)
					( Origin gFrontEnd )
				)
				( attribute "XY" "(2200,2025)"
					( Origin gFrontEnd )
				)
				( attribute "CHIPS_PART_NAME" "CAP"
					( Origin gPackager )
				)
				( attribute "CDS_PART_NAME" "CAP_0402-0.22UF,16V,10%,X7R,A3A"
					( Origin gPackager )
				)
				( objectStatus "C3M36" )
				( pin "a"
					( attribute "PN" "1"
						( Origin gPackager )
					)
					( objectStatus "C3M36.1" )
				)
				( pin "b"
					( attribute "PN" "2"
						( Origin gPackager )
					)
					( objectStatus "C3M36.2" )
				)
			)
			( gate "@baseboard_fab2_lib.baseboard_fab2(sch_1):page105_i223"
				( attribute "CDS_LIB" "mstr_discrete"
					( Origin gPackager )
				)
				( attribute "CDS_LOCATION" "C3M32"
					( Origin gPackager )
				)
				( attribute "CDS_SEC" "1"
					( Origin gPackager )
				)
				( attribute "LOCATION" "C3M32"
					( Origin gFrontEnd )
				)
				( attribute "MATERIAL" "X7R"
					( Origin gFrontEnd )
				)
				( attribute "PACK_TYPE" "0402"
					( Origin gFrontEnd )
				)
				( attribute "PART_NUMBER" "A36096-155"
					( Origin gFrontEnd )
				)
				( attribute "PHYS_PAGE" "105"
					( Origin gFrontEnd )
				)
				( attribute "ROOM" "OCP_STEERING"
					( Origin gFrontEnd )
				)
				( attribute "ROT" "2"
					( Origin gFrontEnd )
				)
				( attribute "SEC" "1"
					( Origin gPackager )
				)
				( attribute "TOLERANCE" "10%"
					( Origin gFrontEnd )
				)
				( attribute "VALUE" "0.22UF"
					( Origin gFrontEnd )
				)
				( attribute "VER" "1"
					( Origin gFrontEnd )
				)
				( attribute "VOLTAGE" "16V"
					( Units "uVoltage" "V" 1.000000)
					( Origin gFrontEnd )
				)
				( attribute "XY" "(2050,1325)"
					( Origin gFrontEnd )
				)
				( attribute "CHIPS_PART_NAME" "CAP"
					( Origin gPackager )
				)
				( attribute "CDS_PART_NAME" "CAP_0402-0.22UF,16V,10%,X7R,A3A"
					( Origin gPackager )
				)
				( objectStatus "C3M32" )
				( pin "a"
					( attribute "PN" "1"
						( Origin gPackager )
					)
					( objectStatus "C3M32.1" )
				)
				( pin "b"
					( attribute "PN" "2"
						( Origin gPackager )
					)
					( objectStatus "C3M32.2" )
				)
			)
			( gate "@baseboard_fab2_lib.baseboard_fab2(sch_1):page105_i225"
				( attribute "CDS_LIB" "mstr_discrete"
					( Origin gPackager )
				)
				( attribute "CDS_LOCATION" "C3M35"
					( Origin gPackager )
				)
				( attribute "CDS_SEC" "1"
					( Origin gPackager )
				)
				( attribute "LOCATION" "C3M35"
					( Origin gFrontEnd )
				)
				( attribute "MATERIAL" "X7R"
					( Origin gFrontEnd )
				)
				( attribute "PACK_TYPE" "0402"
					( Origin gFrontEnd )
				)
				( attribute "PART_NUMBER" "A36096-155"
					( Origin gFrontEnd )
				)
				( attribute "PHYS_PAGE" "105"
					( Origin gFrontEnd )
				)
				( attribute "ROOM" "OCP_STEERING"
					( Origin gFrontEnd )
				)
				( attribute "ROT" "2"
					( Origin gFrontEnd )
				)
				( attribute "SEC" "1"
					( Origin gPackager )
				)
				( attribute "TOLERANCE" "10%"
					( Origin gFrontEnd )
				)
				( attribute "VALUE" "0.22UF"
					( Origin gFrontEnd )
				)
				( attribute "VER" "1"
					( Origin gFrontEnd )
				)
				( attribute "VOLTAGE" "16V"
					( Units "uVoltage" "V" 1.000000)
					( Origin gFrontEnd )
				)
				( attribute "XY" "(2250,1025)"
					( Origin gFrontEnd )
				)
				( attribute "CHIPS_PART_NAME" "CAP"
					( Origin gPackager )
				)
				( attribute "CDS_PART_NAME" "CAP_0402-0.22UF,16V,10%,X7R,A3A"
					( Origin gPackager )
				)
				( objectStatus "C3M35" )
				( pin "a"
					( attribute "PN" "1"
						( Origin gPackager )
					)
					( objectStatus "C3M35.1" )
				)
				( pin "b"
					( attribute "PN" "2"
						( Origin gPackager )
					)
					( objectStatus "C3M35.2" )
				)
			)
			( gate "@baseboard_fab2_lib.baseboard_fab2(sch_1):page105_i229"
				( attribute "CDS_LIB" "mstr_discrete"
					( Origin gPackager )
				)
				( attribute "CDS_LOCATION" "C3M26"
					( Origin gPackager )
				)
				( attribute "CDS_SEC" "1"
					( Origin gPackager )
				)
				( attribute "LOCATION" "C3M26"
					( Origin gFrontEnd )
				)
				( attribute "MATERIAL" "X7R"
					( Origin gFrontEnd )
				)
				( attribute "PACK_TYPE" "0402"
					( Origin gFrontEnd )
				)
				( attribute "PART_NUMBER" "A36096-155"
					( Origin gFrontEnd )
				)
				( attribute "PHYS_PAGE" "105"
					( Origin gFrontEnd )
				)
				( attribute "ROOM" "OCP_STEERING"
					( Origin gFrontEnd )
				)
				( attribute "ROT" "2"
					( Origin gFrontEnd )
				)
				( attribute "SEC" "1"
					( Origin gPackager )
				)
				( attribute "TOLERANCE" "10%"
					( Origin gFrontEnd )
				)
				( attribute "VALUE" "0.22UF"
					( Origin gFrontEnd )
				)
				( attribute "VER" "1"
					( Origin gFrontEnd )
				)
				( attribute "VOLTAGE" "16V"
					( Units "uVoltage" "V" 1.000000)
					( Origin gFrontEnd )
				)
				( attribute "XY" "(1850,1025)"
					( Origin gFrontEnd )
				)
				( attribute "CHIPS_PART_NAME" "CAP"
					( Origin gPackager )
				)
				( attribute "CDS_PART_NAME" "CAP_0402-0.22UF,16V,10%,X7R,A3A"
					( Origin gPackager )
				)
				( objectStatus "C3M26" )
				( pin "a"
					( attribute "PN" "1"
						( Origin gPackager )
					)
					( objectStatus "C3M26.1" )
				)
				( pin "b"
					( attribute "PN" "2"
						( Origin gPackager )
					)
					( objectStatus "C3M26.2" )
				)
			)
			( gate "@baseboard_fab2_lib.baseboard_fab2(sch_1):page105_i232"
				( attribute "CDS_LIB" "mstr_discrete"
					( Origin gPackager )
				)
				( attribute "CDS_LOCATION" "C3M3"
					( Origin gPackager )
				)
				( attribute "CDS_SEC" "1"
					( Origin gPackager )
				)
				( attribute "LOCATION" "C3M3"
					( Origin gFrontEnd )
				)
				( attribute "MATERIAL" "X7R"
					( Origin gFrontEnd )
				)
				( attribute "PACK_TYPE" "0402"
					( Origin gFrontEnd )
				)
				( attribute "PART_NUMBER" "A36096-155"
					( Origin gFrontEnd )
				)
				( attribute "PHYS_PAGE" "105"
					( Origin gFrontEnd )
				)
				( attribute "ROOM" "OCP_STEERING"
					( Origin gFrontEnd )
				)
				( attribute "ROT" "2"
					( Origin gFrontEnd )
				)
				( attribute "SEC" "1"
					( Origin gPackager )
				)
				( attribute "TOLERANCE" "10%"
					( Origin gFrontEnd )
				)
				( attribute "VALUE" "0.22UF"
					( Origin gFrontEnd )
				)
				( attribute "VER" "1"
					( Origin gFrontEnd )
				)
				( attribute "VOLTAGE" "16V"
					( Units "uVoltage" "V" 1.000000)
					( Origin gFrontEnd )
				)
				( attribute "XY" "(1600,2325)"
					( Origin gFrontEnd )
				)
				( attribute "CHIPS_PART_NAME" "CAP"
					( Origin gPackager )
				)
				( attribute "CDS_PART_NAME" "CAP_0402-0.22UF,16V,10%,X7R,A3A"
					( Origin gPackager )
				)
				( objectStatus "C3M3" )
				( pin "a"
					( attribute "PN" "1"
						( Origin gPackager )
					)
					( objectStatus "C3M3.1" )
				)
				( pin "b"
					( attribute "PN" "2"
						( Origin gPackager )
					)
					( objectStatus "C3M3.2" )
				)
			)
			( gate "@baseboard_fab2_lib.baseboard_fab2(sch_1):page105_i234"
				( attribute "CDS_LIB" "mstr_discrete"
					( Origin gPackager )
				)
				( attribute "CDS_LOCATION" "C3M11"
					( Origin gPackager )
				)
				( attribute "CDS_SEC" "1"
					( Origin gPackager )
				)
				( attribute "LOCATION" "C3M11"
					( Origin gFrontEnd )
				)
				( attribute "MATERIAL" "X7R"
					( Origin gFrontEnd )
				)
				( attribute "PACK_TYPE" "0402"
					( Origin gFrontEnd )
				)
				( attribute "PART_NUMBER" "A36096-155"
					( Origin gFrontEnd )
				)
				( attribute "PHYS_PAGE" "105"
					( Origin gFrontEnd )
				)
				( attribute "ROOM" "OCP_STEERING"
					( Origin gFrontEnd )
				)
				( attribute "ROT" "2"
					( Origin gFrontEnd )
				)
				( attribute "SEC" "1"
					( Origin gPackager )
				)
				( attribute "TOLERANCE" "10%"
					( Origin gFrontEnd )
				)
				( attribute "VALUE" "0.22UF"
					( Origin gFrontEnd )
				)
				( attribute "VER" "1"
					( Origin gFrontEnd )
				)
				( attribute "VOLTAGE" "16V"
					( Units "uVoltage" "V" 1.000000)
					( Origin gFrontEnd )
				)
				( attribute "XY" "(1200,2325)"
					( Origin gFrontEnd )
				)
				( attribute "CHIPS_PART_NAME" "CAP"
					( Origin gPackager )
				)
				( attribute "CDS_PART_NAME" "CAP_0402-0.22UF,16V,10%,X7R,A3A"
					( Origin gPackager )
				)
				( objectStatus "C3M11" )
				( pin "a"
					( attribute "PN" "1"
						( Origin gPackager )
					)
					( objectStatus "C3M11.1" )
				)
				( pin "b"
					( attribute "PN" "2"
						( Origin gPackager )
					)
					( objectStatus "C3M11.2" )
				)
			)
			( gate "@baseboard_fab2_lib.baseboard_fab2(sch_1):page105_i239"
				( attribute "CDS_LIB" "mstr_discrete"
					( Origin gPackager )
				)
				( attribute "CDS_LOCATION" "C3M13"
					( Origin gPackager )
				)
				( attribute "CDS_SEC" "1"
					( Origin gPackager )
				)
				( attribute "LOCATION" "C3M13"
					( Origin gFrontEnd )
				)
				( attribute "MATERIAL" "X7R"
					( Origin gFrontEnd )
				)
				( attribute "PACK_TYPE" "0402"
					( Origin gFrontEnd )
				)
				( attribute "PART_NUMBER" "A36096-155"
					( Origin gFrontEnd )
				)
				( attribute "PHYS_PAGE" "105"
					( Origin gFrontEnd )
				)
				( attribute "ROOM" "OCP_STEERING"
					( Origin gFrontEnd )
				)
				( attribute "ROT" "2"
					( Origin gFrontEnd )
				)
				( attribute "SEC" "1"
					( Origin gPackager )
				)
				( attribute "TOLERANCE" "10%"
					( Origin gFrontEnd )
				)
				( attribute "VALUE" "0.22UF"
					( Origin gFrontEnd )
				)
				( attribute "VER" "1"
					( Origin gFrontEnd )
				)
				( attribute "VOLTAGE" "16V"
					( Units "uVoltage" "V" 1.000000)
					( Origin gFrontEnd )
				)
				( attribute "XY" "(1400,2025)"
					( Origin gFrontEnd )
				)
				( attribute "CHIPS_PART_NAME" "CAP"
					( Origin gPackager )
				)
				( attribute "CDS_PART_NAME" "CAP_0402-0.22UF,16V,10%,X7R,A3A"
					( Origin gPackager )
				)
				( objectStatus "C3M13" )
				( pin "a"
					( attribute "PN" "1"
						( Origin gPackager )
					)
					( objectStatus "C3M13.1" )
				)
				( pin "b"
					( attribute "PN" "2"
						( Origin gPackager )
					)
					( objectStatus "C3M13.2" )
				)
			)
			( gate "@baseboard_fab2_lib.baseboard_fab2(sch_1):page105_i244"
				( attribute "CDS_LIB" "mstr_discrete"
					( Origin gPackager )
				)
				( attribute "CDS_LOCATION" "C3M4"
					( Origin gPackager )
				)
				( attribute "CDS_SEC" "1"
					( Origin gPackager )
				)
				( attribute "LOCATION" "C3M4"
					( Origin gFrontEnd )
				)
				( attribute "MATERIAL" "X7R"
					( Origin gFrontEnd )
				)
				( attribute "PACK_TYPE" "0402"
					( Origin gFrontEnd )
				)
				( attribute "PART_NUMBER" "A36096-155"
					( Origin gFrontEnd )
				)
				( attribute "PHYS_PAGE" "105"
					( Origin gFrontEnd )
				)
				( attribute "ROOM" "OCP_STEERING"
					( Origin gFrontEnd )
				)
				( attribute "ROT" "2"
					( Origin gFrontEnd )
				)
				( attribute "SEC" "1"
					( Origin gPackager )
				)
				( attribute "TOLERANCE" "10%"
					( Origin gFrontEnd )
				)
				( attribute "VALUE" "0.22UF"
					( Origin gFrontEnd )
				)
				( attribute "VER" "1"
					( Origin gFrontEnd )
				)
				( attribute "VOLTAGE" "16V"
					( Units "uVoltage" "V" 1.000000)
					( Origin gFrontEnd )
				)
				( attribute "XY" "(1650,1325)"
					( Origin gFrontEnd )
				)
				( attribute "CHIPS_PART_NAME" "CAP"
					( Origin gPackager )
				)
				( attribute "CDS_PART_NAME" "CAP_0402-0.22UF,16V,10%,X7R,A3A"
					( Origin gPackager )
				)
				( objectStatus "C3M4" )
				( pin "a"
					( attribute "PN" "1"
						( Origin gPackager )
					)
					( objectStatus "C3M4.1" )
				)
				( pin "b"
					( attribute "PN" "2"
						( Origin gPackager )
					)
					( objectStatus "C3M4.2" )
				)
			)
			( gate "@baseboard_fab2_lib.baseboard_fab2(sch_1):page105_i246"
				( attribute "CDS_LIB" "mstr_discrete"
					( Origin gPackager )
				)
				( attribute "CDS_LOCATION" "C3M12"
					( Origin gPackager )
				)
				( attribute "CDS_SEC" "1"
					( Origin gPackager )
				)
				( attribute "LOCATION" "C3M12"
					( Origin gFrontEnd )
				)
				( attribute "MATERIAL" "X7R"
					( Origin gFrontEnd )
				)
				( attribute "PACK_TYPE" "0402"
					( Origin gFrontEnd )
				)
				( attribute "PART_NUMBER" "A36096-155"
					( Origin gFrontEnd )
				)
				( attribute "PHYS_PAGE" "105"
					( Origin gFrontEnd )
				)
				( attribute "ROOM" "OCP_STEERING"
					( Origin gFrontEnd )
				)
				( attribute "ROT" "2"
					( Origin gFrontEnd )
				)
				( attribute "SEC" "1"
					( Origin gPackager )
				)
				( attribute "TOLERANCE" "10%"
					( Origin gFrontEnd )
				)
				( attribute "VALUE" "0.22UF"
					( Origin gFrontEnd )
				)
				( attribute "VER" "1"
					( Origin gFrontEnd )
				)
				( attribute "VOLTAGE" "16V"
					( Units "uVoltage" "V" 1.000000)
					( Origin gFrontEnd )
				)
				( attribute "XY" "(1250,1325)"
					( Origin gFrontEnd )
				)
				( attribute "CHIPS_PART_NAME" "CAP"
					( Origin gPackager )
				)
				( attribute "CDS_PART_NAME" "CAP_0402-0.22UF,16V,10%,X7R,A3A"
					( Origin gPackager )
				)
				( objectStatus "C3M12" )
				( pin "a"
					( attribute "PN" "1"
						( Origin gPackager )
					)
					( objectStatus "C3M12.1" )
				)
				( pin "b"
					( attribute "PN" "2"
						( Origin gPackager )
					)
					( objectStatus "C3M12.2" )
				)
			)
			( gate "@baseboard_fab2_lib.baseboard_fab2(sch_1):page105_i247"
				( attribute "CDS_LIB" "mstr_discrete"
					( Origin gPackager )
				)
				( attribute "CDS_LOCATION" "C3M2"
					( Origin gPackager )
				)
				( attribute "CDS_SEC" "1"
					( Origin gPackager )
				)
				( attribute "LOCATION" "C3M2"
					( Origin gFrontEnd )
				)
				( attribute "MATERIAL" "X7R"
					( Origin gFrontEnd )
				)
				( attribute "PACK_TYPE" "0402"
					( Origin gFrontEnd )
				)
				( attribute "PART_NUMBER" "A36096-155"
					( Origin gFrontEnd )
				)
				( attribute "PHYS_PAGE" "105"
					( Origin gFrontEnd )
				)
				( attribute "ROOM" "OCP_STEERING"
					( Origin gFrontEnd )
				)
				( attribute "ROT" "2"
					( Origin gFrontEnd )
				)
				( attribute "SEC" "1"
					( Origin gPackager )
				)
				( attribute "TOLERANCE" "10%"
					( Origin gFrontEnd )
				)
				( attribute "VALUE" "0.22UF"
					( Origin gFrontEnd )
				)
				( attribute "VER" "1"
					( Origin gFrontEnd )
				)
				( attribute "VOLTAGE" "16V"
					( Units "uVoltage" "V" 1.000000)
					( Origin gFrontEnd )
				)
				( attribute "XY" "(1000,2025)"
					( Origin gFrontEnd )
				)
				( attribute "CHIPS_PART_NAME" "CAP"
					( Origin gPackager )
				)
				( attribute "CDS_PART_NAME" "CAP_0402-0.22UF,16V,10%,X7R,A3A"
					( Origin gPackager )
				)
				( objectStatus "C3M2" )
				( pin "a"
					( attribute "PN" "1"
						( Origin gPackager )
					)
					( objectStatus "C3M2.1" )
				)
				( pin "b"
					( attribute "PN" "2"
						( Origin gPackager )
					)
					( objectStatus "C3M2.2" )
				)
			)
			( gate "@baseboard_fab2_lib.baseboard_fab2(sch_1):page105_i253"
				( attribute "CDS_LIB" "mstr_discrete"
					( Origin gPackager )
				)
				( attribute "CDS_LOCATION" "C3M14"
					( Origin gPackager )
				)
				( attribute "CDS_SEC" "1"
					( Origin gPackager )
				)
				( attribute "LOCATION" "C3M14"
					( Origin gFrontEnd )
				)
				( attribute "MATERIAL" "X7R"
					( Origin gFrontEnd )
				)
				( attribute "PACK_TYPE" "0402"
					( Origin gFrontEnd )
				)
				( attribute "PART_NUMBER" "A36096-155"
					( Origin gFrontEnd )
				)
				( attribute "PHYS_PAGE" "105"
					( Origin gFrontEnd )
				)
				( attribute "ROOM" "OCP_STEERING"
					( Origin gFrontEnd )
				)
				( attribute "ROT" "2"
					( Origin gFrontEnd )
				)
				( attribute "SEC" "1"
					( Origin gPackager )
				)
				( attribute "TOLERANCE" "10%"
					( Origin gFrontEnd )
				)
				( attribute "VALUE" "0.22UF"
					( Origin gFrontEnd )
				)
				( attribute "VER" "1"
					( Origin gFrontEnd )
				)
				( attribute "VOLTAGE" "16V"
					( Units "uVoltage" "V" 1.000000)
					( Origin gFrontEnd )
				)
				( attribute "XY" "(1450,1025)"
					( Origin gFrontEnd )
				)
				( attribute "CHIPS_PART_NAME" "CAP"
					( Origin gPackager )
				)
				( attribute "CDS_PART_NAME" "CAP_0402-0.22UF,16V,10%,X7R,A3A"
					( Origin gPackager )
				)
				( objectStatus "C3M14" )
				( pin "a"
					( attribute "PN" "1"
						( Origin gPackager )
					)
					( objectStatus "C3M14.1" )
				)
				( pin "b"
					( attribute "PN" "2"
						( Origin gPackager )
					)
					( objectStatus "C3M14.2" )
				)
			)
			( gate "@baseboard_fab2_lib.baseboard_fab2(sch_1):page105_i255"
				( attribute "CDS_LIB" "mstr_discrete"
					( Origin gPackager )
				)
				( attribute "CDS_LOCATION" "C3M1"
					( Origin gPackager )
				)
				( attribute "CDS_SEC" "1"
					( Origin gPackager )
				)
				( attribute "LOCATION" "C3M1"
					( Origin gFrontEnd )
				)
				( attribute "MATERIAL" "X7R"
					( Origin gFrontEnd )
				)
				( attribute "PACK_TYPE" "0402"
					( Origin gFrontEnd )
				)
				( attribute "PART_NUMBER" "A36096-155"
					( Origin gFrontEnd )
				)
				( attribute "PHYS_PAGE" "105"
					( Origin gFrontEnd )
				)
				( attribute "ROOM" "OCP_STEERING"
					( Origin gFrontEnd )
				)
				( attribute "ROT" "2"
					( Origin gFrontEnd )
				)
				( attribute "SEC" "1"
					( Origin gPackager )
				)
				( attribute "TOLERANCE" "10%"
					( Origin gFrontEnd )
				)
				( attribute "VALUE" "0.22UF"
					( Origin gFrontEnd )
				)
				( attribute "VER" "1"
					( Origin gFrontEnd )
				)
				( attribute "VOLTAGE" "16V"
					( Units "uVoltage" "V" 1.000000)
					( Origin gFrontEnd )
				)
				( attribute "XY" "(1050,1025)"
					( Origin gFrontEnd )
				)
				( attribute "CHIPS_PART_NAME" "CAP"
					( Origin gPackager )
				)
				( attribute "CDS_PART_NAME" "CAP_0402-0.22UF,16V,10%,X7R,A3A"
					( Origin gPackager )
				)
				( objectStatus "C3M1" )
				( pin "a"
					( attribute "PN" "1"
						( Origin gPackager )
					)
					( objectStatus "C3M1.1" )
				)
				( pin "b"
					( attribute "PN" "2"
						( Origin gPackager )
					)
					( objectStatus "C3M1.2" )
				)
			)
			( gate "@baseboard_fab2_lib.baseboard_fab2(sch_1):page106_i10"
				( attribute "BOM_COST" "IO_SLOT"
					( Origin gFrontEnd )
				)
				( attribute "CDS_LIB" "mstr_discrete"
					( Origin gPackager )
				)
				( attribute "CDS_LOCATION" "C1R2"
					( Origin gPackager )
				)
				( attribute "CDS_SEC" "1"
					( Origin gPackager )
				)
				( attribute "LOCATION" "C1R2"
					( Origin gFrontEnd )
				)
				( attribute "MATERIAL" "X7R"
					( Origin gFrontEnd )
				)
				( attribute "PACK_TYPE" "0402"
					( Origin gFrontEnd )
				)
				( attribute "PART_NUMBER" "A36096-155"
					( Origin gFrontEnd )
				)
				( attribute "PHYS_PAGE" "106"
					( Origin gFrontEnd )
				)
				( attribute "ROOM" "PCIE_STEERING"
					( Origin gFrontEnd )
				)
				( attribute "ROT" "2"
					( Origin gFrontEnd )
				)
				( attribute "SEC" "1"
					( Origin gPackager )
				)
				( attribute "TOLERANCE" "10%"
					( Origin gFrontEnd )
				)
				( attribute "VALUE" "0.22UF"
					( Origin gFrontEnd )
				)
				( attribute "VER" "1"
					( Origin gFrontEnd )
				)
				( attribute "VOLTAGE" "16V"
					( Units "uVoltage" "V" 1.000000)
					( Origin gFrontEnd )
				)
				( attribute "XY" "(-4100,2650)"
					( Origin gFrontEnd )
				)
				( attribute "CHIPS_PART_NAME" "CAP"
					( Origin gPackager )
				)
				( attribute "CDS_PART_NAME" "CAP_0402-0.22UF,16V,10%,X7R,A3A"
					( Origin gPackager )
				)
				( objectStatus "C1R2" )
				( pin "a"
					( attribute "PN" "1"
						( Origin gPackager )
					)
					( objectStatus "C1R2.1" )
				)
				( pin "b"
					( attribute "PN" "2"
						( Origin gPackager )
					)
					( objectStatus "C1R2.2" )
				)
			)
			( gate "@baseboard_fab2_lib.baseboard_fab2(sch_1):page106_i26"
				( attribute "BOM_COST" "IO_SLOT"
					( Origin gFrontEnd )
				)
				( attribute "CDS_LIB" "mstr_discrete"
					( Origin gPackager )
				)
				( attribute "CDS_LOCATION" "C1R4"
					( Origin gPackager )
				)
				( attribute "CDS_SEC" "1"
					( Origin gPackager )
				)
				( attribute "LOCATION" "C1R4"
					( Origin gFrontEnd )
				)
				( attribute "MATERIAL" "X7R"
					( Origin gFrontEnd )
				)
				( attribute "PACK_TYPE" "0402"
					( Origin gFrontEnd )
				)
				( attribute "PART_NUMBER" "A36096-155"
					( Origin gFrontEnd )
				)
				( attribute "PHYS_PAGE" "106"
					( Origin gFrontEnd )
				)
				( attribute "ROOM" "PCIE_STEERING"
					( Origin gFrontEnd )
				)
				( attribute "ROT" "2"
					( Origin gFrontEnd )
				)
				( attribute "SEC" "1"
					( Origin gPackager )
				)
				( attribute "TOLERANCE" "10%"
					( Origin gFrontEnd )
				)
				( attribute "VALUE" "0.22UF"
					( Origin gFrontEnd )
				)
				( attribute "VER" "1"
					( Origin gFrontEnd )
				)
				( attribute "VOLTAGE" "16V"
					( Units "uVoltage" "V" 1.000000)
					( Origin gFrontEnd )
				)
				( attribute "XY" "(-4300,2350)"
					( Origin gFrontEnd )
				)
				( attribute "CHIPS_PART_NAME" "CAP"
					( Origin gPackager )
				)
				( attribute "CDS_PART_NAME" "CAP_0402-0.22UF,16V,10%,X7R,A3A"
					( Origin gPackager )
				)
				( objectStatus "C1R4" )
				( pin "a"
					( attribute "PN" "1"
						( Origin gPackager )
					)
					( objectStatus "C1R4.1" )
				)
				( pin "b"
					( attribute "PN" "2"
						( Origin gPackager )
					)
					( objectStatus "C1R4.2" )
				)
			)
			( gate "@baseboard_fab2_lib.baseboard_fab2(sch_1):page106_i29"
				( attribute "BOM_COST" "IO_SLOT"
					( Origin gFrontEnd )
				)
				( attribute "CDS_LIB" "mstr_discrete"
					( Origin gPackager )
				)
				( attribute "CDS_LOCATION" "C1R1"
					( Origin gPackager )
				)
				( attribute "CDS_SEC" "1"
					( Origin gPackager )
				)
				( attribute "LOCATION" "C1R1"
					( Origin gFrontEnd )
				)
				( attribute "MATERIAL" "X7R"
					( Origin gFrontEnd )
				)
				( attribute "PACK_TYPE" "0402"
					( Origin gFrontEnd )
				)
				( attribute "PART_NUMBER" "A36096-155"
					( Origin gFrontEnd )
				)
				( attribute "PHYS_PAGE" "106"
					( Origin gFrontEnd )
				)
				( attribute "ROOM" "PCIE_STEERING"
					( Origin gFrontEnd )
				)
				( attribute "ROT" "2"
					( Origin gFrontEnd )
				)
				( attribute "SEC" "1"
					( Origin gPackager )
				)
				( attribute "TOLERANCE" "10%"
					( Origin gFrontEnd )
				)
				( attribute "VALUE" "0.22UF"
					( Origin gFrontEnd )
				)
				( attribute "VER" "1"
					( Origin gFrontEnd )
				)
				( attribute "VOLTAGE" "16V"
					( Units "uVoltage" "V" 1.000000)
					( Origin gFrontEnd )
				)
				( attribute "XY" "(-4075,1650)"
					( Origin gFrontEnd )
				)
				( attribute "CHIPS_PART_NAME" "CAP"
					( Origin gPackager )
				)
				( attribute "CDS_PART_NAME" "CAP_0402-0.22UF,16V,10%,X7R,A3A"
					( Origin gPackager )
				)
				( objectStatus "C1R1" )
				( pin "a"
					( attribute "PN" "1"
						( Origin gPackager )
					)
					( objectStatus "C1R1.1" )
				)
				( pin "b"
					( attribute "PN" "2"
						( Origin gPackager )
					)
					( objectStatus "C1R1.2" )
				)
			)
			( gate "@baseboard_fab2_lib.baseboard_fab2(sch_1):page106_i37"
				( attribute "BOM_COST" "IO_SLOT"
					( Origin gFrontEnd )
				)
				( attribute "CDS_LIB" "mstr_discrete"
					( Origin gPackager )
				)
				( attribute "CDS_LOCATION" "C1R3"
					( Origin gPackager )
				)
				( attribute "CDS_SEC" "1"
					( Origin gPackager )
				)
				( attribute "LOCATION" "C1R3"
					( Origin gFrontEnd )
				)
				( attribute "MATERIAL" "X7R"
					( Origin gFrontEnd )
				)
				( attribute "PACK_TYPE" "0402"
					( Origin gFrontEnd )
				)
				( attribute "PART_NUMBER" "A36096-155"
					( Origin gFrontEnd )
				)
				( attribute "PHYS_PAGE" "106"
					( Origin gFrontEnd )
				)
				( attribute "ROOM" "PCIE_STEERING"
					( Origin gFrontEnd )
				)
				( attribute "ROT" "2"
					( Origin gFrontEnd )
				)
				( attribute "SEC" "1"
					( Origin gPackager )
				)
				( attribute "TOLERANCE" "10%"
					( Origin gFrontEnd )
				)
				( attribute "VALUE" "0.22UF"
					( Origin gFrontEnd )
				)
				( attribute "VER" "1"
					( Origin gFrontEnd )
				)
				( attribute "VOLTAGE" "16V"
					( Units "uVoltage" "V" 1.000000)
					( Origin gFrontEnd )
				)
				( attribute "XY" "(-4275,1350)"
					( Origin gFrontEnd )
				)
				( attribute "CHIPS_PART_NAME" "CAP"
					( Origin gPackager )
				)
				( attribute "CDS_PART_NAME" "CAP_0402-0.22UF,16V,10%,X7R,A3A"
					( Origin gPackager )
				)
				( objectStatus "C1R3" )
				( pin "a"
					( attribute "PN" "1"
						( Origin gPackager )
					)
					( objectStatus "C1R3.1" )
				)
				( pin "b"
					( attribute "PN" "2"
						( Origin gPackager )
					)
					( objectStatus "C1R3.2" )
				)
			)
			( gate "@baseboard_fab2_lib.baseboard_fab2(sch_1):page106_i40"
				( attribute "CDS_LIB" "mstr_discrete"
					( Origin gPackager )
				)
				( attribute "CDS_LOCATION" "C1R6"
					( Origin gPackager )
				)
				( attribute "CDS_SEC" "1"
					( Origin gPackager )
				)
				( attribute "LOCATION" "C1R6"
					( Origin gFrontEnd )
				)
				( attribute "MATERIAL" "X7R"
					( Origin gFrontEnd )
				)
				( attribute "PACK_TYPE" "0402"
					( Origin gFrontEnd )
				)
				( attribute "PART_NUMBER" "A36096-155"
					( Origin gFrontEnd )
				)
				( attribute "PHYS_PAGE" "106"
					( Origin gFrontEnd )
				)
				( attribute "ROOM" "PCIE_STEERING"
					( Origin gFrontEnd )
				)
				( attribute "ROT" "2"
					( Origin gFrontEnd )
				)
				( attribute "SEC" "1"
					( Origin gPackager )
				)
				( attribute "TOLERANCE" "10%"
					( Origin gFrontEnd )
				)
				( attribute "VALUE" "0.22UF"
					( Origin gFrontEnd )
				)
				( attribute "VER" "1"
					( Origin gFrontEnd )
				)
				( attribute "VOLTAGE" "16V"
					( Units "uVoltage" "V" 1.000000)
					( Origin gFrontEnd )
				)
				( attribute "XY" "(-4500,2650)"
					( Origin gFrontEnd )
				)
				( attribute "CHIPS_PART_NAME" "CAP"
					( Origin gPackager )
				)
				( attribute "CDS_PART_NAME" "CAP_0402-0.22UF,16V,10%,X7R,A3A"
					( Origin gPackager )
				)
				( objectStatus "C1R6" )
				( pin "a"
					( attribute "PN" "1"
						( Origin gPackager )
					)
					( objectStatus "C1R6.1" )
				)
				( pin "b"
					( attribute "PN" "2"
						( Origin gPackager )
					)
					( objectStatus "C1R6.2" )
				)
			)
			( gate "@baseboard_fab2_lib.baseboard_fab2(sch_1):page106_i55"
				( attribute "CDS_LIB" "mstr_discrete"
					( Origin gPackager )
				)
				( attribute "CDS_LOCATION" "C1R8"
					( Origin gPackager )
				)
				( attribute "CDS_SEC" "1"
					( Origin gPackager )
				)
				( attribute "LOCATION" "C1R8"
					( Origin gFrontEnd )
				)
				( attribute "MATERIAL" "X7R"
					( Origin gFrontEnd )
				)
				( attribute "PACK_TYPE" "0402"
					( Origin gFrontEnd )
				)
				( attribute "PART_NUMBER" "A36096-155"
					( Origin gFrontEnd )
				)
				( attribute "PHYS_PAGE" "106"
					( Origin gFrontEnd )
				)
				( attribute "ROOM" "PCIE_STEERING"
					( Origin gFrontEnd )
				)
				( attribute "ROT" "2"
					( Origin gFrontEnd )
				)
				( attribute "SEC" "1"
					( Origin gPackager )
				)
				( attribute "TOLERANCE" "10%"
					( Origin gFrontEnd )
				)
				( attribute "VALUE" "0.22UF"
					( Origin gFrontEnd )
				)
				( attribute "VER" "1"
					( Origin gFrontEnd )
				)
				( attribute "VOLTAGE" "16V"
					( Units "uVoltage" "V" 1.000000)
					( Origin gFrontEnd )
				)
				( attribute "XY" "(-4700,2350)"
					( Origin gFrontEnd )
				)
				( attribute "CHIPS_PART_NAME" "CAP"
					( Origin gPackager )
				)
				( attribute "CDS_PART_NAME" "CAP_0402-0.22UF,16V,10%,X7R,A3A"
					( Origin gPackager )
				)
				( objectStatus "C1R8" )
				( pin "a"
					( attribute "PN" "1"
						( Origin gPackager )
					)
					( objectStatus "C1R8.1" )
				)
				( pin "b"
					( attribute "PN" "2"
						( Origin gPackager )
					)
					( objectStatus "C1R8.2" )
				)
			)
			( gate "@baseboard_fab2_lib.baseboard_fab2(sch_1):page106_i59"
				( attribute "BOM_COST" "IO_SLOT"
					( Origin gFrontEnd )
				)
				( attribute "CDS_LIB" "mstr_discrete"
					( Origin gPackager )
				)
				( attribute "CDS_LOCATION" "C1R5"
					( Origin gPackager )
				)
				( attribute "CDS_SEC" "1"
					( Origin gPackager )
				)
				( attribute "LOCATION" "C1R5"
					( Origin gFrontEnd )
				)
				( attribute "MATERIAL" "X7R"
					( Origin gFrontEnd )
				)
				( attribute "PACK_TYPE" "0402"
					( Origin gFrontEnd )
				)
				( attribute "PART_NUMBER" "A36096-155"
					( Origin gFrontEnd )
				)
				( attribute "PHYS_PAGE" "106"
					( Origin gFrontEnd )
				)
				( attribute "ROOM" "PCIE_STEERING"
					( Origin gFrontEnd )
				)
				( attribute "ROT" "2"
					( Origin gFrontEnd )
				)
				( attribute "SEC" "1"
					( Origin gPackager )
				)
				( attribute "TOLERANCE" "10%"
					( Origin gFrontEnd )
				)
				( attribute "VALUE" "0.22UF"
					( Origin gFrontEnd )
				)
				( attribute "VER" "1"
					( Origin gFrontEnd )
				)
				( attribute "VOLTAGE" "16V"
					( Units "uVoltage" "V" 1.000000)
					( Origin gFrontEnd )
				)
				( attribute "XY" "(-4475,1650)"
					( Origin gFrontEnd )
				)
				( attribute "CHIPS_PART_NAME" "CAP"
					( Origin gPackager )
				)
				( attribute "CDS_PART_NAME" "CAP_0402-0.22UF,16V,10%,X7R,A3A"
					( Origin gPackager )
				)
				( objectStatus "C1R5" )
				( pin "a"
					( attribute "PN" "1"
						( Origin gPackager )
					)
					( objectStatus "C1R5.1" )
				)
				( pin "b"
					( attribute "PN" "2"
						( Origin gPackager )
					)
					( objectStatus "C1R5.2" )
				)
			)
			( gate "@baseboard_fab2_lib.baseboard_fab2(sch_1):page106_i70"
				( attribute "BOM_COST" "IO_SLOT"
					( Origin gFrontEnd )
				)
				( attribute "CDS_LIB" "mstr_discrete"
					( Origin gPackager )
				)
				( attribute "CDS_LOCATION" "C1R7"
					( Origin gPackager )
				)
				( attribute "CDS_SEC" "1"
					( Origin gPackager )
				)
				( attribute "LOCATION" "C1R7"
					( Origin gFrontEnd )
				)
				( attribute "MATERIAL" "X7R"
					( Origin gFrontEnd )
				)
				( attribute "PACK_TYPE" "0402"
					( Origin gFrontEnd )
				)
				( attribute "PART_NUMBER" "A36096-155"
					( Origin gFrontEnd )
				)
				( attribute "PHYS_PAGE" "106"
					( Origin gFrontEnd )
				)
				( attribute "ROOM" "PCIE_STEERING"
					( Origin gFrontEnd )
				)
				( attribute "ROT" "2"
					( Origin gFrontEnd )
				)
				( attribute "SEC" "1"
					( Origin gPackager )
				)
				( attribute "TOLERANCE" "10%"
					( Origin gFrontEnd )
				)
				( attribute "VALUE" "0.22UF"
					( Origin gFrontEnd )
				)
				( attribute "VER" "1"
					( Origin gFrontEnd )
				)
				( attribute "VOLTAGE" "16V"
					( Units "uVoltage" "V" 1.000000)
					( Origin gFrontEnd )
				)
				( attribute "XY" "(-4675,1350)"
					( Origin gFrontEnd )
				)
				( attribute "CHIPS_PART_NAME" "CAP"
					( Origin gPackager )
				)
				( attribute "CDS_PART_NAME" "CAP_0402-0.22UF,16V,10%,X7R,A3A"
					( Origin gPackager )
				)
				( objectStatus "C1R7" )
				( pin "a"
					( attribute "PN" "1"
						( Origin gPackager )
					)
					( objectStatus "C1R7.1" )
				)
				( pin "b"
					( attribute "PN" "2"
						( Origin gPackager )
					)
					( objectStatus "C1R7.2" )
				)
			)
			( gate "@baseboard_fab2_lib.baseboard_fab2(sch_1):page106_i76"
				( attribute "BOM_COST" "IO_SLOT"
					( Origin gFrontEnd )
				)
				( attribute "CDS_LIB" "mstr_discrete"
					( Origin gPackager )
				)
				( attribute "CDS_LOCATION" "C2M14"
					( Origin gPackager )
				)
				( attribute "CDS_SEC" "1"
					( Origin gPackager )
				)
				( attribute "LOCATION" "C2M14"
					( Origin gFrontEnd )
				)
				( attribute "MATERIAL" "X7R"
					( Origin gFrontEnd )
				)
				( attribute "PACK_TYPE" "0402"
					( Origin gFrontEnd )
				)
				( attribute "PART_NUMBER" "A36096-155"
					( Origin gFrontEnd )
				)
				( attribute "PHYS_PAGE" "106"
					( Origin gFrontEnd )
				)
				( attribute "ROOM" "PCIE_STEERING"
					( Origin gFrontEnd )
				)
				( attribute "ROT" "2"
					( Origin gFrontEnd )
				)
				( attribute "SEC" "1"
					( Origin gPackager )
				)
				( attribute "TOLERANCE" "10%"
					( Origin gFrontEnd )
				)
				( attribute "VALUE" "0.22UF"
					( Origin gFrontEnd )
				)
				( attribute "VER" "1"
					( Origin gFrontEnd )
				)
				( attribute "VOLTAGE" "16V"
					( Units "uVoltage" "V" 1.000000)
					( Origin gFrontEnd )
				)
				( attribute "XY" "(-5700,2650)"
					( Origin gFrontEnd )
				)
				( attribute "CHIPS_PART_NAME" "CAP"
					( Origin gPackager )
				)
				( attribute "CDS_PART_NAME" "CAP_0402-0.22UF,16V,10%,X7R,A3A"
					( Origin gPackager )
				)
				( objectStatus "C2M14" )
				( pin "a"
					( attribute "PN" "1"
						( Origin gPackager )
					)
					( objectStatus "C2M14.1" )
				)
				( pin "b"
					( attribute "PN" "2"
						( Origin gPackager )
					)
					( objectStatus "C2M14.2" )
				)
			)
			( gate "@baseboard_fab2_lib.baseboard_fab2(sch_1):page106_i78"
				( attribute "BOM_COST" "IO_SLOT"
					( Origin gFrontEnd )
				)
				( attribute "CDS_LIB" "mstr_discrete"
					( Origin gPackager )
				)
				( attribute "CDS_LOCATION" "C1M18"
					( Origin gPackager )
				)
				( attribute "CDS_SEC" "1"
					( Origin gPackager )
				)
				( attribute "LOCATION" "C1M18"
					( Origin gFrontEnd )
				)
				( attribute "MATERIAL" "X7R"
					( Origin gFrontEnd )
				)
				( attribute "PACK_TYPE" "0402"
					( Origin gFrontEnd )
				)
				( attribute "PART_NUMBER" "A36096-155"
					( Origin gFrontEnd )
				)
				( attribute "PHYS_PAGE" "106"
					( Origin gFrontEnd )
				)
				( attribute "ROOM" "PCIE_STEERING"
					( Origin gFrontEnd )
				)
				( attribute "ROT" "2"
					( Origin gFrontEnd )
				)
				( attribute "SEC" "1"
					( Origin gPackager )
				)
				( attribute "TOLERANCE" "10%"
					( Origin gFrontEnd )
				)
				( attribute "VALUE" "0.22UF"
					( Origin gFrontEnd )
				)
				( attribute "VER" "1"
					( Origin gFrontEnd )
				)
				( attribute "VOLTAGE" "16V"
					( Units "uVoltage" "V" 1.000000)
					( Origin gFrontEnd )
				)
				( attribute "XY" "(-5900,2350)"
					( Origin gFrontEnd )
				)
				( attribute "CHIPS_PART_NAME" "CAP"
					( Origin gPackager )
				)
				( attribute "CDS_PART_NAME" "CAP_0402-0.22UF,16V,10%,X7R,A3A"
					( Origin gPackager )
				)
				( objectStatus "C1M18" )
				( pin "a"
					( attribute "PN" "1"
						( Origin gPackager )
					)
					( objectStatus "C1M18.1" )
				)
				( pin "b"
					( attribute "PN" "2"
						( Origin gPackager )
					)
					( objectStatus "C1M18.2" )
				)
			)
			( gate "@baseboard_fab2_lib.baseboard_fab2(sch_1):page106_i82"
				( attribute "BOM_COST" "IO_SLOT"
					( Origin gFrontEnd )
				)
				( attribute "CDS_LIB" "mstr_discrete"
					( Origin gPackager )
				)
				( attribute "CDS_LOCATION" "C1M16"
					( Origin gPackager )
				)
				( attribute "CDS_SEC" "1"
					( Origin gPackager )
				)
				( attribute "LOCATION" "C1M16"
					( Origin gFrontEnd )
				)
				( attribute "MATERIAL" "X7R"
					( Origin gFrontEnd )
				)
				( attribute "PACK_TYPE" "0402"
					( Origin gFrontEnd )
				)
				( attribute "PART_NUMBER" "A36096-155"
					( Origin gFrontEnd )
				)
				( attribute "PHYS_PAGE" "106"
					( Origin gFrontEnd )
				)
				( attribute "ROOM" "PCIE_STEERING"
					( Origin gFrontEnd )
				)
				( attribute "ROT" "2"
					( Origin gFrontEnd )
				)
				( attribute "SEC" "1"
					( Origin gPackager )
				)
				( attribute "TOLERANCE" "10%"
					( Origin gFrontEnd )
				)
				( attribute "VALUE" "0.22UF"
					( Origin gFrontEnd )
				)
				( attribute "VER" "1"
					( Origin gFrontEnd )
				)
				( attribute "VOLTAGE" "16V"
					( Units "uVoltage" "V" 1.000000)
					( Origin gFrontEnd )
				)
				( attribute "XY" "(-6100,2650)"
					( Origin gFrontEnd )
				)
				( attribute "CHIPS_PART_NAME" "CAP"
					( Origin gPackager )
				)
				( attribute "CDS_PART_NAME" "CAP_0402-0.22UF,16V,10%,X7R,A3A"
					( Origin gPackager )
				)
				( objectStatus "C1M16" )
				( pin "a"
					( attribute "PN" "1"
						( Origin gPackager )
					)
					( objectStatus "C1M16.1" )
				)
				( pin "b"
					( attribute "PN" "2"
						( Origin gPackager )
					)
					( objectStatus "C1M16.2" )
				)
			)
			( gate "@baseboard_fab2_lib.baseboard_fab2(sch_1):page106_i85"
				( attribute "BOM_COST" "IO_SLOT"
					( Origin gFrontEnd )
				)
				( attribute "CDS_LIB" "mstr_discrete"
					( Origin gPackager )
				)
				( attribute "CDS_LOCATION" "C1M14"
					( Origin gPackager )
				)
				( attribute "CDS_SEC" "1"
					( Origin gPackager )
				)
				( attribute "LOCATION" "C1M14"
					( Origin gFrontEnd )
				)
				( attribute "MATERIAL" "X7R"
					( Origin gFrontEnd )
				)
				( attribute "PACK_TYPE" "0402"
					( Origin gFrontEnd )
				)
				( attribute "PART_NUMBER" "A36096-155"
					( Origin gFrontEnd )
				)
				( attribute "PHYS_PAGE" "106"
					( Origin gFrontEnd )
				)
				( attribute "ROOM" "PCIE_STEERING"
					( Origin gFrontEnd )
				)
				( attribute "ROT" "2"
					( Origin gFrontEnd )
				)
				( attribute "SEC" "1"
					( Origin gPackager )
				)
				( attribute "TOLERANCE" "10%"
					( Origin gFrontEnd )
				)
				( attribute "VALUE" "0.22UF"
					( Origin gFrontEnd )
				)
				( attribute "VER" "1"
					( Origin gFrontEnd )
				)
				( attribute "VOLTAGE" "16V"
					( Units "uVoltage" "V" 1.000000)
					( Origin gFrontEnd )
				)
				( attribute "XY" "(-6300,2350)"
					( Origin gFrontEnd )
				)
				( attribute "CHIPS_PART_NAME" "CAP"
					( Origin gPackager )
				)
				( attribute "CDS_PART_NAME" "CAP_0402-0.22UF,16V,10%,X7R,A3A"
					( Origin gPackager )
				)
				( objectStatus "C1M14" )
				( pin "a"
					( attribute "PN" "1"
						( Origin gPackager )
					)
					( objectStatus "C1M14.1" )
				)
				( pin "b"
					( attribute "PN" "2"
						( Origin gPackager )
					)
					( objectStatus "C1M14.2" )
				)
			)
			( gate "@baseboard_fab2_lib.baseboard_fab2(sch_1):page106_i86"
				( attribute "BOM_COST" "IO_SLOT"
					( Origin gFrontEnd )
				)
				( attribute "CDS_LIB" "mstr_discrete"
					( Origin gPackager )
				)
				( attribute "CDS_LOCATION" "C2M15"
					( Origin gPackager )
				)
				( attribute "CDS_SEC" "1"
					( Origin gPackager )
				)
				( attribute "LOCATION" "C2M15"
					( Origin gFrontEnd )
				)
				( attribute "MATERIAL" "X7R"
					( Origin gFrontEnd )
				)
				( attribute "PACK_TYPE" "0402"
					( Origin gFrontEnd )
				)
				( attribute "PART_NUMBER" "A36096-155"
					( Origin gFrontEnd )
				)
				( attribute "PHYS_PAGE" "106"
					( Origin gFrontEnd )
				)
				( attribute "ROOM" "PCIE_STEERING"
					( Origin gFrontEnd )
				)
				( attribute "ROT" "2"
					( Origin gFrontEnd )
				)
				( attribute "SEC" "1"
					( Origin gPackager )
				)
				( attribute "TOLERANCE" "10%"
					( Origin gFrontEnd )
				)
				( attribute "VALUE" "0.22UF"
					( Origin gFrontEnd )
				)
				( attribute "VER" "1"
					( Origin gFrontEnd )
				)
				( attribute "VOLTAGE" "16V"
					( Units "uVoltage" "V" 1.000000)
					( Origin gFrontEnd )
				)
				( attribute "XY" "(-5650,1650)"
					( Origin gFrontEnd )
				)
				( attribute "CHIPS_PART_NAME" "CAP"
					( Origin gPackager )
				)
				( attribute "CDS_PART_NAME" "CAP_0402-0.22UF,16V,10%,X7R,A3A"
					( Origin gPackager )
				)
				( objectStatus "C2M15" )
				( pin "a"
					( attribute "PN" "1"
						( Origin gPackager )
					)
					( objectStatus "C2M15.1" )
				)
				( pin "b"
					( attribute "PN" "2"
						( Origin gPackager )
					)
					( objectStatus "C2M15.2" )
				)
			)
			( gate "@baseboard_fab2_lib.baseboard_fab2(sch_1):page106_i90"
				( attribute "BOM_COST" "IO_SLOT"
					( Origin gFrontEnd )
				)
				( attribute "CDS_LIB" "mstr_discrete"
					( Origin gPackager )
				)
				( attribute "CDS_LOCATION" "C1M19"
					( Origin gPackager )
				)
				( attribute "CDS_SEC" "1"
					( Origin gPackager )
				)
				( attribute "LOCATION" "C1M19"
					( Origin gFrontEnd )
				)
				( attribute "MATERIAL" "X7R"
					( Origin gFrontEnd )
				)
				( attribute "PACK_TYPE" "0402"
					( Origin gFrontEnd )
				)
				( attribute "PART_NUMBER" "A36096-155"
					( Origin gFrontEnd )
				)
				( attribute "PHYS_PAGE" "106"
					( Origin gFrontEnd )
				)
				( attribute "ROOM" "PCIE_STEERING"
					( Origin gFrontEnd )
				)
				( attribute "ROT" "2"
					( Origin gFrontEnd )
				)
				( attribute "SEC" "1"
					( Origin gPackager )
				)
				( attribute "TOLERANCE" "10%"
					( Origin gFrontEnd )
				)
				( attribute "VALUE" "0.22UF"
					( Origin gFrontEnd )
				)
				( attribute "VER" "1"
					( Origin gFrontEnd )
				)
				( attribute "VOLTAGE" "16V"
					( Units "uVoltage" "V" 1.000000)
					( Origin gFrontEnd )
				)
				( attribute "XY" "(-5850,1350)"
					( Origin gFrontEnd )
				)
				( attribute "CHIPS_PART_NAME" "CAP"
					( Origin gPackager )
				)
				( attribute "CDS_PART_NAME" "CAP_0402-0.22UF,16V,10%,X7R,A3A"
					( Origin gPackager )
				)
				( objectStatus "C1M19" )
				( pin "a"
					( attribute "PN" "1"
						( Origin gPackager )
					)
					( objectStatus "C1M19.1" )
				)
				( pin "b"
					( attribute "PN" "2"
						( Origin gPackager )
					)
					( objectStatus "C1M19.2" )
				)
			)
			( gate "@baseboard_fab2_lib.baseboard_fab2(sch_1):page106_i92"
				( attribute "BOM_COST" "IO_SLOT"
					( Origin gFrontEnd )
				)
				( attribute "CDS_LIB" "mstr_discrete"
					( Origin gPackager )
				)
				( attribute "CDS_LOCATION" "C1M17"
					( Origin gPackager )
				)
				( attribute "CDS_SEC" "1"
					( Origin gPackager )
				)
				( attribute "LOCATION" "C1M17"
					( Origin gFrontEnd )
				)
				( attribute "MATERIAL" "X7R"
					( Origin gFrontEnd )
				)
				( attribute "PACK_TYPE" "0402"
					( Origin gFrontEnd )
				)
				( attribute "PART_NUMBER" "A36096-155"
					( Origin gFrontEnd )
				)
				( attribute "PHYS_PAGE" "106"
					( Origin gFrontEnd )
				)
				( attribute "ROOM" "PCIE_STEERING"
					( Origin gFrontEnd )
				)
				( attribute "ROT" "2"
					( Origin gFrontEnd )
				)
				( attribute "SEC" "1"
					( Origin gPackager )
				)
				( attribute "TOLERANCE" "10%"
					( Origin gFrontEnd )
				)
				( attribute "VALUE" "0.22UF"
					( Origin gFrontEnd )
				)
				( attribute "VER" "1"
					( Origin gFrontEnd )
				)
				( attribute "VOLTAGE" "16V"
					( Units "uVoltage" "V" 1.000000)
					( Origin gFrontEnd )
				)
				( attribute "XY" "(-6050,1650)"
					( Origin gFrontEnd )
				)
				( attribute "CHIPS_PART_NAME" "CAP"
					( Origin gPackager )
				)
				( attribute "CDS_PART_NAME" "CAP_0402-0.22UF,16V,10%,X7R,A3A"
					( Origin gPackager )
				)
				( objectStatus "C1M17" )
				( pin "a"
					( attribute "PN" "1"
						( Origin gPackager )
					)
					( objectStatus "C1M17.1" )
				)
				( pin "b"
					( attribute "PN" "2"
						( Origin gPackager )
					)
					( objectStatus "C1M17.2" )
				)
			)
			( gate "@baseboard_fab2_lib.baseboard_fab2(sch_1):page106_i95"
				( attribute "BOM_COST" "IO_SLOT"
					( Origin gFrontEnd )
				)
				( attribute "CDS_LIB" "mstr_discrete"
					( Origin gPackager )
				)
				( attribute "CDS_LOCATION" "C1M15"
					( Origin gPackager )
				)
				( attribute "CDS_SEC" "1"
					( Origin gPackager )
				)
				( attribute "LOCATION" "C1M15"
					( Origin gFrontEnd )
				)
				( attribute "MATERIAL" "X7R"
					( Origin gFrontEnd )
				)
				( attribute "PACK_TYPE" "0402"
					( Origin gFrontEnd )
				)
				( attribute "PART_NUMBER" "A36096-155"
					( Origin gFrontEnd )
				)
				( attribute "PHYS_PAGE" "106"
					( Origin gFrontEnd )
				)
				( attribute "ROOM" "PCIE_STEERING"
					( Origin gFrontEnd )
				)
				( attribute "ROT" "2"
					( Origin gFrontEnd )
				)
				( attribute "SEC" "1"
					( Origin gPackager )
				)
				( attribute "TOLERANCE" "10%"
					( Origin gFrontEnd )
				)
				( attribute "VALUE" "0.22UF"
					( Origin gFrontEnd )
				)
				( attribute "VER" "1"
					( Origin gFrontEnd )
				)
				( attribute "VOLTAGE" "16V"
					( Units "uVoltage" "V" 1.000000)
					( Origin gFrontEnd )
				)
				( attribute "XY" "(-6250,1350)"
					( Origin gFrontEnd )
				)
				( attribute "CHIPS_PART_NAME" "CAP"
					( Origin gPackager )
				)
				( attribute "CDS_PART_NAME" "CAP_0402-0.22UF,16V,10%,X7R,A3A"
					( Origin gPackager )
				)
				( objectStatus "C1M15" )
				( pin "a"
					( attribute "PN" "1"
						( Origin gPackager )
					)
					( objectStatus "C1M15.1" )
				)
				( pin "b"
					( attribute "PN" "2"
						( Origin gPackager )
					)
					( objectStatus "C1M15.2" )
				)
			)
			( gate "@baseboard_fab2_lib.baseboard_fab2(sch_1):page106_i100"
				( attribute "BOM_COST" "IO_SLOT"
					( Origin gFrontEnd )
				)
				( attribute "CDS_LIB" "mstr_discrete"
					( Origin gPackager )
				)
				( attribute "CDS_LOCATION" "C1M12"
					( Origin gPackager )
				)
				( attribute "CDS_SEC" "1"
					( Origin gPackager )
				)
				( attribute "LOCATION" "C1M12"
					( Origin gFrontEnd )
				)
				( attribute "MATERIAL" "X7R"
					( Origin gFrontEnd )
				)
				( attribute "PACK_TYPE" "0402"
					( Origin gFrontEnd )
				)
				( attribute "PART_NUMBER" "A36096-155"
					( Origin gFrontEnd )
				)
				( attribute "PHYS_PAGE" "106"
					( Origin gFrontEnd )
				)
				( attribute "ROOM" "PCIE_STEERING"
					( Origin gFrontEnd )
				)
				( attribute "ROT" "2"
					( Origin gFrontEnd )
				)
				( attribute "SEC" "1"
					( Origin gPackager )
				)
				( attribute "TOLERANCE" "10%"
					( Origin gFrontEnd )
				)
				( attribute "VALUE" "0.22UF"
					( Origin gFrontEnd )
				)
				( attribute "VER" "1"
					( Origin gFrontEnd )
				)
				( attribute "VOLTAGE" "16V"
					( Units "uVoltage" "V" 1.000000)
					( Origin gFrontEnd )
				)
				( attribute "XY" "(-6500,2650)"
					( Origin gFrontEnd )
				)
				( attribute "CHIPS_PART_NAME" "CAP"
					( Origin gPackager )
				)
				( attribute "CDS_PART_NAME" "CAP_0402-0.22UF,16V,10%,X7R,A3A"
					( Origin gPackager )
				)
				( objectStatus "C1M12" )
				( pin "a"
					( attribute "PN" "1"
						( Origin gPackager )
					)
					( objectStatus "C1M12.1" )
				)
				( pin "b"
					( attribute "PN" "2"
						( Origin gPackager )
					)
					( objectStatus "C1M12.2" )
				)
			)
			( gate "@baseboard_fab2_lib.baseboard_fab2(sch_1):page106_i102"
				( attribute "BOM_COST" "IO_SLOT"
					( Origin gFrontEnd )
				)
				( attribute "CDS_LIB" "mstr_discrete"
					( Origin gPackager )
				)
				( attribute "CDS_LOCATION" "C1M10"
					( Origin gPackager )
				)
				( attribute "CDS_SEC" "1"
					( Origin gPackager )
				)
				( attribute "LOCATION" "C1M10"
					( Origin gFrontEnd )
				)
				( attribute "MATERIAL" "X7R"
					( Origin gFrontEnd )
				)
				( attribute "PACK_TYPE" "0402"
					( Origin gFrontEnd )
				)
				( attribute "PART_NUMBER" "A36096-155"
					( Origin gFrontEnd )
				)
				( attribute "PHYS_PAGE" "106"
					( Origin gFrontEnd )
				)
				( attribute "ROOM" "PCIE_STEERING"
					( Origin gFrontEnd )
				)
				( attribute "ROT" "2"
					( Origin gFrontEnd )
				)
				( attribute "SEC" "1"
					( Origin gPackager )
				)
				( attribute "TOLERANCE" "10%"
					( Origin gFrontEnd )
				)
				( attribute "VALUE" "0.22UF"
					( Origin gFrontEnd )
				)
				( attribute "VER" "1"
					( Origin gFrontEnd )
				)
				( attribute "VOLTAGE" "16V"
					( Units "uVoltage" "V" 1.000000)
					( Origin gFrontEnd )
				)
				( attribute "XY" "(-6700,2350)"
					( Origin gFrontEnd )
				)
				( attribute "CHIPS_PART_NAME" "CAP"
					( Origin gPackager )
				)
				( attribute "CDS_PART_NAME" "CAP_0402-0.22UF,16V,10%,X7R,A3A"
					( Origin gPackager )
				)
				( objectStatus "C1M10" )
				( pin "a"
					( attribute "PN" "1"
						( Origin gPackager )
					)
					( objectStatus "C1M10.1" )
				)
				( pin "b"
					( attribute "PN" "2"
						( Origin gPackager )
					)
					( objectStatus "C1M10.2" )
				)
			)
			( gate "@baseboard_fab2_lib.baseboard_fab2(sch_1):page106_i105"
				( attribute "CDS_LIB" "mstr_discrete"
					( Origin gPackager )
				)
				( attribute "CDS_LOCATION" "C1M8"
					( Origin gPackager )
				)
				( attribute "CDS_SEC" "1"
					( Origin gPackager )
				)
				( attribute "LOCATION" "C1M8"
					( Origin gFrontEnd )
				)
				( attribute "MATERIAL" "X7R"
					( Origin gFrontEnd )
				)
				( attribute "PACK_TYPE" "0402"
					( Origin gFrontEnd )
				)
				( attribute "PART_NUMBER" "A36096-155"
					( Origin gFrontEnd )
				)
				( attribute "PHYS_PAGE" "106"
					( Origin gFrontEnd )
				)
				( attribute "ROOM" "PCIE_STEERING"
					( Origin gFrontEnd )
				)
				( attribute "ROT" "2"
					( Origin gFrontEnd )
				)
				( attribute "SEC" "1"
					( Origin gPackager )
				)
				( attribute "TOLERANCE" "10%"
					( Origin gFrontEnd )
				)
				( attribute "VALUE" "0.22UF"
					( Origin gFrontEnd )
				)
				( attribute "VER" "1"
					( Origin gFrontEnd )
				)
				( attribute "VOLTAGE" "16V"
					( Units "uVoltage" "V" 1.000000)
					( Origin gFrontEnd )
				)
				( attribute "XY" "(-6900,2650)"
					( Origin gFrontEnd )
				)
				( attribute "CHIPS_PART_NAME" "CAP"
					( Origin gPackager )
				)
				( attribute "CDS_PART_NAME" "CAP_0402-0.22UF,16V,10%,X7R,A3A"
					( Origin gPackager )
				)
				( objectStatus "C1M8" )
				( pin "a"
					( attribute "PN" "1"
						( Origin gPackager )
					)
					( objectStatus "C1M8.1" )
				)
				( pin "b"
					( attribute "PN" "2"
						( Origin gPackager )
					)
					( objectStatus "C1M8.2" )
				)
			)
			( gate "@baseboard_fab2_lib.baseboard_fab2(sch_1):page106_i109"
				( attribute "CDS_LIB" "mstr_discrete"
					( Origin gPackager )
				)
				( attribute "CDS_LOCATION" "C1M6"
					( Origin gPackager )
				)
				( attribute "CDS_SEC" "1"
					( Origin gPackager )
				)
				( attribute "LOCATION" "C1M6"
					( Origin gFrontEnd )
				)
				( attribute "MATERIAL" "X7R"
					( Origin gFrontEnd )
				)
				( attribute "PACK_TYPE" "0402"
					( Origin gFrontEnd )
				)
				( attribute "PART_NUMBER" "A36096-155"
					( Origin gFrontEnd )
				)
				( attribute "PHYS_PAGE" "106"
					( Origin gFrontEnd )
				)
				( attribute "ROOM" "PCIE_STEERING"
					( Origin gFrontEnd )
				)
				( attribute "ROT" "2"
					( Origin gFrontEnd )
				)
				( attribute "SEC" "1"
					( Origin gPackager )
				)
				( attribute "TOLERANCE" "10%"
					( Origin gFrontEnd )
				)
				( attribute "VALUE" "0.22UF"
					( Origin gFrontEnd )
				)
				( attribute "VER" "1"
					( Origin gFrontEnd )
				)
				( attribute "VOLTAGE" "16V"
					( Units "uVoltage" "V" 1.000000)
					( Origin gFrontEnd )
				)
				( attribute "XY" "(-7100,2350)"
					( Origin gFrontEnd )
				)
				( attribute "CHIPS_PART_NAME" "CAP"
					( Origin gPackager )
				)
				( attribute "CDS_PART_NAME" "CAP_0402-0.22UF,16V,10%,X7R,A3A"
					( Origin gPackager )
				)
				( objectStatus "C1M6" )
				( pin "a"
					( attribute "PN" "1"
						( Origin gPackager )
					)
					( objectStatus "C1M6.1" )
				)
				( pin "b"
					( attribute "PN" "2"
						( Origin gPackager )
					)
					( objectStatus "C1M6.2" )
				)
			)
			( gate "@baseboard_fab2_lib.baseboard_fab2(sch_1):page106_i111"
				( attribute "BOM_COST" "IO_SLOT"
					( Origin gFrontEnd )
				)
				( attribute "CDS_LIB" "mstr_discrete"
					( Origin gPackager )
				)
				( attribute "CDS_LOCATION" "C1M13"
					( Origin gPackager )
				)
				( attribute "CDS_SEC" "1"
					( Origin gPackager )
				)
				( attribute "LOCATION" "C1M13"
					( Origin gFrontEnd )
				)
				( attribute "MATERIAL" "X7R"
					( Origin gFrontEnd )
				)
				( attribute "PACK_TYPE" "0402"
					( Origin gFrontEnd )
				)
				( attribute "PART_NUMBER" "A36096-155"
					( Origin gFrontEnd )
				)
				( attribute "PHYS_PAGE" "106"
					( Origin gFrontEnd )
				)
				( attribute "ROOM" "PCIE_STEERING"
					( Origin gFrontEnd )
				)
				( attribute "ROT" "2"
					( Origin gFrontEnd )
				)
				( attribute "SEC" "1"
					( Origin gPackager )
				)
				( attribute "TOLERANCE" "10%"
					( Origin gFrontEnd )
				)
				( attribute "VALUE" "0.22UF"
					( Origin gFrontEnd )
				)
				( attribute "VER" "1"
					( Origin gFrontEnd )
				)
				( attribute "VOLTAGE" "16V"
					( Units "uVoltage" "V" 1.000000)
					( Origin gFrontEnd )
				)
				( attribute "XY" "(-6450,1650)"
					( Origin gFrontEnd )
				)
				( attribute "CHIPS_PART_NAME" "CAP"
					( Origin gPackager )
				)
				( attribute "CDS_PART_NAME" "CAP_0402-0.22UF,16V,10%,X7R,A3A"
					( Origin gPackager )
				)
				( objectStatus "C1M13" )
				( pin "a"
					( attribute "PN" "1"
						( Origin gPackager )
					)
					( objectStatus "C1M13.1" )
				)
				( pin "b"
					( attribute "PN" "2"
						( Origin gPackager )
					)
					( objectStatus "C1M13.2" )
				)
			)
			( gate "@baseboard_fab2_lib.baseboard_fab2(sch_1):page106_i114"
				( attribute "CDS_LIB" "mstr_discrete"
					( Origin gPackager )
				)
				( attribute "CDS_LOCATION" "C1M9"
					( Origin gPackager )
				)
				( attribute "CDS_SEC" "1"
					( Origin gPackager )
				)
				( attribute "LOCATION" "C1M9"
					( Origin gFrontEnd )
				)
				( attribute "MATERIAL" "X7R"
					( Origin gFrontEnd )
				)
				( attribute "PACK_TYPE" "0402"
					( Origin gFrontEnd )
				)
				( attribute "PART_NUMBER" "A36096-155"
					( Origin gFrontEnd )
				)
				( attribute "PHYS_PAGE" "106"
					( Origin gFrontEnd )
				)
				( attribute "ROOM" "PCIE_STEERING"
					( Origin gFrontEnd )
				)
				( attribute "ROT" "2"
					( Origin gFrontEnd )
				)
				( attribute "SEC" "1"
					( Origin gPackager )
				)
				( attribute "TOLERANCE" "10%"
					( Origin gFrontEnd )
				)
				( attribute "VALUE" "0.22UF"
					( Origin gFrontEnd )
				)
				( attribute "VER" "1"
					( Origin gFrontEnd )
				)
				( attribute "VOLTAGE" "16V"
					( Units "uVoltage" "V" 1.000000)
					( Origin gFrontEnd )
				)
				( attribute "XY" "(-6850,1650)"
					( Origin gFrontEnd )
				)
				( attribute "CHIPS_PART_NAME" "CAP"
					( Origin gPackager )
				)
				( attribute "CDS_PART_NAME" "CAP_0402-0.22UF,16V,10%,X7R,A3A"
					( Origin gPackager )
				)
				( objectStatus "C1M9" )
				( pin "a"
					( attribute "PN" "1"
						( Origin gPackager )
					)
					( objectStatus "C1M9.1" )
				)
				( pin "b"
					( attribute "PN" "2"
						( Origin gPackager )
					)
					( objectStatus "C1M9.2" )
				)
			)
			( gate "@baseboard_fab2_lib.baseboard_fab2(sch_1):page106_i117"
				( attribute "BOM_COST" "IO_SLOT"
					( Origin gFrontEnd )
				)
				( attribute "CDS_LIB" "mstr_discrete"
					( Origin gPackager )
				)
				( attribute "CDS_LOCATION" "C1M11"
					( Origin gPackager )
				)
				( attribute "CDS_SEC" "1"
					( Origin gPackager )
				)
				( attribute "LOCATION" "C1M11"
					( Origin gFrontEnd )
				)
				( attribute "MATERIAL" "X7R"
					( Origin gFrontEnd )
				)
				( attribute "PACK_TYPE" "0402"
					( Origin gFrontEnd )
				)
				( attribute "PART_NUMBER" "A36096-155"
					( Origin gFrontEnd )
				)
				( attribute "PHYS_PAGE" "106"
					( Origin gFrontEnd )
				)
				( attribute "ROOM" "PCIE_STEERING"
					( Origin gFrontEnd )
				)
				( attribute "ROT" "2"
					( Origin gFrontEnd )
				)
				( attribute "SEC" "1"
					( Origin gPackager )
				)
				( attribute "TOLERANCE" "10%"
					( Origin gFrontEnd )
				)
				( attribute "VALUE" "0.22UF"
					( Origin gFrontEnd )
				)
				( attribute "VER" "1"
					( Origin gFrontEnd )
				)
				( attribute "VOLTAGE" "16V"
					( Units "uVoltage" "V" 1.000000)
					( Origin gFrontEnd )
				)
				( attribute "XY" "(-6650,1350)"
					( Origin gFrontEnd )
				)
				( attribute "CHIPS_PART_NAME" "CAP"
					( Origin gPackager )
				)
				( attribute "CDS_PART_NAME" "CAP_0402-0.22UF,16V,10%,X7R,A3A"
					( Origin gPackager )
				)
				( objectStatus "C1M11" )
				( pin "a"
					( attribute "PN" "1"
						( Origin gPackager )
					)
					( objectStatus "C1M11.1" )
				)
				( pin "b"
					( attribute "PN" "2"
						( Origin gPackager )
					)
					( objectStatus "C1M11.2" )
				)
			)
			( gate "@baseboard_fab2_lib.baseboard_fab2(sch_1):page106_i122"
				( attribute "CDS_LIB" "mstr_discrete"
					( Origin gPackager )
				)
				( attribute "CDS_LOCATION" "C1M7"
					( Origin gPackager )
				)
				( attribute "CDS_SEC" "1"
					( Origin gPackager )
				)
				( attribute "LOCATION" "C1M7"
					( Origin gFrontEnd )
				)
				( attribute "MATERIAL" "X7R"
					( Origin gFrontEnd )
				)
				( attribute "PACK_TYPE" "0402"
					( Origin gFrontEnd )
				)
				( attribute "PART_NUMBER" "A36096-155"
					( Origin gFrontEnd )
				)
				( attribute "PHYS_PAGE" "106"
					( Origin gFrontEnd )
				)
				( attribute "ROOM" "PCIE_STEERING"
					( Origin gFrontEnd )
				)
				( attribute "ROT" "2"
					( Origin gFrontEnd )
				)
				( attribute "SEC" "1"
					( Origin gPackager )
				)
				( attribute "TOLERANCE" "10%"
					( Origin gFrontEnd )
				)
				( attribute "VALUE" "0.22UF"
					( Origin gFrontEnd )
				)
				( attribute "VER" "1"
					( Origin gFrontEnd )
				)
				( attribute "VOLTAGE" "16V"
					( Units "uVoltage" "V" 1.000000)
					( Origin gFrontEnd )
				)
				( attribute "XY" "(-7050,1350)"
					( Origin gFrontEnd )
				)
				( attribute "CHIPS_PART_NAME" "CAP"
					( Origin gPackager )
				)
				( attribute "CDS_PART_NAME" "CAP_0402-0.22UF,16V,10%,X7R,A3A"
					( Origin gPackager )
				)
				( objectStatus "C1M7" )
				( pin "a"
					( attribute "PN" "1"
						( Origin gPackager )
					)
					( objectStatus "C1M7.1" )
				)
				( pin "b"
					( attribute "PN" "2"
						( Origin gPackager )
					)
					( objectStatus "C1M7.2" )
				)
			)
			( gate "@baseboard_fab2_lib.baseboard_fab2(sch_1):page106_i123"
				( attribute "BOM_COST" "IO_SLOT"
					( Origin gFrontEnd )
				)
				( attribute "CDS_LIB" "mstr_discrete"
					( Origin gPackager )
				)
				( attribute "CDS_LOCATION" "C2R7"
					( Origin gPackager )
				)
				( attribute "CDS_SEC" "1"
					( Origin gPackager )
				)
				( attribute "LOCATION" "C2R7"
					( Origin gFrontEnd )
				)
				( attribute "MATERIAL" "X7R"
					( Origin gFrontEnd )
				)
				( attribute "PACK_TYPE" "0402"
					( Origin gFrontEnd )
				)
				( attribute "PART_NUMBER" "A36096-155"
					( Origin gFrontEnd )
				)
				( attribute "PHYS_PAGE" "106"
					( Origin gFrontEnd )
				)
				( attribute "ROOM" "PCIE_STEERING"
					( Origin gFrontEnd )
				)
				( attribute "ROT" "2"
					( Origin gFrontEnd )
				)
				( attribute "SEC" "1"
					( Origin gPackager )
				)
				( attribute "TOLERANCE" "10%"
					( Origin gFrontEnd )
				)
				( attribute "VALUE" "0.22UF"
					( Origin gFrontEnd )
				)
				( attribute "VER" "1"
					( Origin gFrontEnd )
				)
				( attribute "VOLTAGE" "16V"
					( Units "uVoltage" "V" 1.000000)
					( Origin gFrontEnd )
				)
				( attribute "XY" "(-5275,1650)"
					( Origin gFrontEnd )
				)
				( attribute "CHIPS_PART_NAME" "CAP"
					( Origin gPackager )
				)
				( attribute "CDS_PART_NAME" "CAP_0402-0.22UF,16V,10%,X7R,A3A"
					( Origin gPackager )
				)
				( objectStatus "C2R7" )
				( pin "a"
					( attribute "PN" "1"
						( Origin gPackager )
					)
					( objectStatus "C2R7.1" )
				)
				( pin "b"
					( attribute "PN" "2"
						( Origin gPackager )
					)
					( objectStatus "C2R7.2" )
				)
			)
			( gate "@baseboard_fab2_lib.baseboard_fab2(sch_1):page106_i128"
				( attribute "BOM_COST" "IO_SLOT"
					( Origin gFrontEnd )
				)
				( attribute "CDS_LIB" "mstr_discrete"
					( Origin gPackager )
				)
				( attribute "CDS_LOCATION" "C1R10"
					( Origin gPackager )
				)
				( attribute "CDS_SEC" "1"
					( Origin gPackager )
				)
				( attribute "LOCATION" "C1R10"
					( Origin gFrontEnd )
				)
				( attribute "MATERIAL" "X7R"
					( Origin gFrontEnd )
				)
				( attribute "PACK_TYPE" "0402"
					( Origin gFrontEnd )
				)
				( attribute "PART_NUMBER" "A36096-155"
					( Origin gFrontEnd )
				)
				( attribute "PHYS_PAGE" "106"
					( Origin gFrontEnd )
				)
				( attribute "ROOM" "PCIE_STEERING"
					( Origin gFrontEnd )
				)
				( attribute "ROT" "2"
					( Origin gFrontEnd )
				)
				( attribute "SEC" "1"
					( Origin gPackager )
				)
				( attribute "TOLERANCE" "10%"
					( Origin gFrontEnd )
				)
				( attribute "VALUE" "0.22UF"
					( Origin gFrontEnd )
				)
				( attribute "VER" "1"
					( Origin gFrontEnd )
				)
				( attribute "VOLTAGE" "16V"
					( Units "uVoltage" "V" 1.000000)
					( Origin gFrontEnd )
				)
				( attribute "XY" "(-4900,2650)"
					( Origin gFrontEnd )
				)
				( attribute "CHIPS_PART_NAME" "CAP"
					( Origin gPackager )
				)
				( attribute "CDS_PART_NAME" "CAP_0402-0.22UF,16V,10%,X7R,A3A"
					( Origin gPackager )
				)
				( objectStatus "C1R10" )
				( pin "a"
					( attribute "PN" "1"
						( Origin gPackager )
					)
					( objectStatus "C1R10.1" )
				)
				( pin "b"
					( attribute "PN" "2"
						( Origin gPackager )
					)
					( objectStatus "C1R10.2" )
				)
			)
			( gate "@baseboard_fab2_lib.baseboard_fab2(sch_1):page106_i130"
				( attribute "BOM_COST" "IO_SLOT"
					( Origin gFrontEnd )
				)
				( attribute "CDS_LIB" "mstr_discrete"
					( Origin gPackager )
				)
				( attribute "CDS_LOCATION" "C2R14"
					( Origin gPackager )
				)
				( attribute "CDS_SEC" "1"
					( Origin gPackager )
				)
				( attribute "LOCATION" "C2R14"
					( Origin gFrontEnd )
				)
				( attribute "MATERIAL" "X7R"
					( Origin gFrontEnd )
				)
				( attribute "PACK_TYPE" "0402"
					( Origin gFrontEnd )
				)
				( attribute "PART_NUMBER" "A36096-155"
					( Origin gFrontEnd )
				)
				( attribute "PHYS_PAGE" "106"
					( Origin gFrontEnd )
				)
				( attribute "ROOM" "PCIE_STEERING"
					( Origin gFrontEnd )
				)
				( attribute "ROT" "2"
					( Origin gFrontEnd )
				)
				( attribute "SEC" "1"
					( Origin gPackager )
				)
				( attribute "TOLERANCE" "10%"
					( Origin gFrontEnd )
				)
				( attribute "VALUE" "0.22UF"
					( Origin gFrontEnd )
				)
				( attribute "VER" "1"
					( Origin gFrontEnd )
				)
				( attribute "VOLTAGE" "16V"
					( Units "uVoltage" "V" 1.000000)
					( Origin gFrontEnd )
				)
				( attribute "XY" "(-5100,2350)"
					( Origin gFrontEnd )
				)
				( attribute "CHIPS_PART_NAME" "CAP"
					( Origin gPackager )
				)
				( attribute "CDS_PART_NAME" "CAP_0402-0.22UF,16V,10%,X7R,A3A"
					( Origin gPackager )
				)
				( objectStatus "C2R14" )
				( pin "a"
					( attribute "PN" "1"
						( Origin gPackager )
					)
					( objectStatus "C2R14.1" )
				)
				( pin "b"
					( attribute "PN" "2"
						( Origin gPackager )
					)
					( objectStatus "C2R14.2" )
				)
			)
			( gate "@baseboard_fab2_lib.baseboard_fab2(sch_1):page106_i134"
				( attribute "BOM_COST" "IO_SLOT"
					( Origin gFrontEnd )
				)
				( attribute "CDS_LIB" "mstr_discrete"
					( Origin gPackager )
				)
				( attribute "CDS_LOCATION" "C1R9"
					( Origin gPackager )
				)
				( attribute "CDS_SEC" "1"
					( Origin gPackager )
				)
				( attribute "LOCATION" "C1R9"
					( Origin gFrontEnd )
				)
				( attribute "MATERIAL" "X7R"
					( Origin gFrontEnd )
				)
				( attribute "PACK_TYPE" "0402"
					( Origin gFrontEnd )
				)
				( attribute "PART_NUMBER" "A36096-155"
					( Origin gFrontEnd )
				)
				( attribute "PHYS_PAGE" "106"
					( Origin gFrontEnd )
				)
				( attribute "ROOM" "PCIE_STEERING"
					( Origin gFrontEnd )
				)
				( attribute "ROT" "2"
					( Origin gFrontEnd )
				)
				( attribute "SEC" "1"
					( Origin gPackager )
				)
				( attribute "TOLERANCE" "10%"
					( Origin gFrontEnd )
				)
				( attribute "VALUE" "0.22UF"
					( Origin gFrontEnd )
				)
				( attribute "VER" "1"
					( Origin gFrontEnd )
				)
				( attribute "VOLTAGE" "16V"
					( Units "uVoltage" "V" 1.000000)
					( Origin gFrontEnd )
				)
				( attribute "XY" "(-4875,1650)"
					( Origin gFrontEnd )
				)
				( attribute "CHIPS_PART_NAME" "CAP"
					( Origin gPackager )
				)
				( attribute "CDS_PART_NAME" "CAP_0402-0.22UF,16V,10%,X7R,A3A"
					( Origin gPackager )
				)
				( objectStatus "C1R9" )
				( pin "a"
					( attribute "PN" "1"
						( Origin gPackager )
					)
					( objectStatus "C1R9.1" )
				)
				( pin "b"
					( attribute "PN" "2"
						( Origin gPackager )
					)
					( objectStatus "C1R9.2" )
				)
			)
			( gate "@baseboard_fab2_lib.baseboard_fab2(sch_1):page106_i137"
				( attribute "BOM_COST" "IO_SLOT"
					( Origin gFrontEnd )
				)
				( attribute "CDS_LIB" "mstr_discrete"
					( Origin gPackager )
				)
				( attribute "CDS_LOCATION" "C2R13"
					( Origin gPackager )
				)
				( attribute "CDS_SEC" "1"
					( Origin gPackager )
				)
				( attribute "LOCATION" "C2R13"
					( Origin gFrontEnd )
				)
				( attribute "MATERIAL" "X7R"
					( Origin gFrontEnd )
				)
				( attribute "PACK_TYPE" "0402"
					( Origin gFrontEnd )
				)
				( attribute "PART_NUMBER" "A36096-155"
					( Origin gFrontEnd )
				)
				( attribute "PHYS_PAGE" "106"
					( Origin gFrontEnd )
				)
				( attribute "ROOM" "PCIE_STEERING"
					( Origin gFrontEnd )
				)
				( attribute "ROT" "2"
					( Origin gFrontEnd )
				)
				( attribute "SEC" "1"
					( Origin gPackager )
				)
				( attribute "TOLERANCE" "10%"
					( Origin gFrontEnd )
				)
				( attribute "VALUE" "0.22UF"
					( Origin gFrontEnd )
				)
				( attribute "VER" "1"
					( Origin gFrontEnd )
				)
				( attribute "VOLTAGE" "16V"
					( Units "uVoltage" "V" 1.000000)
					( Origin gFrontEnd )
				)
				( attribute "XY" "(-5075,1350)"
					( Origin gFrontEnd )
				)
				( attribute "CHIPS_PART_NAME" "CAP"
					( Origin gPackager )
				)
				( attribute "CDS_PART_NAME" "CAP_0402-0.22UF,16V,10%,X7R,A3A"
					( Origin gPackager )
				)
				( objectStatus "C2R13" )
				( pin "a"
					( attribute "PN" "1"
						( Origin gPackager )
					)
					( objectStatus "C2R13.1" )
				)
				( pin "b"
					( attribute "PN" "2"
						( Origin gPackager )
					)
					( objectStatus "C2R13.2" )
				)
			)
			( gate "@baseboard_fab2_lib.baseboard_fab2(sch_1):page106_i141"
				( attribute "BOM_COST" "IO_SLOT"
					( Origin gFrontEnd )
				)
				( attribute "CDS_LIB" "mstr_discrete"
					( Origin gPackager )
				)
				( attribute "CDS_LOCATION" "C2R8"
					( Origin gPackager )
				)
				( attribute "CDS_SEC" "1"
					( Origin gPackager )
				)
				( attribute "LOCATION" "C2R8"
					( Origin gFrontEnd )
				)
				( attribute "MATERIAL" "X7R"
					( Origin gFrontEnd )
				)
				( attribute "PACK_TYPE" "0402"
					( Origin gFrontEnd )
				)
				( attribute "PART_NUMBER" "A36096-155"
					( Origin gFrontEnd )
				)
				( attribute "PHYS_PAGE" "106"
					( Origin gFrontEnd )
				)
				( attribute "ROOM" "PCIE_STEERING"
					( Origin gFrontEnd )
				)
				( attribute "ROT" "2"
					( Origin gFrontEnd )
				)
				( attribute "SEC" "1"
					( Origin gPackager )
				)
				( attribute "TOLERANCE" "10%"
					( Origin gFrontEnd )
				)
				( attribute "VALUE" "0.22UF"
					( Origin gFrontEnd )
				)
				( attribute "VER" "1"
					( Origin gFrontEnd )
				)
				( attribute "VOLTAGE" "16V"
					( Units "uVoltage" "V" 1.000000)
					( Origin gFrontEnd )
				)
				( attribute "XY" "(-5300,2650)"
					( Origin gFrontEnd )
				)
				( attribute "CHIPS_PART_NAME" "CAP"
					( Origin gPackager )
				)
				( attribute "CDS_PART_NAME" "CAP_0402-0.22UF,16V,10%,X7R,A3A"
					( Origin gPackager )
				)
				( objectStatus "C2R8" )
				( pin "a"
					( attribute "PN" "1"
						( Origin gPackager )
					)
					( objectStatus "C2R8.1" )
				)
				( pin "b"
					( attribute "PN" "2"
						( Origin gPackager )
					)
					( objectStatus "C2R8.2" )
				)
			)
			( gate "@baseboard_fab2_lib.baseboard_fab2(sch_1):page106_i142"
				( attribute "BOM_COST" "IO_SLOT"
					( Origin gFrontEnd )
				)
				( attribute "CDS_LIB" "mstr_discrete"
					( Origin gPackager )
				)
				( attribute "CDS_LOCATION" "C2R10"
					( Origin gPackager )
				)
				( attribute "CDS_SEC" "1"
					( Origin gPackager )
				)
				( attribute "LOCATION" "C2R10"
					( Origin gFrontEnd )
				)
				( attribute "MATERIAL" "X7R"
					( Origin gFrontEnd )
				)
				( attribute "PACK_TYPE" "0402"
					( Origin gFrontEnd )
				)
				( attribute "PART_NUMBER" "A36096-155"
					( Origin gFrontEnd )
				)
				( attribute "PHYS_PAGE" "106"
					( Origin gFrontEnd )
				)
				( attribute "ROOM" "PCIE_STEERING"
					( Origin gFrontEnd )
				)
				( attribute "ROT" "2"
					( Origin gFrontEnd )
				)
				( attribute "SEC" "1"
					( Origin gPackager )
				)
				( attribute "TOLERANCE" "10%"
					( Origin gFrontEnd )
				)
				( attribute "VALUE" "0.22UF"
					( Origin gFrontEnd )
				)
				( attribute "VER" "1"
					( Origin gFrontEnd )
				)
				( attribute "VOLTAGE" "16V"
					( Units "uVoltage" "V" 1.000000)
					( Origin gFrontEnd )
				)
				( attribute "XY" "(-5500,2350)"
					( Origin gFrontEnd )
				)
				( attribute "CHIPS_PART_NAME" "CAP"
					( Origin gPackager )
				)
				( attribute "CDS_PART_NAME" "CAP_0402-0.22UF,16V,10%,X7R,A3A"
					( Origin gPackager )
				)
				( objectStatus "C2R10" )
				( pin "a"
					( attribute "PN" "1"
						( Origin gPackager )
					)
					( objectStatus "C2R10.1" )
				)
				( pin "b"
					( attribute "PN" "2"
						( Origin gPackager )
					)
					( objectStatus "C2R10.2" )
				)
			)
			( gate "@baseboard_fab2_lib.baseboard_fab2(sch_1):page106_i147"
				( attribute "BOM_COST" "IO_SLOT"
					( Origin gFrontEnd )
				)
				( attribute "CDS_LIB" "mstr_discrete"
					( Origin gPackager )
				)
				( attribute "CDS_LOCATION" "C2R9"
					( Origin gPackager )
				)
				( attribute "CDS_SEC" "1"
					( Origin gPackager )
				)
				( attribute "LOCATION" "C2R9"
					( Origin gFrontEnd )
				)
				( attribute "MATERIAL" "X7R"
					( Origin gFrontEnd )
				)
				( attribute "PACK_TYPE" "0402"
					( Origin gFrontEnd )
				)
				( attribute "PART_NUMBER" "A36096-155"
					( Origin gFrontEnd )
				)
				( attribute "PHYS_PAGE" "106"
					( Origin gFrontEnd )
				)
				( attribute "ROOM" "PCIE_STEERING"
					( Origin gFrontEnd )
				)
				( attribute "ROT" "2"
					( Origin gFrontEnd )
				)
				( attribute "SEC" "1"
					( Origin gPackager )
				)
				( attribute "TOLERANCE" "10%"
					( Origin gFrontEnd )
				)
				( attribute "VALUE" "0.22UF"
					( Origin gFrontEnd )
				)
				( attribute "VER" "1"
					( Origin gFrontEnd )
				)
				( attribute "VOLTAGE" "16V"
					( Units "uVoltage" "V" 1.000000)
					( Origin gFrontEnd )
				)
				( attribute "XY" "(-5475,1350)"
					( Origin gFrontEnd )
				)
				( attribute "CHIPS_PART_NAME" "CAP"
					( Origin gPackager )
				)
				( attribute "CDS_PART_NAME" "CAP_0402-0.22UF,16V,10%,X7R,A3A"
					( Origin gPackager )
				)
				( objectStatus "C2R9" )
				( pin "a"
					( attribute "PN" "1"
						( Origin gPackager )
					)
					( objectStatus "C2R9.1" )
				)
				( pin "b"
					( attribute "PN" "2"
						( Origin gPackager )
					)
					( objectStatus "C2R9.2" )
				)
			)
			( gate "@baseboard_fab2_lib.baseboard_fab2(sch_1):page107_i207"
				( attribute "CDS_LIB" "mstr_discrete"
					( Origin gPackager )
				)
				( attribute "CDS_LOCATION" "C3P13"
					( Origin gPackager )
				)
				( attribute "CDS_SEC" "1"
					( Origin gPackager )
				)
				( attribute "LOCATION" "C3P13"
					( Origin gFrontEnd )
				)
				( attribute "MATERIAL" "X7R"
					( Origin gFrontEnd )
				)
				( attribute "PACK_TYPE" "0402"
					( Origin gFrontEnd )
				)
				( attribute "PART_NUMBER" "A36096-155"
					( Origin gFrontEnd )
				)
				( attribute "PHYS_PAGE" "107"
					( Origin gFrontEnd )
				)
				( attribute "ROT" "2"
					( Origin gFrontEnd )
				)
				( attribute "SEC" "1"
					( Origin gPackager )
				)
				( attribute "TOLERANCE" "10%"
					( Origin gFrontEnd )
				)
				( attribute "VALUE" "0.22UF"
					( Origin gFrontEnd )
				)
				( attribute "VER" "1"
					( Origin gFrontEnd )
				)
				( attribute "VOLTAGE" "16V"
					( Units "uVoltage" "V" 1.000000)
					( Origin gFrontEnd )
				)
				( attribute "XY" "(-5525,1875)"
					( Origin gFrontEnd )
				)
				( attribute "CHIPS_PART_NAME" "CAP"
					( Origin gPackager )
				)
				( attribute "CDS_PART_NAME" "CAP_0402-0.22UF,16V,10%,X7R,A3A"
					( Origin gPackager )
				)
				( objectStatus "C3P13" )
				( pin "a"
					( attribute "PN" "1"
						( Origin gPackager )
					)
					( objectStatus "C3P13.1" )
				)
				( pin "b"
					( attribute "PN" "2"
						( Origin gPackager )
					)
					( objectStatus "C3P13.2" )
				)
			)
			( gate "@baseboard_fab2_lib.baseboard_fab2(sch_1):page107_i208"
				( attribute "CDS_LIB" "mstr_discrete"
					( Origin gPackager )
				)
				( attribute "CDS_LOCATION" "C3P17"
					( Origin gPackager )
				)
				( attribute "CDS_SEC" "1"
					( Origin gPackager )
				)
				( attribute "LOCATION" "C3P17"
					( Origin gFrontEnd )
				)
				( attribute "MATERIAL" "X7R"
					( Origin gFrontEnd )
				)
				( attribute "PACK_TYPE" "0402"
					( Origin gFrontEnd )
				)
				( attribute "PART_NUMBER" "A36096-155"
					( Origin gFrontEnd )
				)
				( attribute "PHYS_PAGE" "107"
					( Origin gFrontEnd )
				)
				( attribute "ROT" "2"
					( Origin gFrontEnd )
				)
				( attribute "SEC" "1"
					( Origin gPackager )
				)
				( attribute "TOLERANCE" "10%"
					( Origin gFrontEnd )
				)
				( attribute "VALUE" "0.22UF"
					( Origin gFrontEnd )
				)
				( attribute "VER" "1"
					( Origin gFrontEnd )
				)
				( attribute "VOLTAGE" "16V"
					( Units "uVoltage" "V" 1.000000)
					( Origin gFrontEnd )
				)
				( attribute "XY" "(-5725,1575)"
					( Origin gFrontEnd )
				)
				( attribute "CHIPS_PART_NAME" "CAP"
					( Origin gPackager )
				)
				( attribute "CDS_PART_NAME" "CAP_0402-0.22UF,16V,10%,X7R,A3A"
					( Origin gPackager )
				)
				( objectStatus "C3P17" )
				( pin "a"
					( attribute "PN" "1"
						( Origin gPackager )
					)
					( objectStatus "C3P17.1" )
				)
				( pin "b"
					( attribute "PN" "2"
						( Origin gPackager )
					)
					( objectStatus "C3P17.2" )
				)
			)
			( gate "@baseboard_fab2_lib.baseboard_fab2(sch_1):page107_i212"
				( attribute "CDS_LIB" "mstr_discrete"
					( Origin gPackager )
				)
				( attribute "CDS_LOCATION" "C3P11"
					( Origin gPackager )
				)
				( attribute "CDS_SEC" "1"
					( Origin gPackager )
				)
				( attribute "LOCATION" "C3P11"
					( Origin gFrontEnd )
				)
				( attribute "MATERIAL" "X7R"
					( Origin gFrontEnd )
				)
				( attribute "PACK_TYPE" "0402"
					( Origin gFrontEnd )
				)
				( attribute "PART_NUMBER" "A36096-155"
					( Origin gFrontEnd )
				)
				( attribute "PHYS_PAGE" "107"
					( Origin gFrontEnd )
				)
				( attribute "ROT" "2"
					( Origin gFrontEnd )
				)
				( attribute "SEC" "1"
					( Origin gPackager )
				)
				( attribute "TOLERANCE" "10%"
					( Origin gFrontEnd )
				)
				( attribute "VALUE" "0.22UF"
					( Origin gFrontEnd )
				)
				( attribute "VER" "1"
					( Origin gFrontEnd )
				)
				( attribute "VOLTAGE" "16V"
					( Units "uVoltage" "V" 1.000000)
					( Origin gFrontEnd )
				)
				( attribute "XY" "(-5475,875)"
					( Origin gFrontEnd )
				)
				( attribute "CHIPS_PART_NAME" "CAP"
					( Origin gPackager )
				)
				( attribute "CDS_PART_NAME" "CAP_0402-0.22UF,16V,10%,X7R,A3A"
					( Origin gPackager )
				)
				( objectStatus "C3P11" )
				( pin "a"
					( attribute "PN" "1"
						( Origin gPackager )
					)
					( objectStatus "C3P11.1" )
				)
				( pin "b"
					( attribute "PN" "2"
						( Origin gPackager )
					)
					( objectStatus "C3P11.2" )
				)
			)
			( gate "@baseboard_fab2_lib.baseboard_fab2(sch_1):page107_i215"
				( attribute "CDS_LIB" "mstr_discrete"
					( Origin gPackager )
				)
				( attribute "CDS_LOCATION" "C3P20"
					( Origin gPackager )
				)
				( attribute "CDS_SEC" "1"
					( Origin gPackager )
				)
				( attribute "LOCATION" "C3P20"
					( Origin gFrontEnd )
				)
				( attribute "MATERIAL" "X7R"
					( Origin gFrontEnd )
				)
				( attribute "PACK_TYPE" "0402"
					( Origin gFrontEnd )
				)
				( attribute "PART_NUMBER" "A36096-155"
					( Origin gFrontEnd )
				)
				( attribute "PHYS_PAGE" "107"
					( Origin gFrontEnd )
				)
				( attribute "ROT" "2"
					( Origin gFrontEnd )
				)
				( attribute "SEC" "1"
					( Origin gPackager )
				)
				( attribute "TOLERANCE" "10%"
					( Origin gFrontEnd )
				)
				( attribute "VALUE" "0.22UF"
					( Origin gFrontEnd )
				)
				( attribute "VER" "1"
					( Origin gFrontEnd )
				)
				( attribute "VOLTAGE" "16V"
					( Units "uVoltage" "V" 1.000000)
					( Origin gFrontEnd )
				)
				( attribute "XY" "(-5925,1900)"
					( Origin gFrontEnd )
				)
				( attribute "CHIPS_PART_NAME" "CAP"
					( Origin gPackager )
				)
				( attribute "CDS_PART_NAME" "CAP_0402-0.22UF,16V,10%,X7R,A3A"
					( Origin gPackager )
				)
				( objectStatus "C3P20" )
				( pin "a"
					( attribute "PN" "1"
						( Origin gPackager )
					)
					( objectStatus "C3P20.1" )
				)
				( pin "b"
					( attribute "PN" "2"
						( Origin gPackager )
					)
					( objectStatus "C3P20.2" )
				)
			)
			( gate "@baseboard_fab2_lib.baseboard_fab2(sch_1):page107_i216"
				( attribute "CDS_LIB" "mstr_discrete"
					( Origin gPackager )
				)
				( attribute "CDS_LOCATION" "C3P25"
					( Origin gPackager )
				)
				( attribute "CDS_SEC" "1"
					( Origin gPackager )
				)
				( attribute "LOCATION" "C3P25"
					( Origin gFrontEnd )
				)
				( attribute "MATERIAL" "X7R"
					( Origin gFrontEnd )
				)
				( attribute "PACK_TYPE" "0402"
					( Origin gFrontEnd )
				)
				( attribute "PART_NUMBER" "A36096-155"
					( Origin gFrontEnd )
				)
				( attribute "PHYS_PAGE" "107"
					( Origin gFrontEnd )
				)
				( attribute "ROT" "2"
					( Origin gFrontEnd )
				)
				( attribute "SEC" "1"
					( Origin gPackager )
				)
				( attribute "TOLERANCE" "10%"
					( Origin gFrontEnd )
				)
				( attribute "VALUE" "0.22UF"
					( Origin gFrontEnd )
				)
				( attribute "VER" "1"
					( Origin gFrontEnd )
				)
				( attribute "VOLTAGE" "16V"
					( Units "uVoltage" "V" 1.000000)
					( Origin gFrontEnd )
				)
				( attribute "XY" "(-6125,1575)"
					( Origin gFrontEnd )
				)
				( attribute "CHIPS_PART_NAME" "CAP"
					( Origin gPackager )
				)
				( attribute "CDS_PART_NAME" "CAP_0402-0.22UF,16V,10%,X7R,A3A"
					( Origin gPackager )
				)
				( objectStatus "C3P25" )
				( pin "a"
					( attribute "PN" "1"
						( Origin gPackager )
					)
					( objectStatus "C3P25.1" )
				)
				( pin "b"
					( attribute "PN" "2"
						( Origin gPackager )
					)
					( objectStatus "C3P25.2" )
				)
			)
			( gate "@baseboard_fab2_lib.baseboard_fab2(sch_1):page107_i219"
				( attribute "CDS_LIB" "mstr_discrete"
					( Origin gPackager )
				)
				( attribute "CDS_LOCATION" "C3P18"
					( Origin gPackager )
				)
				( attribute "CDS_SEC" "1"
					( Origin gPackager )
				)
				( attribute "LOCATION" "C3P18"
					( Origin gFrontEnd )
				)
				( attribute "MATERIAL" "X7R"
					( Origin gFrontEnd )
				)
				( attribute "PACK_TYPE" "0402"
					( Origin gFrontEnd )
				)
				( attribute "PART_NUMBER" "A36096-155"
					( Origin gFrontEnd )
				)
				( attribute "PHYS_PAGE" "107"
					( Origin gFrontEnd )
				)
				( attribute "ROT" "2"
					( Origin gFrontEnd )
				)
				( attribute "SEC" "1"
					( Origin gPackager )
				)
				( attribute "TOLERANCE" "10%"
					( Origin gFrontEnd )
				)
				( attribute "VALUE" "0.22UF"
					( Origin gFrontEnd )
				)
				( attribute "VER" "1"
					( Origin gFrontEnd )
				)
				( attribute "VOLTAGE" "16V"
					( Units "uVoltage" "V" 1.000000)
					( Origin gFrontEnd )
				)
				( attribute "XY" "(-5875,875)"
					( Origin gFrontEnd )
				)
				( attribute "CHIPS_PART_NAME" "CAP"
					( Origin gPackager )
				)
				( attribute "CDS_PART_NAME" "CAP_0402-0.22UF,16V,10%,X7R,A3A"
					( Origin gPackager )
				)
				( objectStatus "C3P18" )
				( pin "a"
					( attribute "PN" "1"
						( Origin gPackager )
					)
					( objectStatus "C3P18.1" )
				)
				( pin "b"
					( attribute "PN" "2"
						( Origin gPackager )
					)
					( objectStatus "C3P18.2" )
				)
			)
			( gate "@baseboard_fab2_lib.baseboard_fab2(sch_1):page107_i223"
				( attribute "CDS_LIB" "mstr_discrete"
					( Origin gPackager )
				)
				( attribute "CDS_LOCATION" "C3P27"
					( Origin gPackager )
				)
				( attribute "CDS_SEC" "1"
					( Origin gPackager )
				)
				( attribute "LOCATION" "C3P27"
					( Origin gFrontEnd )
				)
				( attribute "MATERIAL" "X7R"
					( Origin gFrontEnd )
				)
				( attribute "PACK_TYPE" "0402"
					( Origin gFrontEnd )
				)
				( attribute "PART_NUMBER" "A36096-155"
					( Origin gFrontEnd )
				)
				( attribute "PHYS_PAGE" "107"
					( Origin gFrontEnd )
				)
				( attribute "ROT" "2"
					( Origin gFrontEnd )
				)
				( attribute "SEC" "1"
					( Origin gPackager )
				)
				( attribute "TOLERANCE" "10%"
					( Origin gFrontEnd )
				)
				( attribute "VALUE" "0.22UF"
					( Origin gFrontEnd )
				)
				( attribute "VER" "1"
					( Origin gFrontEnd )
				)
				( attribute "VOLTAGE" "16V"
					( Units "uVoltage" "V" 1.000000)
					( Origin gFrontEnd )
				)
				( attribute "XY" "(-6275,875)"
					( Origin gFrontEnd )
				)
				( attribute "CHIPS_PART_NAME" "CAP"
					( Origin gPackager )
				)
				( attribute "CDS_PART_NAME" "CAP_0402-0.22UF,16V,10%,X7R,A3A"
					( Origin gPackager )
				)
				( objectStatus "C3P27" )
				( pin "a"
					( attribute "PN" "1"
						( Origin gPackager )
					)
					( objectStatus "C3P27.1" )
				)
				( pin "b"
					( attribute "PN" "2"
						( Origin gPackager )
					)
					( objectStatus "C3P27.2" )
				)
			)
			( gate "@baseboard_fab2_lib.baseboard_fab2(sch_1):page107_i226"
				( attribute "CDS_LIB" "mstr_discrete"
					( Origin gPackager )
				)
				( attribute "CDS_LOCATION" "C3P15"
					( Origin gPackager )
				)
				( attribute "CDS_SEC" "1"
					( Origin gPackager )
				)
				( attribute "LOCATION" "C3P15"
					( Origin gFrontEnd )
				)
				( attribute "MATERIAL" "X7R"
					( Origin gFrontEnd )
				)
				( attribute "PACK_TYPE" "0402"
					( Origin gFrontEnd )
				)
				( attribute "PART_NUMBER" "A36096-155"
					( Origin gFrontEnd )
				)
				( attribute "PHYS_PAGE" "107"
					( Origin gFrontEnd )
				)
				( attribute "ROT" "2"
					( Origin gFrontEnd )
				)
				( attribute "SEC" "1"
					( Origin gPackager )
				)
				( attribute "TOLERANCE" "10%"
					( Origin gFrontEnd )
				)
				( attribute "VALUE" "0.22UF"
					( Origin gFrontEnd )
				)
				( attribute "VER" "1"
					( Origin gFrontEnd )
				)
				( attribute "VOLTAGE" "16V"
					( Units "uVoltage" "V" 1.000000)
					( Origin gFrontEnd )
				)
				( attribute "XY" "(-5675,575)"
					( Origin gFrontEnd )
				)
				( attribute "CHIPS_PART_NAME" "CAP"
					( Origin gPackager )
				)
				( attribute "CDS_PART_NAME" "CAP_0402-0.22UF,16V,10%,X7R,A3A"
					( Origin gPackager )
				)
				( objectStatus "C3P15" )
				( pin "a"
					( attribute "PN" "1"
						( Origin gPackager )
					)
					( objectStatus "C3P15.1" )
				)
				( pin "b"
					( attribute "PN" "2"
						( Origin gPackager )
					)
					( objectStatus "C3P15.2" )
				)
			)
			( gate "@baseboard_fab2_lib.baseboard_fab2(sch_1):page107_i229"
				( attribute "CDS_LIB" "mstr_discrete"
					( Origin gPackager )
				)
				( attribute "CDS_LOCATION" "C3P23"
					( Origin gPackager )
				)
				( attribute "CDS_SEC" "1"
					( Origin gPackager )
				)
				( attribute "LOCATION" "C3P23"
					( Origin gFrontEnd )
				)
				( attribute "MATERIAL" "X7R"
					( Origin gFrontEnd )
				)
				( attribute "PACK_TYPE" "0402"
					( Origin gFrontEnd )
				)
				( attribute "PART_NUMBER" "A36096-155"
					( Origin gFrontEnd )
				)
				( attribute "PHYS_PAGE" "107"
					( Origin gFrontEnd )
				)
				( attribute "ROT" "2"
					( Origin gFrontEnd )
				)
				( attribute "SEC" "1"
					( Origin gPackager )
				)
				( attribute "TOLERANCE" "10%"
					( Origin gFrontEnd )
				)
				( attribute "VALUE" "0.22UF"
					( Origin gFrontEnd )
				)
				( attribute "VER" "1"
					( Origin gFrontEnd )
				)
				( attribute "VOLTAGE" "16V"
					( Units "uVoltage" "V" 1.000000)
					( Origin gFrontEnd )
				)
				( attribute "XY" "(-6075,575)"
					( Origin gFrontEnd )
				)
				( attribute "CHIPS_PART_NAME" "CAP"
					( Origin gPackager )
				)
				( attribute "CDS_PART_NAME" "CAP_0402-0.22UF,16V,10%,X7R,A3A"
					( Origin gPackager )
				)
				( objectStatus "C3P23" )
				( pin "a"
					( attribute "PN" "1"
						( Origin gPackager )
					)
					( objectStatus "C3P23.1" )
				)
				( pin "b"
					( attribute "PN" "2"
						( Origin gPackager )
					)
					( objectStatus "C3P23.2" )
				)
			)
			( gate "@baseboard_fab2_lib.baseboard_fab2(sch_1):page107_i232"
				( attribute "CDS_LIB" "mstr_discrete"
					( Origin gPackager )
				)
				( attribute "CDS_LOCATION" "C3P28"
					( Origin gPackager )
				)
				( attribute "CDS_SEC" "1"
					( Origin gPackager )
				)
				( attribute "LOCATION" "C3P28"
					( Origin gFrontEnd )
				)
				( attribute "MATERIAL" "X7R"
					( Origin gFrontEnd )
				)
				( attribute "PACK_TYPE" "0402"
					( Origin gFrontEnd )
				)
				( attribute "PART_NUMBER" "A36096-155"
					( Origin gFrontEnd )
				)
				( attribute "PHYS_PAGE" "107"
					( Origin gFrontEnd )
				)
				( attribute "ROT" "2"
					( Origin gFrontEnd )
				)
				( attribute "SEC" "1"
					( Origin gPackager )
				)
				( attribute "TOLERANCE" "10%"
					( Origin gFrontEnd )
				)
				( attribute "VALUE" "0.22UF"
					( Origin gFrontEnd )
				)
				( attribute "VER" "1"
					( Origin gFrontEnd )
				)
				( attribute "VOLTAGE" "16V"
					( Units "uVoltage" "V" 1.000000)
					( Origin gFrontEnd )
				)
				( attribute "XY" "(-6325,1875)"
					( Origin gFrontEnd )
				)
				( attribute "CHIPS_PART_NAME" "CAP"
					( Origin gPackager )
				)
				( attribute "CDS_PART_NAME" "CAP_0402-0.22UF,16V,10%,X7R,A3A"
					( Origin gPackager )
				)
				( objectStatus "C3P28" )
				( pin "a"
					( attribute "PN" "1"
						( Origin gPackager )
					)
					( objectStatus "C3P28.1" )
				)
				( pin "b"
					( attribute "PN" "2"
						( Origin gPackager )
					)
					( objectStatus "C3P28.2" )
				)
			)
			( gate "@baseboard_fab2_lib.baseboard_fab2(sch_1):page107_i234"
				( attribute "CDS_LIB" "mstr_discrete"
					( Origin gPackager )
				)
				( attribute "CDS_LOCATION" "C3P32"
					( Origin gPackager )
				)
				( attribute "CDS_SEC" "1"
					( Origin gPackager )
				)
				( attribute "LOCATION" "C3P32"
					( Origin gFrontEnd )
				)
				( attribute "MATERIAL" "X7R"
					( Origin gFrontEnd )
				)
				( attribute "PACK_TYPE" "0402"
					( Origin gFrontEnd )
				)
				( attribute "PART_NUMBER" "A36096-155"
					( Origin gFrontEnd )
				)
				( attribute "PHYS_PAGE" "107"
					( Origin gFrontEnd )
				)
				( attribute "ROT" "2"
					( Origin gFrontEnd )
				)
				( attribute "SEC" "1"
					( Origin gPackager )
				)
				( attribute "TOLERANCE" "10%"
					( Origin gFrontEnd )
				)
				( attribute "VALUE" "0.22UF"
					( Origin gFrontEnd )
				)
				( attribute "VER" "1"
					( Origin gFrontEnd )
				)
				( attribute "VOLTAGE" "16V"
					( Units "uVoltage" "V" 1.000000)
					( Origin gFrontEnd )
				)
				( attribute "XY" "(-6525,1575)"
					( Origin gFrontEnd )
				)
				( attribute "CHIPS_PART_NAME" "CAP"
					( Origin gPackager )
				)
				( attribute "CDS_PART_NAME" "CAP_0402-0.22UF,16V,10%,X7R,A3A"
					( Origin gPackager )
				)
				( objectStatus "C3P32" )
				( pin "a"
					( attribute "PN" "1"
						( Origin gPackager )
					)
					( objectStatus "C3P32.1" )
				)
				( pin "b"
					( attribute "PN" "2"
						( Origin gPackager )
					)
					( objectStatus "C3P32.2" )
				)
			)
			( gate "@baseboard_fab2_lib.baseboard_fab2(sch_1):page107_i235"
				( attribute "CDS_LIB" "mstr_discrete"
					( Origin gPackager )
				)
				( attribute "CDS_LOCATION" "C3P37"
					( Origin gPackager )
				)
				( attribute "CDS_SEC" "1"
					( Origin gPackager )
				)
				( attribute "LOCATION" "C3P37"
					( Origin gFrontEnd )
				)
				( attribute "MATERIAL" "X7R"
					( Origin gFrontEnd )
				)
				( attribute "PACK_TYPE" "0402"
					( Origin gFrontEnd )
				)
				( attribute "PART_NUMBER" "A36096-155"
					( Origin gFrontEnd )
				)
				( attribute "PHYS_PAGE" "107"
					( Origin gFrontEnd )
				)
				( attribute "ROT" "2"
					( Origin gFrontEnd )
				)
				( attribute "SEC" "1"
					( Origin gPackager )
				)
				( attribute "TOLERANCE" "10%"
					( Origin gFrontEnd )
				)
				( attribute "VALUE" "0.22UF"
					( Origin gFrontEnd )
				)
				( attribute "VER" "1"
					( Origin gFrontEnd )
				)
				( attribute "VOLTAGE" "16V"
					( Units "uVoltage" "V" 1.000000)
					( Origin gFrontEnd )
				)
				( attribute "XY" "(-6725,1875)"
					( Origin gFrontEnd )
				)
				( attribute "CHIPS_PART_NAME" "CAP"
					( Origin gPackager )
				)
				( attribute "CDS_PART_NAME" "CAP_0402-0.22UF,16V,10%,X7R,A3A"
					( Origin gPackager )
				)
				( objectStatus "C3P37" )
				( pin "a"
					( attribute "PN" "1"
						( Origin gPackager )
					)
					( objectStatus "C3P37.1" )
				)
				( pin "b"
					( attribute "PN" "2"
						( Origin gPackager )
					)
					( objectStatus "C3P37.2" )
				)
			)
			( gate "@baseboard_fab2_lib.baseboard_fab2(sch_1):page107_i240"
				( attribute "CDS_LIB" "mstr_discrete"
					( Origin gPackager )
				)
				( attribute "CDS_LOCATION" "C3P35"
					( Origin gPackager )
				)
				( attribute "CDS_SEC" "1"
					( Origin gPackager )
				)
				( attribute "LOCATION" "C3P35"
					( Origin gFrontEnd )
				)
				( attribute "MATERIAL" "X7R"
					( Origin gFrontEnd )
				)
				( attribute "PACK_TYPE" "0402"
					( Origin gFrontEnd )
				)
				( attribute "PART_NUMBER" "A36096-155"
					( Origin gFrontEnd )
				)
				( attribute "PHYS_PAGE" "107"
					( Origin gFrontEnd )
				)
				( attribute "ROT" "2"
					( Origin gFrontEnd )
				)
				( attribute "SEC" "1"
					( Origin gPackager )
				)
				( attribute "TOLERANCE" "10%"
					( Origin gFrontEnd )
				)
				( attribute "VALUE" "0.22UF"
					( Origin gFrontEnd )
				)
				( attribute "VER" "1"
					( Origin gFrontEnd )
				)
				( attribute "VOLTAGE" "16V"
					( Units "uVoltage" "V" 1.000000)
					( Origin gFrontEnd )
				)
				( attribute "XY" "(-6675,875)"
					( Origin gFrontEnd )
				)
				( attribute "CHIPS_PART_NAME" "CAP"
					( Origin gPackager )
				)
				( attribute "CDS_PART_NAME" "CAP_0402-0.22UF,16V,10%,X7R,A3A"
					( Origin gPackager )
				)
				( objectStatus "C3P35" )
				( pin "a"
					( attribute "PN" "1"
						( Origin gPackager )
					)
					( objectStatus "C3P35.1" )
				)
				( pin "b"
					( attribute "PN" "2"
						( Origin gPackager )
					)
					( objectStatus "C3P35.2" )
				)
			)
			( gate "@baseboard_fab2_lib.baseboard_fab2(sch_1):page107_i241"
				( attribute "CDS_LIB" "mstr_discrete"
					( Origin gPackager )
				)
				( attribute "CDS_LOCATION" "C3P40"
					( Origin gPackager )
				)
				( attribute "CDS_SEC" "1"
					( Origin gPackager )
				)
				( attribute "LOCATION" "C3P40"
					( Origin gFrontEnd )
				)
				( attribute "MATERIAL" "X7R"
					( Origin gFrontEnd )
				)
				( attribute "PACK_TYPE" "0402"
					( Origin gFrontEnd )
				)
				( attribute "PART_NUMBER" "A36096-155"
					( Origin gFrontEnd )
				)
				( attribute "PHYS_PAGE" "107"
					( Origin gFrontEnd )
				)
				( attribute "ROT" "2"
					( Origin gFrontEnd )
				)
				( attribute "SEC" "1"
					( Origin gPackager )
				)
				( attribute "TOLERANCE" "10%"
					( Origin gFrontEnd )
				)
				( attribute "VALUE" "0.22UF"
					( Origin gFrontEnd )
				)
				( attribute "VER" "1"
					( Origin gFrontEnd )
				)
				( attribute "VOLTAGE" "16V"
					( Units "uVoltage" "V" 1.000000)
					( Origin gFrontEnd )
				)
				( attribute "XY" "(-6925,1575)"
					( Origin gFrontEnd )
				)
				( attribute "CHIPS_PART_NAME" "CAP"
					( Origin gPackager )
				)
				( attribute "CDS_PART_NAME" "CAP_0402-0.22UF,16V,10%,X7R,A3A"
					( Origin gPackager )
				)
				( objectStatus "C3P40" )
				( pin "a"
					( attribute "PN" "1"
						( Origin gPackager )
					)
					( objectStatus "C3P40.1" )
				)
				( pin "b"
					( attribute "PN" "2"
						( Origin gPackager )
					)
					( objectStatus "C3P40.2" )
				)
			)
			( gate "@baseboard_fab2_lib.baseboard_fab2(sch_1):page107_i245"
				( attribute "CDS_LIB" "mstr_discrete"
					( Origin gPackager )
				)
				( attribute "CDS_LOCATION" "C3P30"
					( Origin gPackager )
				)
				( attribute "CDS_SEC" "1"
					( Origin gPackager )
				)
				( attribute "LOCATION" "C3P30"
					( Origin gFrontEnd )
				)
				( attribute "MATERIAL" "X7R"
					( Origin gFrontEnd )
				)
				( attribute "PACK_TYPE" "0402"
					( Origin gFrontEnd )
				)
				( attribute "PART_NUMBER" "A36096-155"
					( Origin gFrontEnd )
				)
				( attribute "PHYS_PAGE" "107"
					( Origin gFrontEnd )
				)
				( attribute "ROT" "2"
					( Origin gFrontEnd )
				)
				( attribute "SEC" "1"
					( Origin gPackager )
				)
				( attribute "TOLERANCE" "10%"
					( Origin gFrontEnd )
				)
				( attribute "VALUE" "0.22UF"
					( Origin gFrontEnd )
				)
				( attribute "VER" "1"
					( Origin gFrontEnd )
				)
				( attribute "VOLTAGE" "16V"
					( Units "uVoltage" "V" 1.000000)
					( Origin gFrontEnd )
				)
				( attribute "XY" "(-6475,575)"
					( Origin gFrontEnd )
				)
				( attribute "CHIPS_PART_NAME" "CAP"
					( Origin gPackager )
				)
				( attribute "CDS_PART_NAME" "CAP_0402-0.22UF,16V,10%,X7R,A3A"
					( Origin gPackager )
				)
				( objectStatus "C3P30" )
				( pin "a"
					( attribute "PN" "1"
						( Origin gPackager )
					)
					( objectStatus "C3P30.1" )
				)
				( pin "b"
					( attribute "PN" "2"
						( Origin gPackager )
					)
					( objectStatus "C3P30.2" )
				)
			)
			( gate "@baseboard_fab2_lib.baseboard_fab2(sch_1):page107_i248"
				( attribute "CDS_LIB" "mstr_discrete"
					( Origin gPackager )
				)
				( attribute "CDS_LOCATION" "C3P39"
					( Origin gPackager )
				)
				( attribute "CDS_SEC" "1"
					( Origin gPackager )
				)
				( attribute "LOCATION" "C3P39"
					( Origin gFrontEnd )
				)
				( attribute "MATERIAL" "X7R"
					( Origin gFrontEnd )
				)
				( attribute "PACK_TYPE" "0402"
					( Origin gFrontEnd )
				)
				( attribute "PART_NUMBER" "A36096-155"
					( Origin gFrontEnd )
				)
				( attribute "PHYS_PAGE" "107"
					( Origin gFrontEnd )
				)
				( attribute "ROT" "2"
					( Origin gFrontEnd )
				)
				( attribute "SEC" "1"
					( Origin gPackager )
				)
				( attribute "TOLERANCE" "10%"
					( Origin gFrontEnd )
				)
				( attribute "VALUE" "0.22UF"
					( Origin gFrontEnd )
				)
				( attribute "VER" "1"
					( Origin gFrontEnd )
				)
				( attribute "VOLTAGE" "16V"
					( Units "uVoltage" "V" 1.000000)
					( Origin gFrontEnd )
				)
				( attribute "XY" "(-6875,575)"
					( Origin gFrontEnd )
				)
				( attribute "CHIPS_PART_NAME" "CAP"
					( Origin gPackager )
				)
				( attribute "CDS_PART_NAME" "CAP_0402-0.22UF,16V,10%,X7R,A3A"
					( Origin gPackager )
				)
				( objectStatus "C3P39" )
				( pin "a"
					( attribute "PN" "1"
						( Origin gPackager )
					)
					( objectStatus "C3P39.1" )
				)
				( pin "b"
					( attribute "PN" "2"
						( Origin gPackager )
					)
					( objectStatus "C3P39.2" )
				)
			)
			( gate "@baseboard_fab2_lib.baseboard_fab2(sch_1):page107_i257"
				( attribute "CDS_LIB" "mstr_discrete"
					( Origin gPackager )
				)
				( attribute "CDS_LOCATION" "C2U4"
					( Origin gPackager )
				)
				( attribute "CDS_SEC" "1"
					( Origin gPackager )
				)
				( attribute "LOCATION" "C2U4"
					( Origin gFrontEnd )
				)
				( attribute "MATERIAL" "X7R"
					( Origin gFrontEnd )
				)
				( attribute "PACK_TYPE" "0402"
					( Origin gFrontEnd )
				)
				( attribute "PART_NUMBER" "A36096-155"
					( Origin gFrontEnd )
				)
				( attribute "PHYS_PAGE" "107"
					( Origin gFrontEnd )
				)
				( attribute "ROT" "2"
					( Origin gFrontEnd )
				)
				( attribute "SEC" "1"
					( Origin gFrontEnd )
				)
				( attribute "SEC_TYPE" "0402"
					( Origin gFrontEnd )
				)
				( attribute "TOLERANCE" "10%"
					( Origin gFrontEnd )
				)
				( attribute "VALUE" "0.22UF"
					( Origin gFrontEnd )
				)
				( attribute "VER" "1"
					( Origin gFrontEnd )
				)
				( attribute "VOLTAGE" "16V"
					( Units "uVoltage" "V" 1.000000)
					( Origin gFrontEnd )
				)
				( attribute "XY" "(-1950,1825)"
					( Origin gFrontEnd )
				)
				( attribute "CHIPS_PART_NAME" "CAP"
					( Origin gPackager )
				)
				( attribute "CDS_PART_NAME" "CAP_0402-0.22UF,16V,10%,X7R,A3A"
					( Origin gPackager )
				)
				( objectStatus "C2U4" )
				( pin "a"
					( attribute "PN" "1"
						( Origin gPackager )
					)
					( objectStatus "C2U4.1" )
				)
				( pin "b"
					( attribute "PN" "2"
						( Origin gPackager )
					)
					( objectStatus "C2U4.2" )
				)
			)
			( gate "@baseboard_fab2_lib.baseboard_fab2(sch_1):page107_i260"
				( attribute "CDS_LIB" "mstr_discrete"
					( Origin gPackager )
				)
				( attribute "CDS_LOCATION" "C2U6"
					( Origin gPackager )
				)
				( attribute "CDS_SEC" "1"
					( Origin gPackager )
				)
				( attribute "LOCATION" "C2U6"
					( Origin gFrontEnd )
				)
				( attribute "MATERIAL" "X7R"
					( Origin gFrontEnd )
				)
				( attribute "PACK_TYPE" "0402"
					( Origin gFrontEnd )
				)
				( attribute "PART_NUMBER" "A36096-155"
					( Origin gFrontEnd )
				)
				( attribute "PHYS_PAGE" "107"
					( Origin gFrontEnd )
				)
				( attribute "ROT" "2"
					( Origin gFrontEnd )
				)
				( attribute "SEC" "1"
					( Origin gFrontEnd )
				)
				( attribute "SEC_TYPE" "0402"
					( Origin gFrontEnd )
				)
				( attribute "TOLERANCE" "10%"
					( Origin gFrontEnd )
				)
				( attribute "VALUE" "0.22UF"
					( Origin gFrontEnd )
				)
				( attribute "VER" "1"
					( Origin gFrontEnd )
				)
				( attribute "VOLTAGE" "16V"
					( Units "uVoltage" "V" 1.000000)
					( Origin gFrontEnd )
				)
				( attribute "XY" "(-2150,1525)"
					( Origin gFrontEnd )
				)
				( attribute "CHIPS_PART_NAME" "CAP"
					( Origin gPackager )
				)
				( attribute "CDS_PART_NAME" "CAP_0402-0.22UF,16V,10%,X7R,A3A"
					( Origin gPackager )
				)
				( objectStatus "C2U6" )
				( pin "a"
					( attribute "PN" "1"
						( Origin gPackager )
					)
					( objectStatus "C2U6.1" )
				)
				( pin "b"
					( attribute "PN" "2"
						( Origin gPackager )
					)
					( objectStatus "C2U6.2" )
				)
			)
			( gate "@baseboard_fab2_lib.baseboard_fab2(sch_1):page107_i264"
				( attribute "CDS_LIB" "mstr_discrete"
					( Origin gPackager )
				)
				( attribute "CDS_LOCATION" "C2U8"
					( Origin gPackager )
				)
				( attribute "CDS_SEC" "1"
					( Origin gPackager )
				)
				( attribute "LOCATION" "C2U8"
					( Origin gFrontEnd )
				)
				( attribute "MATERIAL" "X7R"
					( Origin gFrontEnd )
				)
				( attribute "PACK_TYPE" "0402"
					( Origin gFrontEnd )
				)
				( attribute "PART_NUMBER" "A36096-155"
					( Origin gFrontEnd )
				)
				( attribute "PHYS_PAGE" "107"
					( Origin gFrontEnd )
				)
				( attribute "ROT" "2"
					( Origin gFrontEnd )
				)
				( attribute "SEC" "1"
					( Origin gFrontEnd )
				)
				( attribute "SEC_TYPE" "0402"
					( Origin gFrontEnd )
				)
				( attribute "TOLERANCE" "10%"
					( Origin gFrontEnd )
				)
				( attribute "VALUE" "0.22UF"
					( Origin gFrontEnd )
				)
				( attribute "VER" "1"
					( Origin gFrontEnd )
				)
				( attribute "VOLTAGE" "16V"
					( Units "uVoltage" "V" 1.000000)
					( Origin gFrontEnd )
				)
				( attribute "XY" "(-2350,1825)"
					( Origin gFrontEnd )
				)
				( attribute "CHIPS_PART_NAME" "CAP"
					( Origin gPackager )
				)
				( attribute "CDS_PART_NAME" "CAP_0402-0.22UF,16V,10%,X7R,A3A"
					( Origin gPackager )
				)
				( objectStatus "C2U8" )
				( pin "a"
					( attribute "PN" "1"
						( Origin gPackager )
					)
					( objectStatus "C2U8.1" )
				)
				( pin "b"
					( attribute "PN" "2"
						( Origin gPackager )
					)
					( objectStatus "C2U8.2" )
				)
			)
			( gate "@baseboard_fab2_lib.baseboard_fab2(sch_1):page107_i265"
				( attribute "CDS_LIB" "mstr_discrete"
					( Origin gPackager )
				)
				( attribute "CDS_LOCATION" "C2U12"
					( Origin gPackager )
				)
				( attribute "CDS_SEC" "1"
					( Origin gPackager )
				)
				( attribute "LOCATION" "C2U12"
					( Origin gFrontEnd )
				)
				( attribute "MATERIAL" "X7R"
					( Origin gFrontEnd )
				)
				( attribute "PACK_TYPE" "0402"
					( Origin gFrontEnd )
				)
				( attribute "PART_NUMBER" "A36096-155"
					( Origin gFrontEnd )
				)
				( attribute "PHYS_PAGE" "107"
					( Origin gFrontEnd )
				)
				( attribute "ROT" "2"
					( Origin gFrontEnd )
				)
				( attribute "SEC" "1"
					( Origin gFrontEnd )
				)
				( attribute "SEC_TYPE" "0402"
					( Origin gFrontEnd )
				)
				( attribute "TOLERANCE" "10%"
					( Origin gFrontEnd )
				)
				( attribute "VALUE" "0.22UF"
					( Origin gFrontEnd )
				)
				( attribute "VER" "1"
					( Origin gFrontEnd )
				)
				( attribute "VOLTAGE" "16V"
					( Units "uVoltage" "V" 1.000000)
					( Origin gFrontEnd )
				)
				( attribute "XY" "(-2750,1825)"
					( Origin gFrontEnd )
				)
				( attribute "CHIPS_PART_NAME" "CAP"
					( Origin gPackager )
				)
				( attribute "CDS_PART_NAME" "CAP_0402-0.22UF,16V,10%,X7R,A3A"
					( Origin gPackager )
				)
				( objectStatus "C2U12" )
				( pin "a"
					( attribute "PN" "1"
						( Origin gPackager )
					)
					( objectStatus "C2U12.1" )
				)
				( pin "b"
					( attribute "PN" "2"
						( Origin gPackager )
					)
					( objectStatus "C2U12.2" )
				)
			)
			( gate "@baseboard_fab2_lib.baseboard_fab2(sch_1):page107_i267"
				( attribute "CDS_LIB" "mstr_discrete"
					( Origin gPackager )
				)
				( attribute "CDS_LOCATION" "C2U10"
					( Origin gPackager )
				)
				( attribute "CDS_SEC" "1"
					( Origin gPackager )
				)
				( attribute "LOCATION" "C2U10"
					( Origin gFrontEnd )
				)
				( attribute "MATERIAL" "X7R"
					( Origin gFrontEnd )
				)
				( attribute "PACK_TYPE" "0402"
					( Origin gFrontEnd )
				)
				( attribute "PART_NUMBER" "A36096-155"
					( Origin gFrontEnd )
				)
				( attribute "PHYS_PAGE" "107"
					( Origin gFrontEnd )
				)
				( attribute "ROT" "2"
					( Origin gFrontEnd )
				)
				( attribute "SEC" "1"
					( Origin gFrontEnd )
				)
				( attribute "SEC_TYPE" "0402"
					( Origin gFrontEnd )
				)
				( attribute "TOLERANCE" "10%"
					( Origin gFrontEnd )
				)
				( attribute "VALUE" "0.22UF"
					( Origin gFrontEnd )
				)
				( attribute "VER" "1"
					( Origin gFrontEnd )
				)
				( attribute "VOLTAGE" "16V"
					( Units "uVoltage" "V" 1.000000)
					( Origin gFrontEnd )
				)
				( attribute "XY" "(-2550,1525)"
					( Origin gFrontEnd )
				)
				( attribute "CHIPS_PART_NAME" "CAP"
					( Origin gPackager )
				)
				( attribute "CDS_PART_NAME" "CAP_0402-0.22UF,16V,10%,X7R,A3A"
					( Origin gPackager )
				)
				( objectStatus "C2U10" )
				( pin "a"
					( attribute "PN" "1"
						( Origin gPackager )
					)
					( objectStatus "C2U10.1" )
				)
				( pin "b"
					( attribute "PN" "2"
						( Origin gPackager )
					)
					( objectStatus "C2U10.2" )
				)
			)
			( gate "@baseboard_fab2_lib.baseboard_fab2(sch_1):page107_i272"
				( attribute "CDS_LIB" "mstr_discrete"
					( Origin gPackager )
				)
				( attribute "CDS_LOCATION" "C2U3"
					( Origin gPackager )
				)
				( attribute "CDS_SEC" "1"
					( Origin gPackager )
				)
				( attribute "LOCATION" "C2U3"
					( Origin gFrontEnd )
				)
				( attribute "MATERIAL" "X7R"
					( Origin gFrontEnd )
				)
				( attribute "PACK_TYPE" "0402"
					( Origin gFrontEnd )
				)
				( attribute "PART_NUMBER" "A36096-155"
					( Origin gFrontEnd )
				)
				( attribute "PHYS_PAGE" "107"
					( Origin gFrontEnd )
				)
				( attribute "ROT" "2"
					( Origin gFrontEnd )
				)
				( attribute "SEC" "1"
					( Origin gFrontEnd )
				)
				( attribute "SEC_TYPE" "0402"
					( Origin gFrontEnd )
				)
				( attribute "TOLERANCE" "10%"
					( Origin gFrontEnd )
				)
				( attribute "VALUE" "0.22UF"
					( Origin gFrontEnd )
				)
				( attribute "VER" "1"
					( Origin gFrontEnd )
				)
				( attribute "VOLTAGE" "16V"
					( Units "uVoltage" "V" 1.000000)
					( Origin gFrontEnd )
				)
				( attribute "XY" "(-1900,825)"
					( Origin gFrontEnd )
				)
				( attribute "CHIPS_PART_NAME" "CAP"
					( Origin gPackager )
				)
				( attribute "CDS_PART_NAME" "CAP_0402-0.22UF,16V,10%,X7R,A3A"
					( Origin gPackager )
				)
				( objectStatus "C2U3" )
				( pin "a"
					( attribute "PN" "1"
						( Origin gPackager )
					)
					( objectStatus "C2U3.1" )
				)
				( pin "b"
					( attribute "PN" "2"
						( Origin gPackager )
					)
					( objectStatus "C2U3.2" )
				)
			)
			( gate "@baseboard_fab2_lib.baseboard_fab2(sch_1):page107_i274"
				( attribute "CDS_LIB" "mstr_discrete"
					( Origin gPackager )
				)
				( attribute "CDS_LOCATION" "C2U5"
					( Origin gPackager )
				)
				( attribute "CDS_SEC" "1"
					( Origin gPackager )
				)
				( attribute "LOCATION" "C2U5"
					( Origin gFrontEnd )
				)
				( attribute "MATERIAL" "X7R"
					( Origin gFrontEnd )
				)
				( attribute "PACK_TYPE" "0402"
					( Origin gFrontEnd )
				)
				( attribute "PART_NUMBER" "A36096-155"
					( Origin gFrontEnd )
				)
				( attribute "PHYS_PAGE" "107"
					( Origin gFrontEnd )
				)
				( attribute "ROT" "2"
					( Origin gFrontEnd )
				)
				( attribute "SEC" "1"
					( Origin gFrontEnd )
				)
				( attribute "SEC_TYPE" "0402"
					( Origin gFrontEnd )
				)
				( attribute "TOLERANCE" "10%"
					( Origin gFrontEnd )
				)
				( attribute "VALUE" "0.22UF"
					( Origin gFrontEnd )
				)
				( attribute "VER" "1"
					( Origin gFrontEnd )
				)
				( attribute "VOLTAGE" "16V"
					( Units "uVoltage" "V" 1.000000)
					( Origin gFrontEnd )
				)
				( attribute "XY" "(-2100,525)"
					( Origin gFrontEnd )
				)
				( attribute "CHIPS_PART_NAME" "CAP"
					( Origin gPackager )
				)
				( attribute "CDS_PART_NAME" "CAP_0402-0.22UF,16V,10%,X7R,A3A"
					( Origin gPackager )
				)
				( objectStatus "C2U5" )
				( pin "a"
					( attribute "PN" "1"
						( Origin gPackager )
					)
					( objectStatus "C2U5.1" )
				)
				( pin "b"
					( attribute "PN" "2"
						( Origin gPackager )
					)
					( objectStatus "C2U5.2" )
				)
			)
			( gate "@baseboard_fab2_lib.baseboard_fab2(sch_1):page107_i277"
				( attribute "CDS_LIB" "mstr_discrete"
					( Origin gPackager )
				)
				( attribute "CDS_LOCATION" "C2U7"
					( Origin gPackager )
				)
				( attribute "CDS_SEC" "1"
					( Origin gPackager )
				)
				( attribute "LOCATION" "C2U7"
					( Origin gFrontEnd )
				)
				( attribute "MATERIAL" "X7R"
					( Origin gFrontEnd )
				)
				( attribute "PACK_TYPE" "0402"
					( Origin gFrontEnd )
				)
				( attribute "PART_NUMBER" "A36096-155"
					( Origin gFrontEnd )
				)
				( attribute "PHYS_PAGE" "107"
					( Origin gFrontEnd )
				)
				( attribute "ROT" "2"
					( Origin gFrontEnd )
				)
				( attribute "SEC" "1"
					( Origin gFrontEnd )
				)
				( attribute "SEC_TYPE" "0402"
					( Origin gFrontEnd )
				)
				( attribute "TOLERANCE" "10%"
					( Origin gFrontEnd )
				)
				( attribute "VALUE" "0.22UF"
					( Origin gFrontEnd )
				)
				( attribute "VER" "1"
					( Origin gFrontEnd )
				)
				( attribute "VOLTAGE" "16V"
					( Units "uVoltage" "V" 1.000000)
					( Origin gFrontEnd )
				)
				( attribute "XY" "(-2300,825)"
					( Origin gFrontEnd )
				)
				( attribute "CHIPS_PART_NAME" "CAP"
					( Origin gPackager )
				)
				( attribute "CDS_PART_NAME" "CAP_0402-0.22UF,16V,10%,X7R,A3A"
					( Origin gPackager )
				)
				( objectStatus "C2U7" )
				( pin "a"
					( attribute "PN" "1"
						( Origin gPackager )
					)
					( objectStatus "C2U7.1" )
				)
				( pin "b"
					( attribute "PN" "2"
						( Origin gPackager )
					)
					( objectStatus "C2U7.2" )
				)
			)
			( gate "@baseboard_fab2_lib.baseboard_fab2(sch_1):page107_i278"
				( attribute "CDS_LIB" "mstr_discrete"
					( Origin gPackager )
				)
				( attribute "CDS_LOCATION" "C2U11"
					( Origin gPackager )
				)
				( attribute "CDS_SEC" "1"
					( Origin gPackager )
				)
				( attribute "LOCATION" "C2U11"
					( Origin gFrontEnd )
				)
				( attribute "MATERIAL" "X7R"
					( Origin gFrontEnd )
				)
				( attribute "PACK_TYPE" "0402"
					( Origin gFrontEnd )
				)
				( attribute "PART_NUMBER" "A36096-155"
					( Origin gFrontEnd )
				)
				( attribute "PHYS_PAGE" "107"
					( Origin gFrontEnd )
				)
				( attribute "ROT" "2"
					( Origin gFrontEnd )
				)
				( attribute "SEC" "1"
					( Origin gFrontEnd )
				)
				( attribute "SEC_TYPE" "0402"
					( Origin gFrontEnd )
				)
				( attribute "TOLERANCE" "10%"
					( Origin gFrontEnd )
				)
				( attribute "VALUE" "0.22UF"
					( Origin gFrontEnd )
				)
				( attribute "VER" "1"
					( Origin gFrontEnd )
				)
				( attribute "VOLTAGE" "16V"
					( Units "uVoltage" "V" 1.000000)
					( Origin gFrontEnd )
				)
				( attribute "XY" "(-2700,825)"
					( Origin gFrontEnd )
				)
				( attribute "CHIPS_PART_NAME" "CAP"
					( Origin gPackager )
				)
				( attribute "CDS_PART_NAME" "CAP_0402-0.22UF,16V,10%,X7R,A3A"
					( Origin gPackager )
				)
				( objectStatus "C2U11" )
				( pin "a"
					( attribute "PN" "1"
						( Origin gPackager )
					)
					( objectStatus "C2U11.1" )
				)
				( pin "b"
					( attribute "PN" "2"
						( Origin gPackager )
					)
					( objectStatus "C2U11.2" )
				)
			)
			( gate "@baseboard_fab2_lib.baseboard_fab2(sch_1):page107_i279"
				( attribute "CDS_LIB" "mstr_discrete"
					( Origin gPackager )
				)
				( attribute "CDS_LOCATION" "C2U9"
					( Origin gPackager )
				)
				( attribute "CDS_SEC" "1"
					( Origin gPackager )
				)
				( attribute "LOCATION" "C2U9"
					( Origin gFrontEnd )
				)
				( attribute "MATERIAL" "X7R"
					( Origin gFrontEnd )
				)
				( attribute "PACK_TYPE" "0402"
					( Origin gFrontEnd )
				)
				( attribute "PART_NUMBER" "A36096-155"
					( Origin gFrontEnd )
				)
				( attribute "PHYS_PAGE" "107"
					( Origin gFrontEnd )
				)
				( attribute "ROT" "2"
					( Origin gFrontEnd )
				)
				( attribute "SEC" "1"
					( Origin gFrontEnd )
				)
				( attribute "SEC_TYPE" "0402"
					( Origin gFrontEnd )
				)
				( attribute "TOLERANCE" "10%"
					( Origin gFrontEnd )
				)
				( attribute "VALUE" "0.22UF"
					( Origin gFrontEnd )
				)
				( attribute "VER" "1"
					( Origin gFrontEnd )
				)
				( attribute "VOLTAGE" "16V"
					( Units "uVoltage" "V" 1.000000)
					( Origin gFrontEnd )
				)
				( attribute "XY" "(-2500,525)"
					( Origin gFrontEnd )
				)
				( attribute "CHIPS_PART_NAME" "CAP"
					( Origin gPackager )
				)
				( attribute "CDS_PART_NAME" "CAP_0402-0.22UF,16V,10%,X7R,A3A"
					( Origin gPackager )
				)
				( objectStatus "C2U9" )
				( pin "a"
					( attribute "PN" "1"
						( Origin gPackager )
					)
					( objectStatus "C2U9.1" )
				)
				( pin "b"
					( attribute "PN" "2"
						( Origin gPackager )
					)
					( objectStatus "C2U9.2" )
				)
			)
			( gate "@baseboard_fab2_lib.baseboard_fab2(sch_1):page107_i286"
				( attribute "CDS_LIB" "mstr_discrete"
					( Origin gPackager )
				)
				( attribute "CDS_LOCATION" "C2U16"
					( Origin gPackager )
				)
				( attribute "CDS_SEC" "1"
					( Origin gPackager )
				)
				( attribute "LOCATION" "C2U16"
					( Origin gFrontEnd )
				)
				( attribute "MATERIAL" "X7R"
					( Origin gFrontEnd )
				)
				( attribute "PACK_TYPE" "0402"
					( Origin gFrontEnd )
				)
				( attribute "PART_NUMBER" "A36096-155"
					( Origin gFrontEnd )
				)
				( attribute "PHYS_PAGE" "107"
					( Origin gFrontEnd )
				)
				( attribute "ROT" "2"
					( Origin gFrontEnd )
				)
				( attribute "SEC" "1"
					( Origin gFrontEnd )
				)
				( attribute "SEC_TYPE" "0402"
					( Origin gFrontEnd )
				)
				( attribute "TOLERANCE" "10%"
					( Origin gFrontEnd )
				)
				( attribute "VALUE" "0.22UF"
					( Origin gFrontEnd )
				)
				( attribute "VER" "1"
					( Origin gFrontEnd )
				)
				( attribute "VOLTAGE" "16V"
					( Units "uVoltage" "V" 1.000000)
					( Origin gFrontEnd )
				)
				( attribute "XY" "(-3150,1825)"
					( Origin gFrontEnd )
				)
				( attribute "CHIPS_PART_NAME" "CAP"
					( Origin gPackager )
				)
				( attribute "CDS_PART_NAME" "CAP_0402-0.22UF,16V,10%,X7R,A3A"
					( Origin gPackager )
				)
				( objectStatus "C2U16" )
				( pin "a"
					( attribute "PN" "1"
						( Origin gPackager )
					)
					( objectStatus "C2U16.1" )
				)
				( pin "b"
					( attribute "PN" "2"
						( Origin gPackager )
					)
					( objectStatus "C2U16.2" )
				)
			)
			( gate "@baseboard_fab2_lib.baseboard_fab2(sch_1):page107_i287"
				( attribute "CDS_LIB" "mstr_discrete"
					( Origin gPackager )
				)
				( attribute "CDS_LOCATION" "C2U14"
					( Origin gPackager )
				)
				( attribute "CDS_SEC" "1"
					( Origin gPackager )
				)
				( attribute "LOCATION" "C2U14"
					( Origin gFrontEnd )
				)
				( attribute "MATERIAL" "X7R"
					( Origin gFrontEnd )
				)
				( attribute "PACK_TYPE" "0402"
					( Origin gFrontEnd )
				)
				( attribute "PART_NUMBER" "A36096-155"
					( Origin gFrontEnd )
				)
				( attribute "PHYS_PAGE" "107"
					( Origin gFrontEnd )
				)
				( attribute "ROT" "2"
					( Origin gFrontEnd )
				)
				( attribute "SEC" "1"
					( Origin gFrontEnd )
				)
				( attribute "SEC_TYPE" "0402"
					( Origin gFrontEnd )
				)
				( attribute "TOLERANCE" "10%"
					( Origin gFrontEnd )
				)
				( attribute "VALUE" "0.22UF"
					( Origin gFrontEnd )
				)
				( attribute "VER" "1"
					( Origin gFrontEnd )
				)
				( attribute "VOLTAGE" "16V"
					( Units "uVoltage" "V" 1.000000)
					( Origin gFrontEnd )
				)
				( attribute "XY" "(-2950,1525)"
					( Origin gFrontEnd )
				)
				( attribute "CHIPS_PART_NAME" "CAP"
					( Origin gPackager )
				)
				( attribute "CDS_PART_NAME" "CAP_0402-0.22UF,16V,10%,X7R,A3A"
					( Origin gPackager )
				)
				( objectStatus "C2U14" )
				( pin "a"
					( attribute "PN" "1"
						( Origin gPackager )
					)
					( objectStatus "C2U14.1" )
				)
				( pin "b"
					( attribute "PN" "2"
						( Origin gPackager )
					)
					( objectStatus "C2U14.2" )
				)
			)
			( gate "@baseboard_fab2_lib.baseboard_fab2(sch_1):page107_i294"
				( attribute "CDS_LIB" "mstr_discrete"
					( Origin gPackager )
				)
				( attribute "CDS_LOCATION" "C2U18"
					( Origin gPackager )
				)
				( attribute "CDS_SEC" "1"
					( Origin gPackager )
				)
				( attribute "LOCATION" "C2U18"
					( Origin gFrontEnd )
				)
				( attribute "MATERIAL" "X7R"
					( Origin gFrontEnd )
				)
				( attribute "PACK_TYPE" "0402"
					( Origin gFrontEnd )
				)
				( attribute "PART_NUMBER" "A36096-155"
					( Origin gFrontEnd )
				)
				( attribute "PHYS_PAGE" "107"
					( Origin gFrontEnd )
				)
				( attribute "ROT" "2"
					( Origin gFrontEnd )
				)
				( attribute "SEC" "1"
					( Origin gFrontEnd )
				)
				( attribute "SEC_TYPE" "0402"
					( Origin gFrontEnd )
				)
				( attribute "TOLERANCE" "10%"
					( Origin gFrontEnd )
				)
				( attribute "VALUE" "0.22UF"
					( Origin gFrontEnd )
				)
				( attribute "VER" "1"
					( Origin gFrontEnd )
				)
				( attribute "VOLTAGE" "16V"
					( Units "uVoltage" "V" 1.000000)
					( Origin gFrontEnd )
				)
				( attribute "XY" "(-3350,1525)"
					( Origin gFrontEnd )
				)
				( attribute "CHIPS_PART_NAME" "CAP"
					( Origin gPackager )
				)
				( attribute "CDS_PART_NAME" "CAP_0402-0.22UF,16V,10%,X7R,A3A"
					( Origin gPackager )
				)
				( objectStatus "C2U18" )
				( pin "a"
					( attribute "PN" "1"
						( Origin gPackager )
					)
					( objectStatus "C2U18.1" )
				)
				( pin "b"
					( attribute "PN" "2"
						( Origin gPackager )
					)
					( objectStatus "C2U18.2" )
				)
			)
			( gate "@baseboard_fab2_lib.baseboard_fab2(sch_1):page107_i296"
				( attribute "CDS_LIB" "mstr_discrete"
					( Origin gPackager )
				)
				( attribute "CDS_LOCATION" "C2U15"
					( Origin gPackager )
				)
				( attribute "CDS_SEC" "1"
					( Origin gPackager )
				)
				( attribute "LOCATION" "C2U15"
					( Origin gFrontEnd )
				)
				( attribute "MATERIAL" "X7R"
					( Origin gFrontEnd )
				)
				( attribute "PACK_TYPE" "0402"
					( Origin gFrontEnd )
				)
				( attribute "PART_NUMBER" "A36096-155"
					( Origin gFrontEnd )
				)
				( attribute "PHYS_PAGE" "107"
					( Origin gFrontEnd )
				)
				( attribute "ROT" "2"
					( Origin gFrontEnd )
				)
				( attribute "SEC" "1"
					( Origin gFrontEnd )
				)
				( attribute "SEC_TYPE" "0402"
					( Origin gFrontEnd )
				)
				( attribute "TOLERANCE" "10%"
					( Origin gFrontEnd )
				)
				( attribute "VALUE" "0.22UF"
					( Origin gFrontEnd )
				)
				( attribute "VER" "1"
					( Origin gFrontEnd )
				)
				( attribute "VOLTAGE" "16V"
					( Units "uVoltage" "V" 1.000000)
					( Origin gFrontEnd )
				)
				( attribute "XY" "(-3100,825)"
					( Origin gFrontEnd )
				)
				( attribute "CHIPS_PART_NAME" "CAP"
					( Origin gPackager )
				)
				( attribute "CDS_PART_NAME" "CAP_0402-0.22UF,16V,10%,X7R,A3A"
					( Origin gPackager )
				)
				( objectStatus "C2U15" )
				( pin "a"
					( attribute "PN" "1"
						( Origin gPackager )
					)
					( objectStatus "C2U15.1" )
				)
				( pin "b"
					( attribute "PN" "2"
						( Origin gPackager )
					)
					( objectStatus "C2U15.2" )
				)
			)
			( gate "@baseboard_fab2_lib.baseboard_fab2(sch_1):page107_i297"
				( attribute "CDS_LIB" "mstr_discrete"
					( Origin gPackager )
				)
				( attribute "CDS_LOCATION" "C2U13"
					( Origin gPackager )
				)
				( attribute "CDS_SEC" "1"
					( Origin gPackager )
				)
				( attribute "LOCATION" "C2U13"
					( Origin gFrontEnd )
				)
				( attribute "MATERIAL" "X7R"
					( Origin gFrontEnd )
				)
				( attribute "PACK_TYPE" "0402"
					( Origin gFrontEnd )
				)
				( attribute "PART_NUMBER" "A36096-155"
					( Origin gFrontEnd )
				)
				( attribute "PHYS_PAGE" "107"
					( Origin gFrontEnd )
				)
				( attribute "ROT" "2"
					( Origin gFrontEnd )
				)
				( attribute "SEC" "1"
					( Origin gFrontEnd )
				)
				( attribute "SEC_TYPE" "0402"
					( Origin gFrontEnd )
				)
				( attribute "TOLERANCE" "10%"
					( Origin gFrontEnd )
				)
				( attribute "VALUE" "0.22UF"
					( Origin gFrontEnd )
				)
				( attribute "VER" "1"
					( Origin gFrontEnd )
				)
				( attribute "VOLTAGE" "16V"
					( Units "uVoltage" "V" 1.000000)
					( Origin gFrontEnd )
				)
				( attribute "XY" "(-2900,525)"
					( Origin gFrontEnd )
				)
				( attribute "CHIPS_PART_NAME" "CAP"
					( Origin gPackager )
				)
				( attribute "CDS_PART_NAME" "CAP_0402-0.22UF,16V,10%,X7R,A3A"
					( Origin gPackager )
				)
				( objectStatus "C2U13" )
				( pin "a"
					( attribute "PN" "1"
						( Origin gPackager )
					)
					( objectStatus "C2U13.1" )
				)
				( pin "b"
					( attribute "PN" "2"
						( Origin gPackager )
					)
					( objectStatus "C2U13.2" )
				)
			)
			( gate "@baseboard_fab2_lib.baseboard_fab2(sch_1):page107_i300"
				( attribute "CDS_LIB" "mstr_discrete"
					( Origin gPackager )
				)
				( attribute "CDS_LOCATION" "C2U17"
					( Origin gPackager )
				)
				( attribute "CDS_SEC" "1"
					( Origin gPackager )
				)
				( attribute "LOCATION" "C2U17"
					( Origin gFrontEnd )
				)
				( attribute "MATERIAL" "X7R"
					( Origin gFrontEnd )
				)
				( attribute "PACK_TYPE" "0402"
					( Origin gFrontEnd )
				)
				( attribute "PART_NUMBER" "A36096-155"
					( Origin gFrontEnd )
				)
				( attribute "PHYS_PAGE" "107"
					( Origin gFrontEnd )
				)
				( attribute "ROT" "2"
					( Origin gFrontEnd )
				)
				( attribute "SEC" "1"
					( Origin gFrontEnd )
				)
				( attribute "SEC_TYPE" "0402"
					( Origin gFrontEnd )
				)
				( attribute "TOLERANCE" "10%"
					( Origin gFrontEnd )
				)
				( attribute "VALUE" "0.22UF"
					( Origin gFrontEnd )
				)
				( attribute "VER" "1"
					( Origin gFrontEnd )
				)
				( attribute "VOLTAGE" "16V"
					( Units "uVoltage" "V" 1.000000)
					( Origin gFrontEnd )
				)
				( attribute "XY" "(-3300,525)"
					( Origin gFrontEnd )
				)
				( attribute "CHIPS_PART_NAME" "CAP"
					( Origin gPackager )
				)
				( attribute "CDS_PART_NAME" "CAP_0402-0.22UF,16V,10%,X7R,A3A"
					( Origin gPackager )
				)
				( objectStatus "C2U17" )
				( pin "a"
					( attribute "PN" "1"
						( Origin gPackager )
					)
					( objectStatus "C2U17.1" )
				)
				( pin "b"
					( attribute "PN" "2"
						( Origin gPackager )
					)
					( objectStatus "C2U17.2" )
				)
			)
			( gate "@baseboard_fab2_lib.baseboard_fab2(sch_1):page107_i415"
				( attribute "CDS_LIB" "mstr_discrete"
					( Origin gPackager )
				)
				( attribute "CDS_LOCATION" "C3P12"
					( Origin gPackager )
				)
				( attribute "CDS_SEC" "1"
					( Origin gPackager )
				)
				( attribute "LOCATION" "C3P12"
					( Origin gFrontEnd )
				)
				( attribute "MATERIAL" "EMPTY"
					( Origin gFrontEnd )
				)
				( attribute "PACK_TYPE" "0402"
					( Origin gFrontEnd )
				)
				( attribute "PART_NUMBER" "A36096-155"
					( Origin gFrontEnd )
				)
				( attribute "PHYS_PAGE" "107"
					( Origin gFrontEnd )
				)
				( attribute "ROT" "2"
					( Origin gFrontEnd )
				)
				( attribute "SEC" "1"
					( Origin gPackager )
				)
				( attribute "TOLERANCE" "10%"
					( Origin gFrontEnd )
				)
				( attribute "VALUE" "0.22UF"
					( Origin gFrontEnd )
				)
				( attribute "VER" "1"
					( Origin gFrontEnd )
				)
				( attribute "VOLTAGE" "16V"
					( Units "uVoltage" "V" 1.000000)
					( Origin gFrontEnd )
				)
				( attribute "XY" "(-4300,3975)"
					( Origin gFrontEnd )
				)
				( attribute "CHIPS_PART_NAME" "CAP"
					( Origin gPackager )
				)
				( attribute "CDS_PART_NAME" "CAP_0402-0.22UF,16V,10%,EMPTY,A"
					( Origin gPackager )
				)
				( objectStatus "C3P12" )
				( pin "a"
					( attribute "PN" "1"
						( Origin gPackager )
					)
					( objectStatus "C3P12.1" )
				)
				( pin "b"
					( attribute "PN" "2"
						( Origin gPackager )
					)
					( objectStatus "C3P12.2" )
				)
			)
			( gate "@baseboard_fab2_lib.baseboard_fab2(sch_1):page107_i417"
				( attribute "CDS_LIB" "mstr_discrete"
					( Origin gPackager )
				)
				( attribute "CDS_LOCATION" "C3P10"
					( Origin gPackager )
				)
				( attribute "CDS_SEC" "1"
					( Origin gPackager )
				)
				( attribute "LOCATION" "C3P10"
					( Origin gFrontEnd )
				)
				( attribute "MATERIAL" "EMPTY"
					( Origin gFrontEnd )
				)
				( attribute "PACK_TYPE" "0402"
					( Origin gFrontEnd )
				)
				( attribute "PART_NUMBER" "A36096-155"
					( Origin gFrontEnd )
				)
				( attribute "PHYS_PAGE" "107"
					( Origin gFrontEnd )
				)
				( attribute "ROT" "2"
					( Origin gFrontEnd )
				)
				( attribute "SEC" "1"
					( Origin gPackager )
				)
				( attribute "TOLERANCE" "10%"
					( Origin gFrontEnd )
				)
				( attribute "VALUE" "0.22UF"
					( Origin gFrontEnd )
				)
				( attribute "VER" "1"
					( Origin gFrontEnd )
				)
				( attribute "VOLTAGE" "16V"
					( Units "uVoltage" "V" 1.000000)
					( Origin gFrontEnd )
				)
				( attribute "XY" "(-4250,2975)"
					( Origin gFrontEnd )
				)
				( attribute "CHIPS_PART_NAME" "CAP"
					( Origin gPackager )
				)
				( attribute "CDS_PART_NAME" "CAP_0402-0.22UF,16V,10%,EMPTY,A"
					( Origin gPackager )
				)
				( objectStatus "C3P10" )
				( pin "a"
					( attribute "PN" "1"
						( Origin gPackager )
					)
					( objectStatus "C3P10.1" )
				)
				( pin "b"
					( attribute "PN" "2"
						( Origin gPackager )
					)
					( objectStatus "C3P10.2" )
				)
			)
			( gate "@baseboard_fab2_lib.baseboard_fab2(sch_1):page107_i422"
				( attribute "CDS_LIB" "mstr_discrete"
					( Origin gPackager )
				)
				( attribute "CDS_LOCATION" "C3P16"
					( Origin gPackager )
				)
				( attribute "CDS_SEC" "1"
					( Origin gPackager )
				)
				( attribute "LOCATION" "C3P16"
					( Origin gFrontEnd )
				)
				( attribute "MATERIAL" "EMPTY"
					( Origin gFrontEnd )
				)
				( attribute "PACK_TYPE" "0402"
					( Origin gFrontEnd )
				)
				( attribute "PART_NUMBER" "A36096-155"
					( Origin gFrontEnd )
				)
				( attribute "PHYS_PAGE" "107"
					( Origin gFrontEnd )
				)
				( attribute "ROT" "2"
					( Origin gFrontEnd )
				)
				( attribute "SEC" "1"
					( Origin gPackager )
				)
				( attribute "TOLERANCE" "10%"
					( Origin gFrontEnd )
				)
				( attribute "VALUE" "0.22UF"
					( Origin gFrontEnd )
				)
				( attribute "VER" "1"
					( Origin gFrontEnd )
				)
				( attribute "VOLTAGE" "16V"
					( Units "uVoltage" "V" 1.000000)
					( Origin gFrontEnd )
				)
				( attribute "XY" "(-4500,3700)"
					( Origin gFrontEnd )
				)
				( attribute "CHIPS_PART_NAME" "CAP"
					( Origin gPackager )
				)
				( attribute "CDS_PART_NAME" "CAP_0402-0.22UF,16V,10%,EMPTY,A"
					( Origin gPackager )
				)
				( objectStatus "C3P16" )
				( pin "a"
					( attribute "PN" "1"
						( Origin gPackager )
					)
					( objectStatus "C3P16.1" )
				)
				( pin "b"
					( attribute "PN" "2"
						( Origin gPackager )
					)
					( objectStatus "C3P16.2" )
				)
			)
			( gate "@baseboard_fab2_lib.baseboard_fab2(sch_1):page107_i423"
				( attribute "CDS_LIB" "mstr_discrete"
					( Origin gPackager )
				)
				( attribute "CDS_LOCATION" "C3P21"
					( Origin gPackager )
				)
				( attribute "CDS_SEC" "1"
					( Origin gPackager )
				)
				( attribute "LOCATION" "C3P21"
					( Origin gFrontEnd )
				)
				( attribute "MATERIAL" "EMPTY"
					( Origin gFrontEnd )
				)
				( attribute "PACK_TYPE" "0402"
					( Origin gFrontEnd )
				)
				( attribute "PART_NUMBER" "A36096-155"
					( Origin gFrontEnd )
				)
				( attribute "PHYS_PAGE" "107"
					( Origin gFrontEnd )
				)
				( attribute "ROT" "2"
					( Origin gFrontEnd )
				)
				( attribute "SEC" "1"
					( Origin gPackager )
				)
				( attribute "TOLERANCE" "10%"
					( Origin gFrontEnd )
				)
				( attribute "VALUE" "0.22UF"
					( Origin gFrontEnd )
				)
				( attribute "VER" "1"
					( Origin gFrontEnd )
				)
				( attribute "VOLTAGE" "16V"
					( Units "uVoltage" "V" 1.000000)
					( Origin gFrontEnd )
				)
				( attribute "XY" "(-4700,3975)"
					( Origin gFrontEnd )
				)
				( attribute "CHIPS_PART_NAME" "CAP"
					( Origin gPackager )
				)
				( attribute "CDS_PART_NAME" "CAP_0402-0.22UF,16V,10%,EMPTY,A"
					( Origin gPackager )
				)
				( objectStatus "C3P21" )
				( pin "a"
					( attribute "PN" "1"
						( Origin gPackager )
					)
					( objectStatus "C3P21.1" )
				)
				( pin "b"
					( attribute "PN" "2"
						( Origin gPackager )
					)
					( objectStatus "C3P21.2" )
				)
			)
			( gate "@baseboard_fab2_lib.baseboard_fab2(sch_1):page107_i424"
				( attribute "CDS_LIB" "mstr_discrete"
					( Origin gPackager )
				)
				( attribute "CDS_LOCATION" "C3P24"
					( Origin gPackager )
				)
				( attribute "CDS_SEC" "1"
					( Origin gPackager )
				)
				( attribute "LOCATION" "C3P24"
					( Origin gFrontEnd )
				)
				( attribute "MATERIAL" "EMPTY"
					( Origin gFrontEnd )
				)
				( attribute "PACK_TYPE" "0402"
					( Origin gFrontEnd )
				)
				( attribute "PART_NUMBER" "A36096-155"
					( Origin gFrontEnd )
				)
				( attribute "PHYS_PAGE" "107"
					( Origin gFrontEnd )
				)
				( attribute "ROT" "2"
					( Origin gFrontEnd )
				)
				( attribute "SEC" "1"
					( Origin gPackager )
				)
				( attribute "TOLERANCE" "10%"
					( Origin gFrontEnd )
				)
				( attribute "VALUE" "0.22UF"
					( Origin gFrontEnd )
				)
				( attribute "VER" "1"
					( Origin gFrontEnd )
				)
				( attribute "VOLTAGE" "16V"
					( Units "uVoltage" "V" 1.000000)
					( Origin gFrontEnd )
				)
				( attribute "XY" "(-4900,3675)"
					( Origin gFrontEnd )
				)
				( attribute "CHIPS_PART_NAME" "CAP"
					( Origin gPackager )
				)
				( attribute "CDS_PART_NAME" "CAP_0402-0.22UF,16V,10%,EMPTY,A"
					( Origin gPackager )
				)
				( objectStatus "C3P24" )
				( pin "a"
					( attribute "PN" "1"
						( Origin gPackager )
					)
					( objectStatus "C3P24.1" )
				)
				( pin "b"
					( attribute "PN" "2"
						( Origin gPackager )
					)
					( objectStatus "C3P24.2" )
				)
			)
			( gate "@baseboard_fab2_lib.baseboard_fab2(sch_1):page107_i427"
				( attribute "CDS_LIB" "mstr_discrete"
					( Origin gPackager )
				)
				( attribute "CDS_LOCATION" "C3P19"
					( Origin gPackager )
				)
				( attribute "CDS_SEC" "1"
					( Origin gPackager )
				)
				( attribute "LOCATION" "C3P19"
					( Origin gFrontEnd )
				)
				( attribute "MATERIAL" "EMPTY"
					( Origin gFrontEnd )
				)
				( attribute "PACK_TYPE" "0402"
					( Origin gFrontEnd )
				)
				( attribute "PART_NUMBER" "A36096-155"
					( Origin gFrontEnd )
				)
				( attribute "PHYS_PAGE" "107"
					( Origin gFrontEnd )
				)
				( attribute "ROT" "2"
					( Origin gFrontEnd )
				)
				( attribute "SEC" "1"
					( Origin gPackager )
				)
				( attribute "TOLERANCE" "10%"
					( Origin gFrontEnd )
				)
				( attribute "VALUE" "0.22UF"
					( Origin gFrontEnd )
				)
				( attribute "VER" "1"
					( Origin gFrontEnd )
				)
				( attribute "VOLTAGE" "16V"
					( Units "uVoltage" "V" 1.000000)
					( Origin gFrontEnd )
				)
				( attribute "XY" "(-4650,2975)"
					( Origin gFrontEnd )
				)
				( attribute "CHIPS_PART_NAME" "CAP"
					( Origin gPackager )
				)
				( attribute "CDS_PART_NAME" "CAP_0402-0.22UF,16V,10%,EMPTY,A"
					( Origin gPackager )
				)
				( objectStatus "C3P19" )
				( pin "a"
					( attribute "PN" "1"
						( Origin gPackager )
					)
					( objectStatus "C3P19.1" )
				)
				( pin "b"
					( attribute "PN" "2"
						( Origin gPackager )
					)
					( objectStatus "C3P19.2" )
				)
			)
			( gate "@baseboard_fab2_lib.baseboard_fab2(sch_1):page107_i431"
				( attribute "CDS_LIB" "mstr_discrete"
					( Origin gPackager )
				)
				( attribute "CDS_LOCATION" "C3P14"
					( Origin gPackager )
				)
				( attribute "CDS_SEC" "1"
					( Origin gPackager )
				)
				( attribute "LOCATION" "C3P14"
					( Origin gFrontEnd )
				)
				( attribute "MATERIAL" "EMPTY"
					( Origin gFrontEnd )
				)
				( attribute "PACK_TYPE" "0402"
					( Origin gFrontEnd )
				)
				( attribute "PART_NUMBER" "A36096-155"
					( Origin gFrontEnd )
				)
				( attribute "PHYS_PAGE" "107"
					( Origin gFrontEnd )
				)
				( attribute "ROT" "2"
					( Origin gFrontEnd )
				)
				( attribute "SEC" "1"
					( Origin gPackager )
				)
				( attribute "TOLERANCE" "10%"
					( Origin gFrontEnd )
				)
				( attribute "VALUE" "0.22UF"
					( Origin gFrontEnd )
				)
				( attribute "VER" "1"
					( Origin gFrontEnd )
				)
				( attribute "VOLTAGE" "16V"
					( Units "uVoltage" "V" 1.000000)
					( Origin gFrontEnd )
				)
				( attribute "XY" "(-4450,2675)"
					( Origin gFrontEnd )
				)
				( attribute "CHIPS_PART_NAME" "CAP"
					( Origin gPackager )
				)
				( attribute "CDS_PART_NAME" "CAP_0402-0.22UF,16V,10%,EMPTY,A"
					( Origin gPackager )
				)
				( objectStatus "C3P14" )
				( pin "a"
					( attribute "PN" "1"
						( Origin gPackager )
					)
					( objectStatus "C3P14.1" )
				)
				( pin "b"
					( attribute "PN" "2"
						( Origin gPackager )
					)
					( objectStatus "C3P14.2" )
				)
			)
			( gate "@baseboard_fab2_lib.baseboard_fab2(sch_1):page107_i435"
				( attribute "CDS_LIB" "mstr_discrete"
					( Origin gPackager )
				)
				( attribute "CDS_LOCATION" "C3P22"
					( Origin gPackager )
				)
				( attribute "CDS_SEC" "1"
					( Origin gPackager )
				)
				( attribute "LOCATION" "C3P22"
					( Origin gFrontEnd )
				)
				( attribute "MATERIAL" "EMPTY"
					( Origin gFrontEnd )
				)
				( attribute "PACK_TYPE" "0402"
					( Origin gFrontEnd )
				)
				( attribute "PART_NUMBER" "A36096-155"
					( Origin gFrontEnd )
				)
				( attribute "PHYS_PAGE" "107"
					( Origin gFrontEnd )
				)
				( attribute "ROT" "2"
					( Origin gFrontEnd )
				)
				( attribute "SEC" "1"
					( Origin gPackager )
				)
				( attribute "TOLERANCE" "10%"
					( Origin gFrontEnd )
				)
				( attribute "VALUE" "0.22UF"
					( Origin gFrontEnd )
				)
				( attribute "VER" "1"
					( Origin gFrontEnd )
				)
				( attribute "VOLTAGE" "16V"
					( Units "uVoltage" "V" 1.000000)
					( Origin gFrontEnd )
				)
				( attribute "XY" "(-4850,2675)"
					( Origin gFrontEnd )
				)
				( attribute "CHIPS_PART_NAME" "CAP"
					( Origin gPackager )
				)
				( attribute "CDS_PART_NAME" "CAP_0402-0.22UF,16V,10%,EMPTY,A"
					( Origin gPackager )
				)
				( objectStatus "C3P22" )
				( pin "a"
					( attribute "PN" "1"
						( Origin gPackager )
					)
					( objectStatus "C3P22.1" )
				)
				( pin "b"
					( attribute "PN" "2"
						( Origin gPackager )
					)
					( objectStatus "C3P22.2" )
				)
			)
			( gate "@baseboard_fab2_lib.baseboard_fab2(sch_1):page107_i437"
				( attribute "CDS_LIB" "mstr_discrete"
					( Origin gPackager )
				)
				( attribute "CDS_LOCATION" "C3P29"
					( Origin gPackager )
				)
				( attribute "CDS_SEC" "1"
					( Origin gPackager )
				)
				( attribute "LOCATION" "C3P29"
					( Origin gFrontEnd )
				)
				( attribute "MATERIAL" "EMPTY"
					( Origin gFrontEnd )
				)
				( attribute "PACK_TYPE" "0402"
					( Origin gFrontEnd )
				)
				( attribute "PART_NUMBER" "A36096-155"
					( Origin gFrontEnd )
				)
				( attribute "PHYS_PAGE" "107"
					( Origin gFrontEnd )
				)
				( attribute "ROT" "2"
					( Origin gFrontEnd )
				)
				( attribute "SEC" "1"
					( Origin gPackager )
				)
				( attribute "TOLERANCE" "10%"
					( Origin gFrontEnd )
				)
				( attribute "VALUE" "0.22UF"
					( Origin gFrontEnd )
				)
				( attribute "VER" "1"
					( Origin gFrontEnd )
				)
				( attribute "VOLTAGE" "16V"
					( Units "uVoltage" "V" 1.000000)
					( Origin gFrontEnd )
				)
				( attribute "XY" "(-5100,3975)"
					( Origin gFrontEnd )
				)
				( attribute "CHIPS_PART_NAME" "CAP"
					( Origin gPackager )
				)
				( attribute "CDS_PART_NAME" "CAP_0402-0.22UF,16V,10%,EMPTY,A"
					( Origin gPackager )
				)
				( objectStatus "C3P29" )
				( pin "a"
					( attribute "PN" "1"
						( Origin gPackager )
					)
					( objectStatus "C3P29.1" )
				)
				( pin "b"
					( attribute "PN" "2"
						( Origin gPackager )
					)
					( objectStatus "C3P29.2" )
				)
			)
			( gate "@baseboard_fab2_lib.baseboard_fab2(sch_1):page107_i438"
				( attribute "CDS_LIB" "mstr_discrete"
					( Origin gPackager )
				)
				( attribute "CDS_LOCATION" "C3P36"
					( Origin gPackager )
				)
				( attribute "CDS_SEC" "1"
					( Origin gPackager )
				)
				( attribute "LOCATION" "C3P36"
					( Origin gFrontEnd )
				)
				( attribute "MATERIAL" "EMPTY"
					( Origin gFrontEnd )
				)
				( attribute "PACK_TYPE" "0402"
					( Origin gFrontEnd )
				)
				( attribute "PART_NUMBER" "A36096-155"
					( Origin gFrontEnd )
				)
				( attribute "PHYS_PAGE" "107"
					( Origin gFrontEnd )
				)
				( attribute "ROT" "2"
					( Origin gFrontEnd )
				)
				( attribute "SEC" "1"
					( Origin gPackager )
				)
				( attribute "TOLERANCE" "10%"
					( Origin gFrontEnd )
				)
				( attribute "VALUE" "0.22UF"
					( Origin gFrontEnd )
				)
				( attribute "VER" "1"
					( Origin gFrontEnd )
				)
				( attribute "VOLTAGE" "16V"
					( Units "uVoltage" "V" 1.000000)
					( Origin gFrontEnd )
				)
				( attribute "XY" "(-5500,3975)"
					( Origin gFrontEnd )
				)
				( attribute "CHIPS_PART_NAME" "CAP"
					( Origin gPackager )
				)
				( attribute "CDS_PART_NAME" "CAP_0402-0.22UF,16V,10%,EMPTY,A"
					( Origin gPackager )
				)
				( objectStatus "C3P36" )
				( pin "a"
					( attribute "PN" "1"
						( Origin gPackager )
					)
					( objectStatus "C3P36.1" )
				)
				( pin "b"
					( attribute "PN" "2"
						( Origin gPackager )
					)
					( objectStatus "C3P36.2" )
				)
			)
			( gate "@baseboard_fab2_lib.baseboard_fab2(sch_1):page107_i439"
				( attribute "CDS_LIB" "mstr_discrete"
					( Origin gPackager )
				)
				( attribute "CDS_LOCATION" "C3P33"
					( Origin gPackager )
				)
				( attribute "CDS_SEC" "1"
					( Origin gPackager )
				)
				( attribute "LOCATION" "C3P33"
					( Origin gFrontEnd )
				)
				( attribute "MATERIAL" "EMPTY"
					( Origin gFrontEnd )
				)
				( attribute "PACK_TYPE" "0402"
					( Origin gFrontEnd )
				)
				( attribute "PART_NUMBER" "A36096-155"
					( Origin gFrontEnd )
				)
				( attribute "PHYS_PAGE" "107"
					( Origin gFrontEnd )
				)
				( attribute "ROT" "2"
					( Origin gFrontEnd )
				)
				( attribute "SEC" "1"
					( Origin gPackager )
				)
				( attribute "TOLERANCE" "10%"
					( Origin gFrontEnd )
				)
				( attribute "VALUE" "0.22UF"
					( Origin gFrontEnd )
				)
				( attribute "VER" "1"
					( Origin gFrontEnd )
				)
				( attribute "VOLTAGE" "16V"
					( Units "uVoltage" "V" 1.000000)
					( Origin gFrontEnd )
				)
				( attribute "XY" "(-5300,3675)"
					( Origin gFrontEnd )
				)
				( attribute "CHIPS_PART_NAME" "CAP"
					( Origin gPackager )
				)
				( attribute "CDS_PART_NAME" "CAP_0402-0.22UF,16V,10%,EMPTY,A"
					( Origin gPackager )
				)
				( objectStatus "C3P33" )
				( pin "a"
					( attribute "PN" "1"
						( Origin gPackager )
					)
					( objectStatus "C3P33.1" )
				)
				( pin "b"
					( attribute "PN" "2"
						( Origin gPackager )
					)
					( objectStatus "C3P33.2" )
				)
			)
			( gate "@baseboard_fab2_lib.baseboard_fab2(sch_1):page107_i444"
				( attribute "CDS_LIB" "mstr_discrete"
					( Origin gPackager )
				)
				( attribute "CDS_LOCATION" "C3P26"
					( Origin gPackager )
				)
				( attribute "CDS_SEC" "1"
					( Origin gPackager )
				)
				( attribute "LOCATION" "C3P26"
					( Origin gFrontEnd )
				)
				( attribute "MATERIAL" "EMPTY"
					( Origin gFrontEnd )
				)
				( attribute "PACK_TYPE" "0402"
					( Origin gFrontEnd )
				)
				( attribute "PART_NUMBER" "A36096-155"
					( Origin gFrontEnd )
				)
				( attribute "PHYS_PAGE" "107"
					( Origin gFrontEnd )
				)
				( attribute "ROT" "2"
					( Origin gFrontEnd )
				)
				( attribute "SEC" "1"
					( Origin gPackager )
				)
				( attribute "TOLERANCE" "10%"
					( Origin gFrontEnd )
				)
				( attribute "VALUE" "0.22UF"
					( Origin gFrontEnd )
				)
				( attribute "VER" "1"
					( Origin gFrontEnd )
				)
				( attribute "VOLTAGE" "16V"
					( Units "uVoltage" "V" 1.000000)
					( Origin gFrontEnd )
				)
				( attribute "XY" "(-5050,2975)"
					( Origin gFrontEnd )
				)
				( attribute "CHIPS_PART_NAME" "CAP"
					( Origin gPackager )
				)
				( attribute "CDS_PART_NAME" "CAP_0402-0.22UF,16V,10%,EMPTY,A"
					( Origin gPackager )
				)
				( objectStatus "C3P26" )
				( pin "a"
					( attribute "PN" "1"
						( Origin gPackager )
					)
					( objectStatus "C3P26.1" )
				)
				( pin "b"
					( attribute "PN" "2"
						( Origin gPackager )
					)
					( objectStatus "C3P26.2" )
				)
			)
			( gate "@baseboard_fab2_lib.baseboard_fab2(sch_1):page107_i447"
				( attribute "CDS_LIB" "mstr_discrete"
					( Origin gPackager )
				)
				( attribute "CDS_LOCATION" "C3P34"
					( Origin gPackager )
				)
				( attribute "CDS_SEC" "1"
					( Origin gPackager )
				)
				( attribute "LOCATION" "C3P34"
					( Origin gFrontEnd )
				)
				( attribute "MATERIAL" "EMPTY"
					( Origin gFrontEnd )
				)
				( attribute "PACK_TYPE" "0402"
					( Origin gFrontEnd )
				)
				( attribute "PART_NUMBER" "A36096-155"
					( Origin gFrontEnd )
				)
				( attribute "PHYS_PAGE" "107"
					( Origin gFrontEnd )
				)
				( attribute "ROT" "2"
					( Origin gFrontEnd )
				)
				( attribute "SEC" "1"
					( Origin gPackager )
				)
				( attribute "TOLERANCE" "10%"
					( Origin gFrontEnd )
				)
				( attribute "VALUE" "0.22UF"
					( Origin gFrontEnd )
				)
				( attribute "VER" "1"
					( Origin gFrontEnd )
				)
				( attribute "VOLTAGE" "16V"
					( Units "uVoltage" "V" 1.000000)
					( Origin gFrontEnd )
				)
				( attribute "XY" "(-5450,2975)"
					( Origin gFrontEnd )
				)
				( attribute "CHIPS_PART_NAME" "CAP"
					( Origin gPackager )
				)
				( attribute "CDS_PART_NAME" "CAP_0402-0.22UF,16V,10%,EMPTY,A"
					( Origin gPackager )
				)
				( objectStatus "C3P34" )
				( pin "a"
					( attribute "PN" "1"
						( Origin gPackager )
					)
					( objectStatus "C3P34.1" )
				)
				( pin "b"
					( attribute "PN" "2"
						( Origin gPackager )
					)
					( objectStatus "C3P34.2" )
				)
			)
			( gate "@baseboard_fab2_lib.baseboard_fab2(sch_1):page107_i448"
				( attribute "CDS_LIB" "mstr_discrete"
					( Origin gPackager )
				)
				( attribute "CDS_LOCATION" "C3P41"
					( Origin gPackager )
				)
				( attribute "CDS_SEC" "1"
					( Origin gPackager )
				)
				( attribute "LOCATION" "C3P41"
					( Origin gFrontEnd )
				)
				( attribute "MATERIAL" "EMPTY"
					( Origin gFrontEnd )
				)
				( attribute "PACK_TYPE" "0402"
					( Origin gFrontEnd )
				)
				( attribute "PART_NUMBER" "A36096-155"
					( Origin gFrontEnd )
				)
				( attribute "PHYS_PAGE" "107"
					( Origin gFrontEnd )
				)
				( attribute "ROT" "2"
					( Origin gFrontEnd )
				)
				( attribute "SEC" "1"
					( Origin gPackager )
				)
				( attribute "TOLERANCE" "10%"
					( Origin gFrontEnd )
				)
				( attribute "VALUE" "0.22UF"
					( Origin gFrontEnd )
				)
				( attribute "VER" "1"
					( Origin gFrontEnd )
				)
				( attribute "VOLTAGE" "16V"
					( Units "uVoltage" "V" 1.000000)
					( Origin gFrontEnd )
				)
				( attribute "XY" "(-5700,3675)"
					( Origin gFrontEnd )
				)
				( attribute "CHIPS_PART_NAME" "CAP"
					( Origin gPackager )
				)
				( attribute "CDS_PART_NAME" "CAP_0402-0.22UF,16V,10%,EMPTY,A"
					( Origin gPackager )
				)
				( objectStatus "C3P41" )
				( pin "a"
					( attribute "PN" "1"
						( Origin gPackager )
					)
					( objectStatus "C3P41.1" )
				)
				( pin "b"
					( attribute "PN" "2"
						( Origin gPackager )
					)
					( objectStatus "C3P41.2" )
				)
			)
			( gate "@baseboard_fab2_lib.baseboard_fab2(sch_1):page107_i452"
				( attribute "CDS_LIB" "mstr_discrete"
					( Origin gPackager )
				)
				( attribute "CDS_LOCATION" "C3P31"
					( Origin gPackager )
				)
				( attribute "CDS_SEC" "1"
					( Origin gPackager )
				)
				( attribute "LOCATION" "C3P31"
					( Origin gFrontEnd )
				)
				( attribute "MATERIAL" "EMPTY"
					( Origin gFrontEnd )
				)
				( attribute "PACK_TYPE" "0402"
					( Origin gFrontEnd )
				)
				( attribute "PART_NUMBER" "A36096-155"
					( Origin gFrontEnd )
				)
				( attribute "PHYS_PAGE" "107"
					( Origin gFrontEnd )
				)
				( attribute "ROT" "2"
					( Origin gFrontEnd )
				)
				( attribute "SEC" "1"
					( Origin gPackager )
				)
				( attribute "TOLERANCE" "10%"
					( Origin gFrontEnd )
				)
				( attribute "VALUE" "0.22UF"
					( Origin gFrontEnd )
				)
				( attribute "VER" "1"
					( Origin gFrontEnd )
				)
				( attribute "VOLTAGE" "16V"
					( Units "uVoltage" "V" 1.000000)
					( Origin gFrontEnd )
				)
				( attribute "XY" "(-5250,2675)"
					( Origin gFrontEnd )
				)
				( attribute "CHIPS_PART_NAME" "CAP"
					( Origin gPackager )
				)
				( attribute "CDS_PART_NAME" "CAP_0402-0.22UF,16V,10%,EMPTY,A"
					( Origin gPackager )
				)
				( objectStatus "C3P31" )
				( pin "a"
					( attribute "PN" "1"
						( Origin gPackager )
					)
					( objectStatus "C3P31.1" )
				)
				( pin "b"
					( attribute "PN" "2"
						( Origin gPackager )
					)
					( objectStatus "C3P31.2" )
				)
			)
			( gate "@baseboard_fab2_lib.baseboard_fab2(sch_1):page107_i455"
				( attribute "CDS_LIB" "mstr_discrete"
					( Origin gPackager )
				)
				( attribute "CDS_LOCATION" "C3P38"
					( Origin gPackager )
				)
				( attribute "CDS_SEC" "1"
					( Origin gPackager )
				)
				( attribute "LOCATION" "C3P38"
					( Origin gFrontEnd )
				)
				( attribute "MATERIAL" "EMPTY"
					( Origin gFrontEnd )
				)
				( attribute "PACK_TYPE" "0402"
					( Origin gFrontEnd )
				)
				( attribute "PART_NUMBER" "A36096-155"
					( Origin gFrontEnd )
				)
				( attribute "PHYS_PAGE" "107"
					( Origin gFrontEnd )
				)
				( attribute "ROT" "2"
					( Origin gFrontEnd )
				)
				( attribute "SEC" "1"
					( Origin gPackager )
				)
				( attribute "TOLERANCE" "10%"
					( Origin gFrontEnd )
				)
				( attribute "VALUE" "0.22UF"
					( Origin gFrontEnd )
				)
				( attribute "VER" "1"
					( Origin gFrontEnd )
				)
				( attribute "VOLTAGE" "16V"
					( Units "uVoltage" "V" 1.000000)
					( Origin gFrontEnd )
				)
				( attribute "XY" "(-5650,2675)"
					( Origin gFrontEnd )
				)
				( attribute "CHIPS_PART_NAME" "CAP"
					( Origin gPackager )
				)
				( attribute "CDS_PART_NAME" "CAP_0402-0.22UF,16V,10%,EMPTY,A"
					( Origin gPackager )
				)
				( objectStatus "C3P38" )
				( pin "a"
					( attribute "PN" "1"
						( Origin gPackager )
					)
					( objectStatus "C3P38.1" )
				)
				( pin "b"
					( attribute "PN" "2"
						( Origin gPackager )
					)
					( objectStatus "C3P38.2" )
				)
			)
			( gate "@baseboard_fab2_lib.baseboard_fab2(sch_1):page107_i458"
				( attribute "CDS_LIB" "mstr_discrete"
					( Origin gPackager )
				)
				( attribute "CDS_LOCATION" "R2U29"
					( Origin gPackager )
				)
				( attribute "CDS_SEC" "1"
					( Origin gPackager )
				)
				( attribute "LOCATION" "R2U29"
					( Origin gFrontEnd )
				)
				( attribute "MATERIAL" "EMPTY"
					( Origin gFrontEnd )
				)
				( attribute "PACK_TYPE" "0402"
					( Origin gFrontEnd )
				)
				( attribute "PART_NUMBER" "G21497-005"
					( Origin gFrontEnd )
				)
				( attribute "PHYS_PAGE" "107"
					( Origin gFrontEnd )
				)
				( attribute "ROT" "0"
					( Origin gFrontEnd )
				)
				( attribute "SEC" "1"
					( Origin gPackager )
				)
				( attribute "TOLERANCE" "5%"
					( Origin gFrontEnd )
				)
				( attribute "VALUE" "0.0"
					( Origin gFrontEnd )
				)
				( attribute "VER" "2"
					( Origin gFrontEnd )
				)
				( attribute "WATTAGE" "1/16W"
					( Origin gFrontEnd )
				)
				( attribute "XY" "(-2225,3825)"
					( Origin gFrontEnd )
				)
				( attribute "CHIPS_PART_NAME" "RES"
					( Origin gPackager )
				)
				( attribute "CDS_PART_NAME" "RES_0402-0.0,5%,1/16W,EMPTY,G2A"
					( Origin gPackager )
				)
				( objectStatus "R2U29" )
				( pin "a"
					( attribute "PN" "1"
						( Origin gPackager )
					)
					( objectStatus "R2U29.1" )
				)
				( pin "b"
					( attribute "PN" "2"
						( Origin gPackager )
					)
					( objectStatus "R2U29.2" )
				)
			)
			( gate "@baseboard_fab2_lib.baseboard_fab2(sch_1):page107_i459"
				( attribute "CDS_LIB" "mstr_discrete"
					( Origin gPackager )
				)
				( attribute "CDS_LOCATION" "R2U27"
					( Origin gPackager )
				)
				( attribute "CDS_SEC" "1"
					( Origin gPackager )
				)
				( attribute "LOCATION" "R2U27"
					( Origin gFrontEnd )
				)
				( attribute "MATERIAL" "EMPTY"
					( Origin gFrontEnd )
				)
				( attribute "PACK_TYPE" "0402"
					( Origin gFrontEnd )
				)
				( attribute "PART_NUMBER" "G21497-005"
					( Origin gFrontEnd )
				)
				( attribute "PHYS_PAGE" "107"
					( Origin gFrontEnd )
				)
				( attribute "ROT" "0"
					( Origin gFrontEnd )
				)
				( attribute "SEC" "1"
					( Origin gPackager )
				)
				( attribute "TOLERANCE" "5%"
					( Origin gFrontEnd )
				)
				( attribute "VALUE" "0.0"
					( Origin gFrontEnd )
				)
				( attribute "VER" "2"
					( Origin gFrontEnd )
				)
				( attribute "WATTAGE" "1/16W"
					( Origin gFrontEnd )
				)
				( attribute "XY" "(-2025,4125)"
					( Origin gFrontEnd )
				)
				( attribute "CHIPS_PART_NAME" "RES"
					( Origin gPackager )
				)
				( attribute "CDS_PART_NAME" "RES_0402-0.0,5%,1/16W,EMPTY,G2A"
					( Origin gPackager )
				)
				( objectStatus "R2U27" )
				( pin "a"
					( attribute "PN" "1"
						( Origin gPackager )
					)
					( objectStatus "R2U27.1" )
				)
				( pin "b"
					( attribute "PN" "2"
						( Origin gPackager )
					)
					( objectStatus "R2U27.2" )
				)
			)
			( gate "@baseboard_fab2_lib.baseboard_fab2(sch_1):page107_i460"
				( attribute "CDS_LIB" "mstr_discrete"
					( Origin gPackager )
				)
				( attribute "CDS_LOCATION" "R2U25"
					( Origin gPackager )
				)
				( attribute "CDS_SEC" "1"
					( Origin gPackager )
				)
				( attribute "LOCATION" "R2U25"
					( Origin gFrontEnd )
				)
				( attribute "MATERIAL" "EMPTY"
					( Origin gFrontEnd )
				)
				( attribute "PACK_TYPE" "0402"
					( Origin gFrontEnd )
				)
				( attribute "PART_NUMBER" "G21497-005"
					( Origin gFrontEnd )
				)
				( attribute "PHYS_PAGE" "107"
					( Origin gFrontEnd )
				)
				( attribute "ROT" "0"
					( Origin gFrontEnd )
				)
				( attribute "SEC" "1"
					( Origin gPackager )
				)
				( attribute "TOLERANCE" "5%"
					( Origin gFrontEnd )
				)
				( attribute "VALUE" "0.0"
					( Origin gFrontEnd )
				)
				( attribute "VER" "2"
					( Origin gFrontEnd )
				)
				( attribute "WATTAGE" "1/16W"
					( Origin gFrontEnd )
				)
				( attribute "XY" "(-1825,3825)"
					( Origin gFrontEnd )
				)
				( attribute "CHIPS_PART_NAME" "RES"
					( Origin gPackager )
				)
				( attribute "CDS_PART_NAME" "RES_0402-0.0,5%,1/16W,EMPTY,G2A"
					( Origin gPackager )
				)
				( objectStatus "R2U25" )
				( pin "a"
					( attribute "PN" "1"
						( Origin gPackager )
					)
					( objectStatus "R2U25.1" )
				)
				( pin "b"
					( attribute "PN" "2"
						( Origin gPackager )
					)
					( objectStatus "R2U25.2" )
				)
			)
			( gate "@baseboard_fab2_lib.baseboard_fab2(sch_1):page107_i461"
				( attribute "CDS_LIB" "mstr_discrete"
					( Origin gPackager )
				)
				( attribute "CDS_LOCATION" "R2U23"
					( Origin gPackager )
				)
				( attribute "CDS_SEC" "1"
					( Origin gPackager )
				)
				( attribute "LOCATION" "R2U23"
					( Origin gFrontEnd )
				)
				( attribute "MATERIAL" "EMPTY"
					( Origin gFrontEnd )
				)
				( attribute "PACK_TYPE" "0402"
					( Origin gFrontEnd )
				)
				( attribute "PART_NUMBER" "G21497-005"
					( Origin gFrontEnd )
				)
				( attribute "PHYS_PAGE" "107"
					( Origin gFrontEnd )
				)
				( attribute "ROT" "0"
					( Origin gFrontEnd )
				)
				( attribute "SEC" "1"
					( Origin gPackager )
				)
				( attribute "TOLERANCE" "5%"
					( Origin gFrontEnd )
				)
				( attribute "VALUE" "0.0"
					( Origin gFrontEnd )
				)
				( attribute "VER" "2"
					( Origin gFrontEnd )
				)
				( attribute "WATTAGE" "1/16W"
					( Origin gFrontEnd )
				)
				( attribute "XY" "(-1625,4125)"
					( Origin gFrontEnd )
				)
				( attribute "CHIPS_PART_NAME" "RES"
					( Origin gPackager )
				)
				( attribute "CDS_PART_NAME" "RES_0402-0.0,5%,1/16W,EMPTY,G2A"
					( Origin gPackager )
				)
				( objectStatus "R2U23" )
				( pin "a"
					( attribute "PN" "1"
						( Origin gPackager )
					)
					( objectStatus "R2U23.1" )
				)
				( pin "b"
					( attribute "PN" "2"
						( Origin gPackager )
					)
					( objectStatus "R2U23.2" )
				)
			)
			( gate "@baseboard_fab2_lib.baseboard_fab2(sch_1):page107_i462"
				( attribute "CDS_LIB" "mstr_discrete"
					( Origin gPackager )
				)
				( attribute "CDS_LOCATION" "R2U21"
					( Origin gPackager )
				)
				( attribute "CDS_SEC" "1"
					( Origin gPackager )
				)
				( attribute "LOCATION" "R2U21"
					( Origin gFrontEnd )
				)
				( attribute "MATERIAL" "EMPTY"
					( Origin gFrontEnd )
				)
				( attribute "PACK_TYPE" "0402"
					( Origin gFrontEnd )
				)
				( attribute "PART_NUMBER" "G21497-005"
					( Origin gFrontEnd )
				)
				( attribute "PHYS_PAGE" "107"
					( Origin gFrontEnd )
				)
				( attribute "ROT" "0"
					( Origin gFrontEnd )
				)
				( attribute "SEC" "1"
					( Origin gPackager )
				)
				( attribute "TOLERANCE" "5%"
					( Origin gFrontEnd )
				)
				( attribute "VALUE" "0.0"
					( Origin gFrontEnd )
				)
				( attribute "VER" "2"
					( Origin gFrontEnd )
				)
				( attribute "WATTAGE" "1/16W"
					( Origin gFrontEnd )
				)
				( attribute "XY" "(-1425,3825)"
					( Origin gFrontEnd )
				)
				( attribute "CHIPS_PART_NAME" "RES"
					( Origin gPackager )
				)
				( attribute "CDS_PART_NAME" "RES_0402-0.0,5%,1/16W,EMPTY,G2A"
					( Origin gPackager )
				)
				( objectStatus "R2U21" )
				( pin "a"
					( attribute "PN" "1"
						( Origin gPackager )
					)
					( objectStatus "R2U21.1" )
				)
				( pin "b"
					( attribute "PN" "2"
						( Origin gPackager )
					)
					( objectStatus "R2U21.2" )
				)
			)
			( gate "@baseboard_fab2_lib.baseboard_fab2(sch_1):page107_i463"
				( attribute "CDS_LIB" "mstr_discrete"
					( Origin gPackager )
				)
				( attribute "CDS_LOCATION" "R2U19"
					( Origin gPackager )
				)
				( attribute "CDS_SEC" "1"
					( Origin gPackager )
				)
				( attribute "LOCATION" "R2U19"
					( Origin gFrontEnd )
				)
				( attribute "MATERIAL" "EMPTY"
					( Origin gFrontEnd )
				)
				( attribute "PACK_TYPE" "0402"
					( Origin gFrontEnd )
				)
				( attribute "PART_NUMBER" "G21497-005"
					( Origin gFrontEnd )
				)
				( attribute "PHYS_PAGE" "107"
					( Origin gFrontEnd )
				)
				( attribute "ROT" "0"
					( Origin gFrontEnd )
				)
				( attribute "SEC" "1"
					( Origin gPackager )
				)
				( attribute "TOLERANCE" "5%"
					( Origin gFrontEnd )
				)
				( attribute "VALUE" "0.0"
					( Origin gFrontEnd )
				)
				( attribute "VER" "2"
					( Origin gFrontEnd )
				)
				( attribute "WATTAGE" "1/16W"
					( Origin gFrontEnd )
				)
				( attribute "XY" "(-1225,4125)"
					( Origin gFrontEnd )
				)
				( attribute "CHIPS_PART_NAME" "RES"
					( Origin gPackager )
				)
				( attribute "CDS_PART_NAME" "RES_0402-0.0,5%,1/16W,EMPTY,G2A"
					( Origin gPackager )
				)
				( objectStatus "R2U19" )
				( pin "a"
					( attribute "PN" "1"
						( Origin gPackager )
					)
					( objectStatus "R2U19.1" )
				)
				( pin "b"
					( attribute "PN" "2"
						( Origin gPackager )
					)
					( objectStatus "R2U19.2" )
				)
			)
			( gate "@baseboard_fab2_lib.baseboard_fab2(sch_1):page107_i464"
				( attribute "CDS_LIB" "mstr_discrete"
					( Origin gPackager )
				)
				( attribute "CDS_LOCATION" "R2U17"
					( Origin gPackager )
				)
				( attribute "CDS_SEC" "1"
					( Origin gPackager )
				)
				( attribute "LOCATION" "R2U17"
					( Origin gFrontEnd )
				)
				( attribute "MATERIAL" "EMPTY"
					( Origin gFrontEnd )
				)
				( attribute "PACK_TYPE" "0402"
					( Origin gFrontEnd )
				)
				( attribute "PART_NUMBER" "G21497-005"
					( Origin gFrontEnd )
				)
				( attribute "PHYS_PAGE" "107"
					( Origin gFrontEnd )
				)
				( attribute "ROT" "0"
					( Origin gFrontEnd )
				)
				( attribute "SEC" "1"
					( Origin gPackager )
				)
				( attribute "TOLERANCE" "5%"
					( Origin gFrontEnd )
				)
				( attribute "VALUE" "0.0"
					( Origin gFrontEnd )
				)
				( attribute "VER" "2"
					( Origin gFrontEnd )
				)
				( attribute "WATTAGE" "1/16W"
					( Origin gFrontEnd )
				)
				( attribute "XY" "(-1025,3825)"
					( Origin gFrontEnd )
				)
				( attribute "CHIPS_PART_NAME" "RES"
					( Origin gPackager )
				)
				( attribute "CDS_PART_NAME" "RES_0402-0.0,5%,1/16W,EMPTY,G2A"
					( Origin gPackager )
				)
				( objectStatus "R2U17" )
				( pin "a"
					( attribute "PN" "1"
						( Origin gPackager )
					)
					( objectStatus "R2U17.1" )
				)
				( pin "b"
					( attribute "PN" "2"
						( Origin gPackager )
					)
					( objectStatus "R2U17.2" )
				)
			)
			( gate "@baseboard_fab2_lib.baseboard_fab2(sch_1):page107_i465"
				( attribute "CDS_LIB" "mstr_discrete"
					( Origin gPackager )
				)
				( attribute "CDS_LOCATION" "R2U15"
					( Origin gPackager )
				)
				( attribute "CDS_SEC" "1"
					( Origin gPackager )
				)
				( attribute "LOCATION" "R2U15"
					( Origin gFrontEnd )
				)
				( attribute "MATERIAL" "EMPTY"
					( Origin gFrontEnd )
				)
				( attribute "PACK_TYPE" "0402"
					( Origin gFrontEnd )
				)
				( attribute "PART_NUMBER" "G21497-005"
					( Origin gFrontEnd )
				)
				( attribute "PHYS_PAGE" "107"
					( Origin gFrontEnd )
				)
				( attribute "ROT" "0"
					( Origin gFrontEnd )
				)
				( attribute "SEC" "1"
					( Origin gPackager )
				)
				( attribute "TOLERANCE" "5%"
					( Origin gFrontEnd )
				)
				( attribute "VALUE" "0.0"
					( Origin gFrontEnd )
				)
				( attribute "VER" "2"
					( Origin gFrontEnd )
				)
				( attribute "WATTAGE" "1/16W"
					( Origin gFrontEnd )
				)
				( attribute "XY" "(-825,4125)"
					( Origin gFrontEnd )
				)
				( attribute "CHIPS_PART_NAME" "RES"
					( Origin gPackager )
				)
				( attribute "CDS_PART_NAME" "RES_0402-0.0,5%,1/16W,EMPTY,G2A"
					( Origin gPackager )
				)
				( objectStatus "R2U15" )
				( pin "a"
					( attribute "PN" "1"
						( Origin gPackager )
					)
					( objectStatus "R2U15.1" )
				)
				( pin "b"
					( attribute "PN" "2"
						( Origin gPackager )
					)
					( objectStatus "R2U15.2" )
				)
			)
			( gate "@baseboard_fab2_lib.baseboard_fab2(sch_1):page107_i466"
				( attribute "CDS_LIB" "mstr_discrete"
					( Origin gPackager )
				)
				( attribute "CDS_LOCATION" "R2U14"
					( Origin gPackager )
				)
				( attribute "CDS_SEC" "1"
					( Origin gPackager )
				)
				( attribute "LOCATION" "R2U14"
					( Origin gFrontEnd )
				)
				( attribute "MATERIAL" "EMPTY"
					( Origin gFrontEnd )
				)
				( attribute "PACK_TYPE" "0402"
					( Origin gFrontEnd )
				)
				( attribute "PART_NUMBER" "G21497-005"
					( Origin gFrontEnd )
				)
				( attribute "PHYS_PAGE" "107"
					( Origin gFrontEnd )
				)
				( attribute "ROT" "0"
					( Origin gFrontEnd )
				)
				( attribute "SEC" "1"
					( Origin gPackager )
				)
				( attribute "TOLERANCE" "5%"
					( Origin gFrontEnd )
				)
				( attribute "VALUE" "0.0"
					( Origin gFrontEnd )
				)
				( attribute "VER" "2"
					( Origin gFrontEnd )
				)
				( attribute "WATTAGE" "1/16W"
					( Origin gFrontEnd )
				)
				( attribute "XY" "(-800,3100)"
					( Origin gFrontEnd )
				)
				( attribute "CHIPS_PART_NAME" "RES"
					( Origin gPackager )
				)
				( attribute "CDS_PART_NAME" "RES_0402-0.0,5%,1/16W,EMPTY,G2A"
					( Origin gPackager )
				)
				( objectStatus "R2U14" )
				( pin "a"
					( attribute "PN" "1"
						( Origin gPackager )
					)
					( objectStatus "R2U14.1" )
				)
				( pin "b"
					( attribute "PN" "2"
						( Origin gPackager )
					)
					( objectStatus "R2U14.2" )
				)
			)
			( gate "@baseboard_fab2_lib.baseboard_fab2(sch_1):page107_i467"
				( attribute "CDS_LIB" "mstr_discrete"
					( Origin gPackager )
				)
				( attribute "CDS_LOCATION" "R2U16"
					( Origin gPackager )
				)
				( attribute "CDS_SEC" "1"
					( Origin gPackager )
				)
				( attribute "LOCATION" "R2U16"
					( Origin gFrontEnd )
				)
				( attribute "MATERIAL" "EMPTY"
					( Origin gFrontEnd )
				)
				( attribute "PACK_TYPE" "0402"
					( Origin gFrontEnd )
				)
				( attribute "PART_NUMBER" "G21497-005"
					( Origin gFrontEnd )
				)
				( attribute "PHYS_PAGE" "107"
					( Origin gFrontEnd )
				)
				( attribute "ROT" "0"
					( Origin gFrontEnd )
				)
				( attribute "SEC" "1"
					( Origin gPackager )
				)
				( attribute "TOLERANCE" "5%"
					( Origin gFrontEnd )
				)
				( attribute "VALUE" "0.0"
					( Origin gFrontEnd )
				)
				( attribute "VER" "2"
					( Origin gFrontEnd )
				)
				( attribute "WATTAGE" "1/16W"
					( Origin gFrontEnd )
				)
				( attribute "XY" "(-1000,2800)"
					( Origin gFrontEnd )
				)
				( attribute "CHIPS_PART_NAME" "RES"
					( Origin gPackager )
				)
				( attribute "CDS_PART_NAME" "RES_0402-0.0,5%,1/16W,EMPTY,G2A"
					( Origin gPackager )
				)
				( objectStatus "R2U16" )
				( pin "a"
					( attribute "PN" "1"
						( Origin gPackager )
					)
					( objectStatus "R2U16.1" )
				)
				( pin "b"
					( attribute "PN" "2"
						( Origin gPackager )
					)
					( objectStatus "R2U16.2" )
				)
			)
			( gate "@baseboard_fab2_lib.baseboard_fab2(sch_1):page107_i468"
				( attribute "CDS_LIB" "mstr_discrete"
					( Origin gPackager )
				)
				( attribute "CDS_LOCATION" "R2U18"
					( Origin gPackager )
				)
				( attribute "CDS_SEC" "1"
					( Origin gPackager )
				)
				( attribute "LOCATION" "R2U18"
					( Origin gFrontEnd )
				)
				( attribute "MATERIAL" "EMPTY"
					( Origin gFrontEnd )
				)
				( attribute "PACK_TYPE" "0402"
					( Origin gFrontEnd )
				)
				( attribute "PART_NUMBER" "G21497-005"
					( Origin gFrontEnd )
				)
				( attribute "PHYS_PAGE" "107"
					( Origin gFrontEnd )
				)
				( attribute "ROT" "0"
					( Origin gFrontEnd )
				)
				( attribute "SEC" "1"
					( Origin gPackager )
				)
				( attribute "TOLERANCE" "5%"
					( Origin gFrontEnd )
				)
				( attribute "VALUE" "0.0"
					( Origin gFrontEnd )
				)
				( attribute "VER" "2"
					( Origin gFrontEnd )
				)
				( attribute "WATTAGE" "1/16W"
					( Origin gFrontEnd )
				)
				( attribute "XY" "(-1200,3100)"
					( Origin gFrontEnd )
				)
				( attribute "CHIPS_PART_NAME" "RES"
					( Origin gPackager )
				)
				( attribute "CDS_PART_NAME" "RES_0402-0.0,5%,1/16W,EMPTY,G2A"
					( Origin gPackager )
				)
				( objectStatus "R2U18" )
				( pin "a"
					( attribute "PN" "1"
						( Origin gPackager )
					)
					( objectStatus "R2U18.1" )
				)
				( pin "b"
					( attribute "PN" "2"
						( Origin gPackager )
					)
					( objectStatus "R2U18.2" )
				)
			)
			( gate "@baseboard_fab2_lib.baseboard_fab2(sch_1):page107_i469"
				( attribute "CDS_LIB" "mstr_discrete"
					( Origin gPackager )
				)
				( attribute "CDS_LOCATION" "R2U20"
					( Origin gPackager )
				)
				( attribute "CDS_SEC" "1"
					( Origin gPackager )
				)
				( attribute "LOCATION" "R2U20"
					( Origin gFrontEnd )
				)
				( attribute "MATERIAL" "EMPTY"
					( Origin gFrontEnd )
				)
				( attribute "PACK_TYPE" "0402"
					( Origin gFrontEnd )
				)
				( attribute "PART_NUMBER" "G21497-005"
					( Origin gFrontEnd )
				)
				( attribute "PHYS_PAGE" "107"
					( Origin gFrontEnd )
				)
				( attribute "ROT" "0"
					( Origin gFrontEnd )
				)
				( attribute "SEC" "1"
					( Origin gPackager )
				)
				( attribute "TOLERANCE" "5%"
					( Origin gFrontEnd )
				)
				( attribute "VALUE" "0.0"
					( Origin gFrontEnd )
				)
				( attribute "VER" "2"
					( Origin gFrontEnd )
				)
				( attribute "WATTAGE" "1/16W"
					( Origin gFrontEnd )
				)
				( attribute "XY" "(-1400,2800)"
					( Origin gFrontEnd )
				)
				( attribute "CHIPS_PART_NAME" "RES"
					( Origin gPackager )
				)
				( attribute "CDS_PART_NAME" "RES_0402-0.0,5%,1/16W,EMPTY,G2A"
					( Origin gPackager )
				)
				( objectStatus "R2U20" )
				( pin "a"
					( attribute "PN" "1"
						( Origin gPackager )
					)
					( objectStatus "R2U20.1" )
				)
				( pin "b"
					( attribute "PN" "2"
						( Origin gPackager )
					)
					( objectStatus "R2U20.2" )
				)
			)
			( gate "@baseboard_fab2_lib.baseboard_fab2(sch_1):page107_i470"
				( attribute "CDS_LIB" "mstr_discrete"
					( Origin gPackager )
				)
				( attribute "CDS_LOCATION" "R2U22"
					( Origin gPackager )
				)
				( attribute "CDS_SEC" "1"
					( Origin gPackager )
				)
				( attribute "LOCATION" "R2U22"
					( Origin gFrontEnd )
				)
				( attribute "MATERIAL" "EMPTY"
					( Origin gFrontEnd )
				)
				( attribute "PACK_TYPE" "0402"
					( Origin gFrontEnd )
				)
				( attribute "PART_NUMBER" "G21497-005"
					( Origin gFrontEnd )
				)
				( attribute "PHYS_PAGE" "107"
					( Origin gFrontEnd )
				)
				( attribute "ROT" "0"
					( Origin gFrontEnd )
				)
				( attribute "SEC" "1"
					( Origin gPackager )
				)
				( attribute "TOLERANCE" "5%"
					( Origin gFrontEnd )
				)
				( attribute "VALUE" "0.0"
					( Origin gFrontEnd )
				)
				( attribute "VER" "2"
					( Origin gFrontEnd )
				)
				( attribute "WATTAGE" "1/16W"
					( Origin gFrontEnd )
				)
				( attribute "XY" "(-1600,3100)"
					( Origin gFrontEnd )
				)
				( attribute "CHIPS_PART_NAME" "RES"
					( Origin gPackager )
				)
				( attribute "CDS_PART_NAME" "RES_0402-0.0,5%,1/16W,EMPTY,G2A"
					( Origin gPackager )
				)
				( objectStatus "R2U22" )
				( pin "a"
					( attribute "PN" "1"
						( Origin gPackager )
					)
					( objectStatus "R2U22.1" )
				)
				( pin "b"
					( attribute "PN" "2"
						( Origin gPackager )
					)
					( objectStatus "R2U22.2" )
				)
			)
			( gate "@baseboard_fab2_lib.baseboard_fab2(sch_1):page107_i471"
				( attribute "CDS_LIB" "mstr_discrete"
					( Origin gPackager )
				)
				( attribute "CDS_LOCATION" "R2U24"
					( Origin gPackager )
				)
				( attribute "CDS_SEC" "1"
					( Origin gPackager )
				)
				( attribute "LOCATION" "R2U24"
					( Origin gFrontEnd )
				)
				( attribute "MATERIAL" "EMPTY"
					( Origin gFrontEnd )
				)
				( attribute "PACK_TYPE" "0402"
					( Origin gFrontEnd )
				)
				( attribute "PART_NUMBER" "G21497-005"
					( Origin gFrontEnd )
				)
				( attribute "PHYS_PAGE" "107"
					( Origin gFrontEnd )
				)
				( attribute "ROT" "0"
					( Origin gFrontEnd )
				)
				( attribute "SEC" "1"
					( Origin gPackager )
				)
				( attribute "TOLERANCE" "5%"
					( Origin gFrontEnd )
				)
				( attribute "VALUE" "0.0"
					( Origin gFrontEnd )
				)
				( attribute "VER" "2"
					( Origin gFrontEnd )
				)
				( attribute "WATTAGE" "1/16W"
					( Origin gFrontEnd )
				)
				( attribute "XY" "(-1800,2800)"
					( Origin gFrontEnd )
				)
				( attribute "CHIPS_PART_NAME" "RES"
					( Origin gPackager )
				)
				( attribute "CDS_PART_NAME" "RES_0402-0.0,5%,1/16W,EMPTY,G2A"
					( Origin gPackager )
				)
				( objectStatus "R2U24" )
				( pin "a"
					( attribute "PN" "1"
						( Origin gPackager )
					)
					( objectStatus "R2U24.1" )
				)
				( pin "b"
					( attribute "PN" "2"
						( Origin gPackager )
					)
					( objectStatus "R2U24.2" )
				)
			)
			( gate "@baseboard_fab2_lib.baseboard_fab2(sch_1):page107_i472"
				( attribute "CDS_LIB" "mstr_discrete"
					( Origin gPackager )
				)
				( attribute "CDS_LOCATION" "R2U26"
					( Origin gPackager )
				)
				( attribute "CDS_SEC" "1"
					( Origin gPackager )
				)
				( attribute "LOCATION" "R2U26"
					( Origin gFrontEnd )
				)
				( attribute "MATERIAL" "EMPTY"
					( Origin gFrontEnd )
				)
				( attribute "PACK_TYPE" "0402"
					( Origin gFrontEnd )
				)
				( attribute "PART_NUMBER" "G21497-005"
					( Origin gFrontEnd )
				)
				( attribute "PHYS_PAGE" "107"
					( Origin gFrontEnd )
				)
				( attribute "ROT" "0"
					( Origin gFrontEnd )
				)
				( attribute "SEC" "1"
					( Origin gPackager )
				)
				( attribute "TOLERANCE" "5%"
					( Origin gFrontEnd )
				)
				( attribute "VALUE" "0.0"
					( Origin gFrontEnd )
				)
				( attribute "VER" "2"
					( Origin gFrontEnd )
				)
				( attribute "WATTAGE" "1/16W"
					( Origin gFrontEnd )
				)
				( attribute "XY" "(-2000,3100)"
					( Origin gFrontEnd )
				)
				( attribute "CHIPS_PART_NAME" "RES"
					( Origin gPackager )
				)
				( attribute "CDS_PART_NAME" "RES_0402-0.0,5%,1/16W,EMPTY,G2A"
					( Origin gPackager )
				)
				( objectStatus "R2U26" )
				( pin "a"
					( attribute "PN" "1"
						( Origin gPackager )
					)
					( objectStatus "R2U26.1" )
				)
				( pin "b"
					( attribute "PN" "2"
						( Origin gPackager )
					)
					( objectStatus "R2U26.2" )
				)
			)
			( gate "@baseboard_fab2_lib.baseboard_fab2(sch_1):page107_i473"
				( attribute "CDS_LIB" "mstr_discrete"
					( Origin gPackager )
				)
				( attribute "CDS_LOCATION" "R2U28"
					( Origin gPackager )
				)
				( attribute "CDS_SEC" "1"
					( Origin gPackager )
				)
				( attribute "LOCATION" "R2U28"
					( Origin gFrontEnd )
				)
				( attribute "MATERIAL" "EMPTY"
					( Origin gFrontEnd )
				)
				( attribute "PACK_TYPE" "0402"
					( Origin gFrontEnd )
				)
				( attribute "PART_NUMBER" "G21497-005"
					( Origin gFrontEnd )
				)
				( attribute "PHYS_PAGE" "107"
					( Origin gFrontEnd )
				)
				( attribute "ROT" "0"
					( Origin gFrontEnd )
				)
				( attribute "SEC" "1"
					( Origin gPackager )
				)
				( attribute "TOLERANCE" "5%"
					( Origin gFrontEnd )
				)
				( attribute "VALUE" "0.0"
					( Origin gFrontEnd )
				)
				( attribute "VER" "2"
					( Origin gFrontEnd )
				)
				( attribute "WATTAGE" "1/16W"
					( Origin gFrontEnd )
				)
				( attribute "XY" "(-2200,2800)"
					( Origin gFrontEnd )
				)
				( attribute "CHIPS_PART_NAME" "RES"
					( Origin gPackager )
				)
				( attribute "CDS_PART_NAME" "RES_0402-0.0,5%,1/16W,EMPTY,G2A"
					( Origin gPackager )
				)
				( objectStatus "R2U28" )
				( pin "a"
					( attribute "PN" "1"
						( Origin gPackager )
					)
					( objectStatus "R2U28.1" )
				)
				( pin "b"
					( attribute "PN" "2"
						( Origin gPackager )
					)
					( objectStatus "R2U28.2" )
				)
			)
			( gate "@baseboard_fab2_lib.baseboard_fab2(sch_1):page108_i1"
				( attribute "CDS_LIB" "dev_discrete"
					( Origin gPackager )
				)
				( attribute "CDS_LOCATION" "C2U20"
					( Origin gPackager )
				)
				( attribute "CDS_SEC" "1"
					( Origin gPackager )
				)
				( attribute "LOCATION" "C2U20"
					( Origin gFrontEnd )
				)
				( attribute "MATERIAL" "X7R"
					( Origin gFrontEnd )
				)
				( attribute "PACK_TYPE" "0402V"
					( Origin gFrontEnd )
				)
				( attribute "PART_NUMBER" "A36096-030"
					( Origin gFrontEnd )
				)
				( attribute "PHYS_PAGE" "108"
					( Origin gFrontEnd )
				)
				( attribute "ROOM" "IO_SLOT"
					( Origin gFrontEnd )
				)
				( attribute "ROT" "0"
					( Origin gFrontEnd )
				)
				( attribute "SEC" "1"
					( Origin gFrontEnd )
				)
				( attribute "SEC_TYPE" "0402V"
					( Origin gFrontEnd )
				)
				( attribute "TOLERANCE" "10%"
					( Origin gFrontEnd )
				)
				( attribute "VALUE" "0.1UF"
					( Origin gFrontEnd )
				)
				( attribute "VER" "1"
					( Origin gFrontEnd )
				)
				( attribute "VOLTAGE" "16V"
					( Units "uVoltage" "V" 1.000000)
					( Origin gFrontEnd )
				)
				( attribute "XY" "(-3275,675)"
					( Origin gFrontEnd )
				)
				( attribute "CHIPS_PART_NAME" "CAP_A"
					( Origin gPackager )
				)
				( attribute "CDS_PART_NAME" "CAP_A_0402V-0.1UF,16V,10%,X7R,A"
					( Origin gPackager )
				)
				( objectStatus "C2U20" )
				( pin "a"
					( attribute "PN" "1"
						( Origin gPackager )
					)
					( objectStatus "C2U20.1" )
				)
				( pin "b"
					( attribute "PN" "2"
						( Origin gPackager )
					)
					( objectStatus "C2U20.2" )
				)
			)
			( gate "@baseboard_fab2_lib.baseboard_fab2(sch_1):page108_i2"
				( attribute "CDS_LIB" "dev_discrete"
					( Origin gPackager )
				)
				( attribute "CDS_LOCATION" "C2U24"
					( Origin gPackager )
				)
				( attribute "CDS_SEC" "1"
					( Origin gPackager )
				)
				( attribute "LOCATION" "C2U24"
					( Origin gFrontEnd )
				)
				( attribute "MATERIAL" "X7R"
					( Origin gFrontEnd )
				)
				( attribute "PACK_TYPE" "0402V"
					( Origin gFrontEnd )
				)
				( attribute "PART_NUMBER" "A36096-030"
					( Origin gFrontEnd )
				)
				( attribute "PHYS_PAGE" "108"
					( Origin gFrontEnd )
				)
				( attribute "ROOM" "IO_SLOT"
					( Origin gFrontEnd )
				)
				( attribute "ROT" "0"
					( Origin gFrontEnd )
				)
				( attribute "SEC" "1"
					( Origin gFrontEnd )
				)
				( attribute "SEC_TYPE" "0402V"
					( Origin gFrontEnd )
				)
				( attribute "TOLERANCE" "10%"
					( Origin gFrontEnd )
				)
				( attribute "VALUE" "0.1UF"
					( Origin gFrontEnd )
				)
				( attribute "VER" "1"
					( Origin gFrontEnd )
				)
				( attribute "VOLTAGE" "16V"
					( Units "uVoltage" "V" 1.000000)
					( Origin gFrontEnd )
				)
				( attribute "XY" "(-2875,650)"
					( Origin gFrontEnd )
				)
				( attribute "CHIPS_PART_NAME" "CAP_A"
					( Origin gPackager )
				)
				( attribute "CDS_PART_NAME" "CAP_A_0402V-0.1UF,16V,10%,X7R,A"
					( Origin gPackager )
				)
				( objectStatus "C2U24" )
				( pin "a"
					( attribute "PN" "1"
						( Origin gPackager )
					)
					( objectStatus "C2U24.1" )
				)
				( pin "b"
					( attribute "PN" "2"
						( Origin gPackager )
					)
					( objectStatus "C2U24.2" )
				)
			)
			( gate "@baseboard_fab2_lib.baseboard_fab2(sch_1):page108_i5"
				( attribute "CDS_LIB" "dev_discrete"
					( Origin gPackager )
				)
				( attribute "CDS_LOCATION" "C2U21"
					( Origin gPackager )
				)
				( attribute "CDS_SEC" "1"
					( Origin gPackager )
				)
				( attribute "LOCATION" "C2U21"
					( Origin gFrontEnd )
				)
				( attribute "MATERIAL" "X7R"
					( Origin gFrontEnd )
				)
				( attribute "PACK_TYPE" "0402V"
					( Origin gFrontEnd )
				)
				( attribute "PART_NUMBER" "A36096-030"
					( Origin gFrontEnd )
				)
				( attribute "PHYS_PAGE" "108"
					( Origin gFrontEnd )
				)
				( attribute "ROOM" "IO_SLOT"
					( Origin gFrontEnd )
				)
				( attribute "ROT" "0"
					( Origin gFrontEnd )
				)
				( attribute "SEC" "1"
					( Origin gFrontEnd )
				)
				( attribute "SEC_TYPE" "0402V"
					( Origin gFrontEnd )
				)
				( attribute "TOLERANCE" "10%"
					( Origin gFrontEnd )
				)
				( attribute "VALUE" "0.1UF"
					( Origin gFrontEnd )
				)
				( attribute "VER" "1"
					( Origin gFrontEnd )
				)
				( attribute "VOLTAGE" "16V"
					( Units "uVoltage" "V" 1.000000)
					( Origin gFrontEnd )
				)
				( attribute "XY" "(-3275,1400)"
					( Origin gFrontEnd )
				)
				( attribute "CHIPS_PART_NAME" "CAP_A"
					( Origin gPackager )
				)
				( attribute "CDS_PART_NAME" "CAP_A_0402V-0.1UF,16V,10%,X7R,A"
					( Origin gPackager )
				)
				( objectStatus "C2U21" )
				( pin "a"
					( attribute "PN" "1"
						( Origin gPackager )
					)
					( objectStatus "C2U21.1" )
				)
				( pin "b"
					( attribute "PN" "2"
						( Origin gPackager )
					)
					( objectStatus "C2U21.2" )
				)
			)
			( gate "@baseboard_fab2_lib.baseboard_fab2(sch_1):page108_i7"
				( attribute "CDS_LIB" "dev_discrete"
					( Origin gPackager )
				)
				( attribute "CDS_LOCATION" "C2U25"
					( Origin gPackager )
				)
				( attribute "CDS_SEC" "1"
					( Origin gPackager )
				)
				( attribute "LOCATION" "C2U25"
					( Origin gFrontEnd )
				)
				( attribute "MATERIAL" "X7R"
					( Origin gFrontEnd )
				)
				( attribute "PACK_TYPE" "0402V"
					( Origin gFrontEnd )
				)
				( attribute "PART_NUMBER" "A36096-030"
					( Origin gFrontEnd )
				)
				( attribute "PHYS_PAGE" "108"
					( Origin gFrontEnd )
				)
				( attribute "ROOM" "IO_SLOT"
					( Origin gFrontEnd )
				)
				( attribute "ROT" "0"
					( Origin gFrontEnd )
				)
				( attribute "SEC" "1"
					( Origin gFrontEnd )
				)
				( attribute "SEC_TYPE" "0402V"
					( Origin gFrontEnd )
				)
				( attribute "TOLERANCE" "10%"
					( Origin gFrontEnd )
				)
				( attribute "VALUE" "0.1UF"
					( Origin gFrontEnd )
				)
				( attribute "VER" "1"
					( Origin gFrontEnd )
				)
				( attribute "VOLTAGE" "16V"
					( Units "uVoltage" "V" 1.000000)
					( Origin gFrontEnd )
				)
				( attribute "XY" "(-2875,1375)"
					( Origin gFrontEnd )
				)
				( attribute "CHIPS_PART_NAME" "CAP_A"
					( Origin gPackager )
				)
				( attribute "CDS_PART_NAME" "CAP_A_0402V-0.1UF,16V,10%,X7R,A"
					( Origin gPackager )
				)
				( objectStatus "C2U25" )
				( pin "a"
					( attribute "PN" "1"
						( Origin gPackager )
					)
					( objectStatus "C2U25.1" )
				)
				( pin "b"
					( attribute "PN" "2"
						( Origin gPackager )
					)
					( objectStatus "C2U25.2" )
				)
			)
			( gate "@baseboard_fab2_lib.baseboard_fab2(sch_1):page108_i173"
				( attribute "CDS_LIB" "mstr_discrete"
					( Origin gPackager )
				)
				( attribute "CDS_LOCATION" "R2U37"
					( Origin gPackager )
				)
				( attribute "CDS_SEC" "1"
					( Origin gPackager )
				)
				( attribute "LOCATION" "R2U37"
					( Origin gFrontEnd )
				)
				( attribute "MATERIAL" "CHIP"
					( Origin gFrontEnd )
				)
				( attribute "PACK_TYPE" "0402"
					( Origin gFrontEnd )
				)
				( attribute "PART_NUMBER" "G21497-005"
					( Origin gFrontEnd )
				)
				( attribute "PHYS_PAGE" "108"
					( Origin gFrontEnd )
				)
				( attribute "ROOM" "IO_SLOT"
					( Origin gFrontEnd )
				)
				( attribute "ROT" "0"
					( Origin gFrontEnd )
				)
				( attribute "SEC" "1"
					( Origin gFrontEnd )
				)
				( attribute "SEC_TYPE" "0402"
					( Origin gFrontEnd )
				)
				( attribute "TOLERANCE" "5%"
					( Origin gFrontEnd )
				)
				( attribute "VALUE" "0.0"
					( Origin gFrontEnd )
				)
				( attribute "VER" "1"
					( Origin gFrontEnd )
				)
				( attribute "WATTAGE" "1/16W"
					( Origin gFrontEnd )
				)
				( attribute "XY" "(-625,3625)"
					( Origin gFrontEnd )
				)
				( attribute "CHIPS_PART_NAME" "RES"
					( Origin gPackager )
				)
				( attribute "CDS_PART_NAME" "RES_0402-0.0,5%,1/16W,CHIP,G21A"
					( Origin gPackager )
				)
				( objectStatus "R2U37" )
				( pin "a"
					( attribute "PN" "1"
						( Origin gPackager )
					)
					( objectStatus "R2U37.1" )
				)
				( pin "b"
					( attribute "PN" "2"
						( Origin gPackager )
					)
					( objectStatus "R2U37.2" )
				)
			)
			( gate "@baseboard_fab2_lib.baseboard_fab2(sch_1):page108_i258"
				( attribute "CDS_LIB" "mstr_sconn"
					( Origin gPackager )
				)
				( attribute "CDS_LMAN_SYM_OUTLINE" "-250,1350,250,-1350"
					( Origin gPackager )
				)
				( attribute "CDS_LOCATION" "J8G1"
					( Origin gPackager )
				)
				( attribute "LOCATION" "J8G1"
					( Origin gFrontEnd )
				)
				( attribute "MATERIAL" "CONN"
					( Origin gFrontEnd )
				)
				( attribute "PACK_TYPE" "SM"
					( Origin gFrontEnd )
				)
				( attribute "PART_NUMBER" "H68296-001"
					( Origin gFrontEnd )
				)
				( attribute "PHYS_PAGE" "108"
					( Origin gFrontEnd )
				)
				( attribute "ROOM" "IO_SLOT"
					( Origin gFrontEnd )
				)
				( attribute "ROT" "0"
					( Origin gFrontEnd )
				)
				( attribute "SEC" "1"
					( Origin gFrontEnd )
				)
				( attribute "SEC_TYPE" "SM"
					( Origin gFrontEnd )
				)
				( attribute "VER" "1"
					( Origin gFrontEnd )
				)
				( attribute "XY" "(500,3075)"
					( Origin gFrontEnd )
				)
				( attribute "CHIPS_PART_NAME" "SCONN200_H68296001"
					( Origin gPackager )
				)
				( attribute "CDS_PART_NAME" "SCONN200_H68296001_SM-CONN,H68A"
					( Origin gPackager )
				)
				( attribute "CDS_SEC" "1"
					( Origin gPackager )
				)
				( objectStatus "J8G1" )
				( pin "io1"
					( attribute "PN" "1"
						( Origin gPackager )
					)
					( objectStatus "J8G1.1" )
				)
				( pin "io2"
					( attribute "PN" "2"
						( Origin gPackager )
					)
					( objectStatus "J8G1.2" )
				)
				( pin "io3"
					( attribute "PN" "3"
						( Origin gPackager )
					)
					( objectStatus "J8G1.3" )
				)
				( pin "io4"
					( attribute "PN" "4"
						( Origin gPackager )
					)
					( objectStatus "J8G1.4" )
				)
				( pin "io5"
					( attribute "PN" "5"
						( Origin gPackager )
					)
					( objectStatus "J8G1.5" )
				)
				( pin "io6"
					( attribute "PN" "6"
						( Origin gPackager )
					)
					( objectStatus "J8G1.6" )
				)
				( pin "io7"
					( attribute "PN" "7"
						( Origin gPackager )
					)
					( objectStatus "J8G1.7" )
				)
				( pin "io8"
					( attribute "PN" "8"
						( Origin gPackager )
					)
					( objectStatus "J8G1.8" )
				)
				( pin "io9"
					( attribute "PN" "9"
						( Origin gPackager )
					)
					( objectStatus "J8G1.9" )
				)
				( pin "io10"
					( attribute "PN" "10"
						( Origin gPackager )
					)
					( objectStatus "J8G1.10" )
				)
				( pin "io11"
					( attribute "PN" "11"
						( Origin gPackager )
					)
					( objectStatus "J8G1.11" )
				)
				( pin "io12"
					( attribute "PN" "12"
						( Origin gPackager )
					)
					( objectStatus "J8G1.12" )
				)
				( pin "io13"
					( attribute "PN" "13"
						( Origin gPackager )
					)
					( objectStatus "J8G1.13" )
				)
				( pin "io14"
					( attribute "PN" "14"
						( Origin gPackager )
					)
					( objectStatus "J8G1.14" )
				)
				( pin "io15"
					( attribute "PN" "15"
						( Origin gPackager )
					)
					( objectStatus "J8G1.15" )
				)
				( pin "io16"
					( attribute "PN" "16"
						( Origin gPackager )
					)
					( objectStatus "J8G1.16" )
				)
				( pin "io17"
					( attribute "PN" "17"
						( Origin gPackager )
					)
					( objectStatus "J8G1.17" )
				)
				( pin "io18"
					( attribute "PN" "18"
						( Origin gPackager )
					)
					( objectStatus "J8G1.18" )
				)
				( pin "io19"
					( attribute "PN" "19"
						( Origin gPackager )
					)
					( objectStatus "J8G1.19" )
				)
				( pin "io20"
					( attribute "PN" "20"
						( Origin gPackager )
					)
					( objectStatus "J8G1.20" )
				)
				( pin "io21"
					( attribute "PN" "21"
						( Origin gPackager )
					)
					( objectStatus "J8G1.21" )
				)
				( pin "io22"
					( attribute "PN" "22"
						( Origin gPackager )
					)
					( objectStatus "J8G1.22" )
				)
				( pin "io23"
					( attribute "PN" "23"
						( Origin gPackager )
					)
					( objectStatus "J8G1.23" )
				)
				( pin "io24"
					( attribute "PN" "24"
						( Origin gPackager )
					)
					( objectStatus "J8G1.24" )
				)
				( pin "io25"
					( attribute "PN" "25"
						( Origin gPackager )
					)
					( objectStatus "J8G1.25" )
				)
				( pin "io26"
					( attribute "PN" "26"
						( Origin gPackager )
					)
					( objectStatus "J8G1.26" )
				)
				( pin "io27"
					( attribute "PN" "27"
						( Origin gPackager )
					)
					( objectStatus "J8G1.27" )
				)
				( pin "io28"
					( attribute "PN" "28"
						( Origin gPackager )
					)
					( objectStatus "J8G1.28" )
				)
				( pin "io29"
					( attribute "PN" "29"
						( Origin gPackager )
					)
					( objectStatus "J8G1.29" )
				)
				( pin "io30"
					( attribute "PN" "30"
						( Origin gPackager )
					)
					( objectStatus "J8G1.30" )
				)
				( pin "io31"
					( attribute "PN" "31"
						( Origin gPackager )
					)
					( objectStatus "J8G1.31" )
				)
				( pin "io32"
					( attribute "PN" "32"
						( Origin gPackager )
					)
					( objectStatus "J8G1.32" )
				)
				( pin "io33"
					( attribute "PN" "33"
						( Origin gPackager )
					)
					( objectStatus "J8G1.33" )
				)
				( pin "io34"
					( attribute "PN" "34"
						( Origin gPackager )
					)
					( objectStatus "J8G1.34" )
				)
				( pin "io35"
					( attribute "PN" "35"
						( Origin gPackager )
					)
					( objectStatus "J8G1.35" )
				)
				( pin "io36"
					( attribute "PN" "36"
						( Origin gPackager )
					)
					( objectStatus "J8G1.36" )
				)
				( pin "io37"
					( attribute "PN" "37"
						( Origin gPackager )
					)
					( objectStatus "J8G1.37" )
				)
				( pin "io38"
					( attribute "PN" "38"
						( Origin gPackager )
					)
					( objectStatus "J8G1.38" )
				)
				( pin "io39"
					( attribute "PN" "39"
						( Origin gPackager )
					)
					( objectStatus "J8G1.39" )
				)
				( pin "io40"
					( attribute "PN" "40"
						( Origin gPackager )
					)
					( objectStatus "J8G1.40" )
				)
				( pin "io41"
					( attribute "PN" "41"
						( Origin gPackager )
					)
					( objectStatus "J8G1.41" )
				)
				( pin "io42"
					( attribute "PN" "42"
						( Origin gPackager )
					)
					( objectStatus "J8G1.42" )
				)
				( pin "io43"
					( attribute "PN" "43"
						( Origin gPackager )
					)
					( objectStatus "J8G1.43" )
				)
				( pin "io44"
					( attribute "PN" "44"
						( Origin gPackager )
					)
					( objectStatus "J8G1.44" )
				)
				( pin "io45"
					( attribute "PN" "45"
						( Origin gPackager )
					)
					( objectStatus "J8G1.45" )
				)
				( pin "io46"
					( attribute "PN" "46"
						( Origin gPackager )
					)
					( objectStatus "J8G1.46" )
				)
				( pin "io47"
					( attribute "PN" "47"
						( Origin gPackager )
					)
					( objectStatus "J8G1.47" )
				)
				( pin "io48"
					( attribute "PN" "48"
						( Origin gPackager )
					)
					( objectStatus "J8G1.48" )
				)
				( pin "io49"
					( attribute "PN" "49"
						( Origin gPackager )
					)
					( objectStatus "J8G1.49" )
				)
				( pin "io50"
					( attribute "PN" "50"
						( Origin gPackager )
					)
					( objectStatus "J8G1.50" )
				)
				( pin "io51"
					( attribute "PN" "51"
						( Origin gPackager )
					)
					( objectStatus "J8G1.51" )
				)
				( pin "io52"
					( attribute "PN" "52"
						( Origin gPackager )
					)
					( objectStatus "J8G1.52" )
				)
				( pin "io53"
					( attribute "PN" "53"
						( Origin gPackager )
					)
					( objectStatus "J8G1.53" )
				)
				( pin "io54"
					( attribute "PN" "54"
						( Origin gPackager )
					)
					( objectStatus "J8G1.54" )
				)
				( pin "io55"
					( attribute "PN" "55"
						( Origin gPackager )
					)
					( objectStatus "J8G1.55" )
				)
				( pin "io56"
					( attribute "PN" "56"
						( Origin gPackager )
					)
					( objectStatus "J8G1.56" )
				)
				( pin "io57"
					( attribute "PN" "57"
						( Origin gPackager )
					)
					( objectStatus "J8G1.57" )
				)
				( pin "io58"
					( attribute "PN" "58"
						( Origin gPackager )
					)
					( objectStatus "J8G1.58" )
				)
				( pin "io59"
					( attribute "PN" "59"
						( Origin gPackager )
					)
					( objectStatus "J8G1.59" )
				)
				( pin "io60"
					( attribute "PN" "60"
						( Origin gPackager )
					)
					( objectStatus "J8G1.60" )
				)
				( pin "io61"
					( attribute "PN" "61"
						( Origin gPackager )
					)
					( objectStatus "J8G1.61" )
				)
				( pin "io62"
					( attribute "PN" "62"
						( Origin gPackager )
					)
					( objectStatus "J8G1.62" )
				)
				( pin "io63"
					( attribute "PN" "63"
						( Origin gPackager )
					)
					( objectStatus "J8G1.63" )
				)
				( pin "io64"
					( attribute "PN" "64"
						( Origin gPackager )
					)
					( objectStatus "J8G1.64" )
				)
				( pin "io65"
					( attribute "PN" "65"
						( Origin gPackager )
					)
					( objectStatus "J8G1.65" )
				)
				( pin "io66"
					( attribute "PN" "66"
						( Origin gPackager )
					)
					( objectStatus "J8G1.66" )
				)
				( pin "io67"
					( attribute "PN" "67"
						( Origin gPackager )
					)
					( objectStatus "J8G1.67" )
				)
				( pin "io68"
					( attribute "PN" "68"
						( Origin gPackager )
					)
					( objectStatus "J8G1.68" )
				)
				( pin "io69"
					( attribute "PN" "69"
						( Origin gPackager )
					)
					( objectStatus "J8G1.69" )
				)
				( pin "io70"
					( attribute "PN" "70"
						( Origin gPackager )
					)
					( objectStatus "J8G1.70" )
				)
				( pin "io71"
					( attribute "PN" "71"
						( Origin gPackager )
					)
					( objectStatus "J8G1.71" )
				)
				( pin "io72"
					( attribute "PN" "72"
						( Origin gPackager )
					)
					( objectStatus "J8G1.72" )
				)
				( pin "io73"
					( attribute "PN" "73"
						( Origin gPackager )
					)
					( objectStatus "J8G1.73" )
				)
				( pin "io74"
					( attribute "PN" "74"
						( Origin gPackager )
					)
					( objectStatus "J8G1.74" )
				)
				( pin "io75"
					( attribute "PN" "75"
						( Origin gPackager )
					)
					( objectStatus "J8G1.75" )
				)
				( pin "io76"
					( attribute "PN" "76"
						( Origin gPackager )
					)
					( objectStatus "J8G1.76" )
				)
				( pin "io77"
					( attribute "PN" "77"
						( Origin gPackager )
					)
					( objectStatus "J8G1.77" )
				)
				( pin "io78"
					( attribute "PN" "78"
						( Origin gPackager )
					)
					( objectStatus "J8G1.78" )
				)
				( pin "io79"
					( attribute "PN" "79"
						( Origin gPackager )
					)
					( objectStatus "J8G1.79" )
				)
				( pin "io80"
					( attribute "PN" "80"
						( Origin gPackager )
					)
					( objectStatus "J8G1.80" )
				)
				( pin "io81"
					( attribute "PN" "81"
						( Origin gPackager )
					)
					( objectStatus "J8G1.81" )
				)
				( pin "io82"
					( attribute "PN" "82"
						( Origin gPackager )
					)
					( objectStatus "J8G1.82" )
				)
				( pin "io83"
					( attribute "PN" "83"
						( Origin gPackager )
					)
					( objectStatus "J8G1.83" )
				)
				( pin "io84"
					( attribute "PN" "84"
						( Origin gPackager )
					)
					( objectStatus "J8G1.84" )
				)
				( pin "io85"
					( attribute "PN" "85"
						( Origin gPackager )
					)
					( objectStatus "J8G1.85" )
				)
				( pin "io86"
					( attribute "PN" "86"
						( Origin gPackager )
					)
					( objectStatus "J8G1.86" )
				)
				( pin "io87"
					( attribute "PN" "87"
						( Origin gPackager )
					)
					( objectStatus "J8G1.87" )
				)
				( pin "io88"
					( attribute "PN" "88"
						( Origin gPackager )
					)
					( objectStatus "J8G1.88" )
				)
				( pin "io89"
					( attribute "PN" "89"
						( Origin gPackager )
					)
					( objectStatus "J8G1.89" )
				)
				( pin "io90"
					( attribute "PN" "90"
						( Origin gPackager )
					)
					( objectStatus "J8G1.90" )
				)
				( pin "io91"
					( attribute "PN" "91"
						( Origin gPackager )
					)
					( objectStatus "J8G1.91" )
				)
				( pin "io92"
					( attribute "PN" "92"
						( Origin gPackager )
					)
					( objectStatus "J8G1.92" )
				)
				( pin "io93"
					( attribute "PN" "93"
						( Origin gPackager )
					)
					( objectStatus "J8G1.93" )
				)
				( pin "io94"
					( attribute "PN" "94"
						( Origin gPackager )
					)
					( objectStatus "J8G1.94" )
				)
				( pin "io95"
					( attribute "PN" "95"
						( Origin gPackager )
					)
					( objectStatus "J8G1.95" )
				)
				( pin "io96"
					( attribute "PN" "96"
						( Origin gPackager )
					)
					( objectStatus "J8G1.96" )
				)
				( pin "io97"
					( attribute "PN" "97"
						( Origin gPackager )
					)
					( objectStatus "J8G1.97" )
				)
				( pin "io98"
					( attribute "PN" "98"
						( Origin gPackager )
					)
					( objectStatus "J8G1.98" )
				)
				( pin "io99"
					( attribute "PN" "99"
						( Origin gPackager )
					)
					( objectStatus "J8G1.99" )
				)
				( pin "io100"
					( attribute "PN" "100"
						( Origin gPackager )
					)
					( objectStatus "J8G1.100" )
				)
				( pin "mh1"
					( attribute "PN" "MH1"
						( Origin gPackager )
					)
					( objectStatus "J8G1.MH1" )
				)
				( pin "mh2"
					( attribute "PN" "MH2"
						( Origin gPackager )
					)
					( objectStatus "J8G1.MH2" )
				)
			)
			( gate "@baseboard_fab2_lib.baseboard_fab2(sch_1):page108_i315"
				( attribute "CDS_LIB" "dev_discrete"
					( Origin gPackager )
				)
				( attribute "CDS_LOCATION" "C2U23"
					( Origin gPackager )
				)
				( attribute "CDS_SEC" "1"
					( Origin gPackager )
				)
				( attribute "LOCATION" "C2U23"
					( Origin gFrontEnd )
				)
				( attribute "MATERIAL" "X7R"
					( Origin gFrontEnd )
				)
				( attribute "PACK_TYPE" "0402V"
					( Origin gFrontEnd )
				)
				( attribute "PART_NUMBER" "A36096-030"
					( Origin gFrontEnd )
				)
				( attribute "PHYS_PAGE" "108"
					( Origin gFrontEnd )
				)
				( attribute "ROOM" "IO_SLOT"
					( Origin gFrontEnd )
				)
				( attribute "ROT" "0"
					( Origin gFrontEnd )
				)
				( attribute "SEC" "1"
					( Origin gFrontEnd )
				)
				( attribute "SEC_TYPE" "0402V"
					( Origin gFrontEnd )
				)
				( attribute "TOLERANCE" "10%"
					( Origin gFrontEnd )
				)
				( attribute "VALUE" "0.1UF"
					( Origin gFrontEnd )
				)
				( attribute "VER" "1"
					( Origin gFrontEnd )
				)
				( attribute "VOLTAGE" "16V"
					( Units "uVoltage" "V" 1.000000)
					( Origin gFrontEnd )
				)
				( attribute "XY" "(-1950,1350)"
					( Origin gFrontEnd )
				)
				( attribute "CHIPS_PART_NAME" "CAP_A"
					( Origin gPackager )
				)
				( attribute "CDS_PART_NAME" "CAP_A_0402V-0.1UF,16V,10%,X7R,A"
					( Origin gPackager )
				)
				( objectStatus "C2U23" )
				( pin "a"
					( attribute "PN" "1"
						( Origin gPackager )
					)
					( objectStatus "C2U23.1" )
				)
				( pin "b"
					( attribute "PN" "2"
						( Origin gPackager )
					)
					( objectStatus "C2U23.2" )
				)
			)
			( gate "@baseboard_fab2_lib.baseboard_fab2(sch_1):page108_i318"
				( attribute "CDS_LIB" "dev_discrete"
					( Origin gPackager )
				)
				( attribute "CDS_LOCATION" "C2U22"
					( Origin gPackager )
				)
				( attribute "CDS_SEC" "1"
					( Origin gPackager )
				)
				( attribute "LOCATION" "C2U22"
					( Origin gFrontEnd )
				)
				( attribute "MATERIAL" "X7R"
					( Origin gFrontEnd )
				)
				( attribute "PACK_TYPE" "0402V"
					( Origin gFrontEnd )
				)
				( attribute "PART_NUMBER" "A36096-030"
					( Origin gFrontEnd )
				)
				( attribute "PHYS_PAGE" "108"
					( Origin gFrontEnd )
				)
				( attribute "ROOM" "IO_SLOT"
					( Origin gFrontEnd )
				)
				( attribute "ROT" "0"
					( Origin gFrontEnd )
				)
				( attribute "SEC" "1"
					( Origin gFrontEnd )
				)
				( attribute "SEC_TYPE" "0402V"
					( Origin gFrontEnd )
				)
				( attribute "TOLERANCE" "10%"
					( Origin gFrontEnd )
				)
				( attribute "VALUE" "0.1UF"
					( Origin gFrontEnd )
				)
				( attribute "VER" "1"
					( Origin gFrontEnd )
				)
				( attribute "VOLTAGE" "16V"
					( Units "uVoltage" "V" 1.000000)
					( Origin gFrontEnd )
				)
				( attribute "XY" "(-2350,1375)"
					( Origin gFrontEnd )
				)
				( attribute "CHIPS_PART_NAME" "CAP_A"
					( Origin gPackager )
				)
				( attribute "CDS_PART_NAME" "CAP_A_0402V-0.1UF,16V,10%,X7R,A"
					( Origin gPackager )
				)
				( objectStatus "C2U22" )
				( pin "a"
					( attribute "PN" "1"
						( Origin gPackager )
					)
					( objectStatus "C2U22.1" )
				)
				( pin "b"
					( attribute "PN" "2"
						( Origin gPackager )
					)
					( objectStatus "C2U22.2" )
				)
			)
			( gate "@baseboard_fab2_lib.baseboard_fab2(sch_1):page108_i320"
				( attribute "BOM_COST" "SM_CONTROLLER"
					( Origin gFrontEnd )
				)
				( attribute "CDS_LIB" "mstr_discrete"
					( Origin gPackager )
				)
				( attribute "CDS_LOCATION" "R2U35"
					( Origin gPackager )
				)
				( attribute "CDS_SEC" "1"
					( Origin gPackager )
				)
				( attribute "LOCATION" "R2U35"
					( Origin gFrontEnd )
				)
				( attribute "MATERIAL" "EMPTY"
					( Origin gFrontEnd )
				)
				( attribute "PACK_TYPE" "0402"
					( Origin gFrontEnd )
				)
				( attribute "PART_NUMBER" "G21796-173"
					( Origin gFrontEnd )
				)
				( attribute "PHYS_PAGE" "108"
					( Origin gFrontEnd )
				)
				( attribute "ROOM" "SMBUS"
					( Origin gFrontEnd )
				)
				( attribute "ROT" "0"
					( Origin gFrontEnd )
				)
				( attribute "SEC" "1"
					( Origin gPackager )
				)
				( attribute "SKU" "A"
					( Origin gFrontEnd )
				)
				( attribute "TOLERANCE" "1%"
					( Origin gFrontEnd )
				)
				( attribute "VALUE" "20.0"
					( Origin gFrontEnd )
				)
				( attribute "VER" "1"
					( Origin gFrontEnd )
				)
				( attribute "WATTAGE" "1/16W"
					( Origin gFrontEnd )
				)
				( attribute "XY" "(-2400,4600)"
					( Origin gFrontEnd )
				)
				( attribute "CHIPS_PART_NAME" "RES"
					( Origin gPackager )
				)
				( attribute "CDS_PART_NAME" "RES_0402-20.0,1%,1/16W,EMPTY,GA"
					( Origin gPackager )
				)
				( objectStatus "R2U35" )
				( pin "a"
					( attribute "PN" "1"
						( Origin gPackager )
					)
					( objectStatus "R2U35.1" )
				)
				( pin "b"
					( attribute "PN" "2"
						( Origin gPackager )
					)
					( objectStatus "R2U35.2" )
				)
			)
			( gate "@baseboard_fab2_lib.baseboard_fab2(sch_1):page108_i330"
				( attribute "BOM_COST" "SM_CONTROLLER"
					( Origin gFrontEnd )
				)
				( attribute "CDS_LIB" "mstr_discrete"
					( Origin gPackager )
				)
				( attribute "CDS_LOCATION" "R2U31"
					( Origin gPackager )
				)
				( attribute "CDS_SEC" "1"
					( Origin gPackager )
				)
				( attribute "LOCATION" "R2U31"
					( Origin gFrontEnd )
				)
				( attribute "MATERIAL" "CHIP"
					( Origin gFrontEnd )
				)
				( attribute "PACK_TYPE" "0402"
					( Origin gFrontEnd )
				)
				( attribute "PART_NUMBER" "G21796-173"
					( Origin gFrontEnd )
				)
				( attribute "PHYS_PAGE" "108"
					( Origin gFrontEnd )
				)
				( attribute "ROOM" "SMBUS"
					( Origin gFrontEnd )
				)
				( attribute "ROT" "0"
					( Origin gFrontEnd )
				)
				( attribute "SEC" "1"
					( Origin gPackager )
				)
				( attribute "SKU" "B"
					( Origin gFrontEnd )
				)
				( attribute "TOLERANCE" "1%"
					( Origin gFrontEnd )
				)
				( attribute "VALUE" "20.0"
					( Origin gFrontEnd )
				)
				( attribute "VER" "1"
					( Origin gFrontEnd )
				)
				( attribute "WATTAGE" "1/16W"
					( Origin gFrontEnd )
				)
				( attribute "XY" "(-2400,4500)"
					( Origin gFrontEnd )
				)
				( attribute "CHIPS_PART_NAME" "RES"
					( Origin gPackager )
				)
				( attribute "CDS_PART_NAME" "RES_0402-20.0,1%,1/16W,CHIP,G2A"
					( Origin gPackager )
				)
				( objectStatus "R2U31" )
				( pin "a"
					( attribute "PN" "1"
						( Origin gPackager )
					)
					( objectStatus "R2U31.1" )
				)
				( pin "b"
					( attribute "PN" "2"
						( Origin gPackager )
					)
					( objectStatus "R2U31.2" )
				)
			)
			( gate "@baseboard_fab2_lib.baseboard_fab2(sch_1):page108_i339"
				( attribute "BOM_COST" "SM_CONTROLLER"
					( Origin gFrontEnd )
				)
				( attribute "CDS_LIB" "mstr_discrete"
					( Origin gPackager )
				)
				( attribute "CDS_LOCATION" "R2U32"
					( Origin gPackager )
				)
				( attribute "CDS_SEC" "1"
					( Origin gPackager )
				)
				( attribute "LOCATION" "R2U32"
					( Origin gFrontEnd )
				)
				( attribute "MATERIAL" "CHIP"
					( Origin gFrontEnd )
				)
				( attribute "PACK_TYPE" "0402"
					( Origin gFrontEnd )
				)
				( attribute "PART_NUMBER" "G21796-173"
					( Origin gFrontEnd )
				)
				( attribute "PHYS_PAGE" "108"
					( Origin gFrontEnd )
				)
				( attribute "ROOM" "SMBUS"
					( Origin gFrontEnd )
				)
				( attribute "ROT" "0"
					( Origin gFrontEnd )
				)
				( attribute "SEC" "1"
					( Origin gPackager )
				)
				( attribute "SKU" "B"
					( Origin gFrontEnd )
				)
				( attribute "TOLERANCE" "1%"
					( Origin gFrontEnd )
				)
				( attribute "VALUE" "20.0"
					( Origin gFrontEnd )
				)
				( attribute "VER" "1"
					( Origin gFrontEnd )
				)
				( attribute "WATTAGE" "1/16W"
					( Origin gFrontEnd )
				)
				( attribute "XY" "(-2400,4250)"
					( Origin gFrontEnd )
				)
				( attribute "CHIPS_PART_NAME" "RES"
					( Origin gPackager )
				)
				( attribute "CDS_PART_NAME" "RES_0402-20.0,1%,1/16W,CHIP,G2A"
					( Origin gPackager )
				)
				( objectStatus "R2U32" )
				( pin "a"
					( attribute "PN" "1"
						( Origin gPackager )
					)
					( objectStatus "R2U32.1" )
				)
				( pin "b"
					( attribute "PN" "2"
						( Origin gPackager )
					)
					( objectStatus "R2U32.2" )
				)
			)
			( gate "@baseboard_fab2_lib.baseboard_fab2(sch_1):page108_i340"
				( attribute "BOM_COST" "SM_CONTROLLER"
					( Origin gFrontEnd )
				)
				( attribute "CDS_LIB" "mstr_discrete"
					( Origin gPackager )
				)
				( attribute "CDS_LOCATION" "R2U36"
					( Origin gPackager )
				)
				( attribute "CDS_SEC" "1"
					( Origin gPackager )
				)
				( attribute "LOCATION" "R2U36"
					( Origin gFrontEnd )
				)
				( attribute "MATERIAL" "EMPTY"
					( Origin gFrontEnd )
				)
				( attribute "PACK_TYPE" "0402"
					( Origin gFrontEnd )
				)
				( attribute "PART_NUMBER" "G21796-173"
					( Origin gFrontEnd )
				)
				( attribute "PHYS_PAGE" "108"
					( Origin gFrontEnd )
				)
				( attribute "ROOM" "SMBUS"
					( Origin gFrontEnd )
				)
				( attribute "ROT" "0"
					( Origin gFrontEnd )
				)
				( attribute "SEC" "1"
					( Origin gPackager )
				)
				( attribute "SKU" "A"
					( Origin gFrontEnd )
				)
				( attribute "TOLERANCE" "1%"
					( Origin gFrontEnd )
				)
				( attribute "VALUE" "20.0"
					( Origin gFrontEnd )
				)
				( attribute "VER" "1"
					( Origin gFrontEnd )
				)
				( attribute "WATTAGE" "1/16W"
					( Origin gFrontEnd )
				)
				( attribute "XY" "(-2400,4350)"
					( Origin gFrontEnd )
				)
				( attribute "CHIPS_PART_NAME" "RES"
					( Origin gPackager )
				)
				( attribute "CDS_PART_NAME" "RES_0402-20.0,1%,1/16W,EMPTY,GA"
					( Origin gPackager )
				)
				( objectStatus "R2U36" )
				( pin "a"
					( attribute "PN" "1"
						( Origin gPackager )
					)
					( objectStatus "R2U36.1" )
				)
				( pin "b"
					( attribute "PN" "2"
						( Origin gPackager )
					)
					( objectStatus "R2U36.2" )
				)
			)
			( gate "@baseboard_fab2_lib.baseboard_fab2(sch_1):page108_i341"
				( attribute "CDS_LIB" "mstr_discrete"
					( Origin gPackager )
				)
				( attribute "CDS_LOCATION" "R7E22"
					( Origin gPackager )
				)
				( attribute "CDS_SEC" "1"
					( Origin gPackager )
				)
				( attribute "LOCATION" "R7E22"
					( Origin gFrontEnd )
				)
				( attribute "MATERIAL" "CHIP"
					( Origin gFrontEnd )
				)
				( attribute "PACK_TYPE" "0402"
					( Origin gFrontEnd )
				)
				( attribute "PART_NUMBER" "G21497-005"
					( Origin gFrontEnd )
				)
				( attribute "PHYS_PAGE" "108"
					( Origin gFrontEnd )
				)
				( attribute "ROOM" "IO_SLOT"
					( Origin gFrontEnd )
				)
				( attribute "ROT" "0"
					( Origin gFrontEnd )
				)
				( attribute "SEC" "1"
					( Origin gFrontEnd )
				)
				( attribute "SEC_TYPE" "0402"
					( Origin gFrontEnd )
				)
				( attribute "TOLERANCE" "5%"
					( Origin gFrontEnd )
				)
				( attribute "VALUE" "0.0"
					( Origin gFrontEnd )
				)
				( attribute "VER" "1"
					( Origin gFrontEnd )
				)
				( attribute "WATTAGE" "1/16W"
					( Origin gFrontEnd )
				)
				( attribute "XY" "(2375,3775)"
					( Origin gFrontEnd )
				)
				( attribute "CHIPS_PART_NAME" "RES"
					( Origin gPackager )
				)
				( attribute "CDS_PART_NAME" "RES_0402-0.0,5%,1/16W,CHIP,G21A"
					( Origin gPackager )
				)
				( objectStatus "R7E22" )
				( pin "a"
					( attribute "PN" "1"
						( Origin gPackager )
					)
					( objectStatus "R7E22.1" )
				)
				( pin "b"
					( attribute "PN" "2"
						( Origin gPackager )
					)
					( objectStatus "R7E22.2" )
				)
			)
			( gate "@baseboard_fab2_lib.baseboard_fab2(sch_1):page108_i343"
				( attribute "CDS_LIB" "mstr_discrete"
					( Origin gPackager )
				)
				( attribute "CDS_LOCATION" "R7E21"
					( Origin gPackager )
				)
				( attribute "CDS_SEC" "1"
					( Origin gPackager )
				)
				( attribute "LOCATION" "R7E21"
					( Origin gFrontEnd )
				)
				( attribute "MATERIAL" "CHIP"
					( Origin gFrontEnd )
				)
				( attribute "PACK_TYPE" "0402"
					( Origin gFrontEnd )
				)
				( attribute "PART_NUMBER" "G21796-072"
					( Origin gFrontEnd )
				)
				( attribute "PHYS_PAGE" "108"
					( Origin gFrontEnd )
				)
				( attribute "ROOM" "IO_SLOT"
					( Origin gFrontEnd )
				)
				( attribute "ROT" "0"
					( Origin gFrontEnd )
				)
				( attribute "SEC" "1"
					( Origin gFrontEnd )
				)
				( attribute "SEC_TYPE" "0402"
					( Origin gFrontEnd )
				)
				( attribute "TOLERANCE" "1%"
					( Origin gFrontEnd )
				)
				( attribute "VALUE" "4.75K"
					( Origin gFrontEnd )
				)
				( attribute "VER" "2"
					( Origin gFrontEnd )
				)
				( attribute "WATTAGE" "1/16W"
					( Origin gFrontEnd )
				)
				( attribute "XY" "(2225,4300)"
					( Origin gFrontEnd )
				)
				( attribute "CHIPS_PART_NAME" "RES"
					( Origin gPackager )
				)
				( attribute "CDS_PART_NAME" "RES_0402-4.75K,1%,1/16W,CHIP,GA"
					( Origin gPackager )
				)
				( objectStatus "R7E21" )
				( pin "a"
					( attribute "PN" "1"
						( Origin gPackager )
					)
					( objectStatus "R7E21.1" )
				)
				( pin "b"
					( attribute "PN" "2"
						( Origin gPackager )
					)
					( objectStatus "R7E21.2" )
				)
			)
			( gate "@baseboard_fab2_lib.baseboard_fab2(sch_1):page110_i1"
				( attribute "CDS_LIB" "mstr_misc"
					( Origin gPackager )
				)
				( attribute "CDS_LOCATION" "TC9F1"
					( Origin gPackager )
				)
				( attribute "CDS_SEC" "1"
					( Origin gPackager )
				)
				( attribute "LOCATION" "TC9F1"
					( Origin gFrontEnd )
				)
				( attribute "MATERIAL" "EMPTY"
					( Origin gFrontEnd )
				)
				( attribute "PACK_TYPE" "ID4"
					( Origin gFrontEnd )
				)
				( attribute "PART_NUMBER" "N_A"
					( Origin gFrontEnd )
				)
				( attribute "PHYS_PAGE" "110"
					( Origin gFrontEnd )
				)
				( attribute "ROT" "0"
					( Origin gFrontEnd )
				)
				( attribute "SEC" "1"
					( Origin gPackager )
				)
				( attribute "VER" "1"
					( Origin gFrontEnd )
				)
				( attribute "XY" "(-425,1350)"
					( Origin gFrontEnd )
				)
				( attribute "CHIPS_PART_NAME" "RCC_DFX1940"
					( Origin gPackager )
				)
				( attribute "CDS_PART_NAME" "RCC_DFX1940_ID4-EMPTY,N_A"
					( Origin gPackager )
				)
				( objectStatus "TC9F1" )
				( pin "gnd"
					( attribute "PN" "1"
						( Origin gPackager )
					)
					( objectStatus "TC9F1.1" )
				)
				( pin "io1"
					( attribute "PN" "2"
						( Origin gPackager )
					)
					( objectStatus "TC9F1.2" )
				)
				( pin "io2"
					( attribute "PN" "3"
						( Origin gPackager )
					)
					( objectStatus "TC9F1.3" )
				)
			)
			( gate "@baseboard_fab2_lib.baseboard_fab2(sch_1):page110_i3"
				( attribute "CDS_LIB" "mstr_misc"
					( Origin gPackager )
				)
				( attribute "CDS_LOCATION" "TC1G1"
					( Origin gPackager )
				)
				( attribute "CDS_SEC" "1"
					( Origin gPackager )
				)
				( attribute "LOCATION" "TC1G1"
					( Origin gFrontEnd )
				)
				( attribute "MATERIAL" "EMPTY"
					( Origin gFrontEnd )
				)
				( attribute "PACK_TYPE" "ID4"
					( Origin gFrontEnd )
				)
				( attribute "PART_NUMBER" "N_A"
					( Origin gFrontEnd )
				)
				( attribute "PHYS_PAGE" "110"
					( Origin gFrontEnd )
				)
				( attribute "ROT" "0"
					( Origin gFrontEnd )
				)
				( attribute "SEC" "1"
					( Origin gPackager )
				)
				( attribute "VER" "1"
					( Origin gFrontEnd )
				)
				( attribute "XY" "(-400,925)"
					( Origin gFrontEnd )
				)
				( attribute "CHIPS_PART_NAME" "RCC_DFX1940"
					( Origin gPackager )
				)
				( attribute "CDS_PART_NAME" "RCC_DFX1940_ID4-EMPTY,N_A"
					( Origin gPackager )
				)
				( objectStatus "TC1G1" )
				( pin "gnd"
					( attribute "PN" "1"
						( Origin gPackager )
					)
					( objectStatus "TC1G1.1" )
				)
				( pin "io1"
					( attribute "PN" "2"
						( Origin gPackager )
					)
					( objectStatus "TC1G1.2" )
				)
				( pin "io2"
					( attribute "PN" "3"
						( Origin gPackager )
					)
					( objectStatus "TC1G1.3" )
				)
			)
			( gate "@baseboard_fab2_lib.baseboard_fab2(sch_1):page110_i7"
				( attribute "CDS_LIB" "mstr_misc"
					( Origin gPackager )
				)
				( attribute "CDS_LOCATION" "TC1A1"
					( Origin gPackager )
				)
				( attribute "CDS_SEC" "1"
					( Origin gPackager )
				)
				( attribute "LOCATION" "TC1A1"
					( Origin gFrontEnd )
				)
				( attribute "MATERIAL" "EMPTY"
					( Origin gFrontEnd )
				)
				( attribute "PACK_TYPE" "ID4"
					( Origin gFrontEnd )
				)
				( attribute "PART_NUMBER" "N_A"
					( Origin gFrontEnd )
				)
				( attribute "PHYS_PAGE" "110"
					( Origin gFrontEnd )
				)
				( attribute "ROT" "0"
					( Origin gFrontEnd )
				)
				( attribute "SEC" "1"
					( Origin gPackager )
				)
				( attribute "VER" "1"
					( Origin gFrontEnd )
				)
				( attribute "XY" "(-2075,1325)"
					( Origin gFrontEnd )
				)
				( attribute "CHIPS_PART_NAME" "RCC_DFX1940"
					( Origin gPackager )
				)
				( attribute "CDS_PART_NAME" "RCC_DFX1940_ID4-EMPTY,N_A"
					( Origin gPackager )
				)
				( objectStatus "TC1A1" )
				( pin "gnd"
					( attribute "PN" "1"
						( Origin gPackager )
					)
					( objectStatus "TC1A1.1" )
				)
				( pin "io1"
					( attribute "PN" "2"
						( Origin gPackager )
					)
					( objectStatus "TC1A1.2" )
				)
				( pin "io2"
					( attribute "PN" "3"
						( Origin gPackager )
					)
					( objectStatus "TC1A1.3" )
				)
			)
			( gate "@baseboard_fab2_lib.baseboard_fab2(sch_1):page110_i9"
				( attribute "CDS_LIB" "mstr_misc"
					( Origin gPackager )
				)
				( attribute "CDS_LOCATION" "TC9A1"
					( Origin gPackager )
				)
				( attribute "CDS_SEC" "1"
					( Origin gPackager )
				)
				( attribute "LOCATION" "TC9A1"
					( Origin gFrontEnd )
				)
				( attribute "MATERIAL" "EMPTY"
					( Origin gFrontEnd )
				)
				( attribute "PACK_TYPE" "ID4"
					( Origin gFrontEnd )
				)
				( attribute "PART_NUMBER" "N_A"
					( Origin gFrontEnd )
				)
				( attribute "PHYS_PAGE" "110"
					( Origin gFrontEnd )
				)
				( attribute "ROT" "0"
					( Origin gFrontEnd )
				)
				( attribute "SEC" "1"
					( Origin gPackager )
				)
				( attribute "VER" "1"
					( Origin gFrontEnd )
				)
				( attribute "XY" "(-2050,925)"
					( Origin gFrontEnd )
				)
				( attribute "CHIPS_PART_NAME" "RCC_DFX1940"
					( Origin gPackager )
				)
				( attribute "CDS_PART_NAME" "RCC_DFX1940_ID4-EMPTY,N_A"
					( Origin gPackager )
				)
				( objectStatus "TC9A1" )
				( pin "gnd"
					( attribute "PN" "1"
						( Origin gPackager )
					)
					( objectStatus "TC9A1.1" )
				)
				( pin "io1"
					( attribute "PN" "2"
						( Origin gPackager )
					)
					( objectStatus "TC9A1.2" )
				)
				( pin "io2"
					( attribute "PN" "3"
						( Origin gPackager )
					)
					( objectStatus "TC9A1.3" )
				)
			)
			( gate "@baseboard_fab2_lib.baseboard_fab2(sch_1):page110_i11"
				( attribute "BOM_COST" "TEST_MFG"
					( Origin gFrontEnd )
				)
				( attribute "CDS_LIB" "mstr_misc"
					( Origin gPackager )
				)
				( attribute "CDS_LOCATION" "LB2F1"
					( Origin gPackager )
				)
				( attribute "LOCATION" "LB2F1"
					( Origin gFrontEnd )
				)
				( attribute "MATERIAL" "EMPTY"
					( Origin gFrontEnd )
				)
				( attribute "PACK_TYPE" "LABEL"
					( Origin gFrontEnd )
				)
				( attribute "PART_NUMBER" "N_A"
					( Origin gFrontEnd )
				)
				( attribute "PHYS_PAGE" "110"
					( Origin gFrontEnd )
				)
				( attribute "ROOM" "LABELS"
					( Origin gFrontEnd )
				)
				( attribute "ROT" "0"
					( Origin gFrontEnd )
				)
				( attribute "VER" "1"
					( Origin gFrontEnd )
				)
				( attribute "XY" "(-1525,4450)"
					( Origin gFrontEnd )
				)
				( attribute "CHIPS_PART_NAME" "SNLABEL_A"
					( Origin gPackager )
				)
				( attribute "CDS_PART_NAME" "SNLABEL_A_LABEL-EMPTY,N_A"
					( Origin gPackager )
				)
				( objectStatus "LB2F1" )
			)
			( gate "@baseboard_fab2_lib.baseboard_fab2(sch_1):page110_i12"
				( attribute "BOM_COST" "TEST_MFG"
					( Origin gFrontEnd )
				)
				( attribute "CDS_LIB" "mstr_misc"
					( Origin gPackager )
				)
				( attribute "CDS_LOCATION" "LB5F1"
					( Origin gPackager )
				)
				( attribute "LOCATION" "LB5F1"
					( Origin gFrontEnd )
				)
				( attribute "MATERIAL" "EMPTY"
					( Origin gFrontEnd )
				)
				( attribute "PACK_TYPE" "LABEL"
					( Origin gFrontEnd )
				)
				( attribute "PART_NUMBER" "N_A"
					( Origin gFrontEnd )
				)
				( attribute "PHYS_PAGE" "110"
					( Origin gFrontEnd )
				)
				( attribute "ROOM" "LABELS"
					( Origin gFrontEnd )
				)
				( attribute "ROT" "0"
					( Origin gFrontEnd )
				)
				( attribute "VER" "1"
					( Origin gFrontEnd )
				)
				( attribute "XY" "(-1525,3800)"
					( Origin gFrontEnd )
				)
				( attribute "CHIPS_PART_NAME" "SNLABEL_A"
					( Origin gPackager )
				)
				( attribute "CDS_PART_NAME" "SNLABEL_A_LABEL-EMPTY,N_A"
					( Origin gPackager )
				)
				( objectStatus "LB5F1" )
			)
			( gate "@baseboard_fab2_lib.baseboard_fab2(sch_1):page110_i13"
				( attribute "BOM_COST" "TEST_MFG"
					( Origin gFrontEnd )
				)
				( attribute "CDS_LIB" "mstr_misc"
					( Origin gPackager )
				)
				( attribute "CDS_LOCATION" "LB2B1"
					( Origin gPackager )
				)
				( attribute "LOCATION" "LB2B1"
					( Origin gFrontEnd )
				)
				( attribute "MATERIAL" "EMPTY"
					( Origin gFrontEnd )
				)
				( attribute "PACK_TYPE" "LABEL"
					( Origin gFrontEnd )
				)
				( attribute "PART_NUMBER" "N_A"
					( Origin gFrontEnd )
				)
				( attribute "PHYS_PAGE" "110"
					( Origin gFrontEnd )
				)
				( attribute "ROOM" "LABELS"
					( Origin gFrontEnd )
				)
				( attribute "ROT" "0"
					( Origin gFrontEnd )
				)
				( attribute "VER" "1"
					( Origin gFrontEnd )
				)
				( attribute "XY" "(-1525,3125)"
					( Origin gFrontEnd )
				)
				( attribute "CHIPS_PART_NAME" "SNLABEL_A"
					( Origin gPackager )
				)
				( attribute "CDS_PART_NAME" "SNLABEL_A_LABEL-EMPTY,N_A"
					( Origin gPackager )
				)
				( objectStatus "LB2B1" )
			)
			( gate "@baseboard_fab2_lib.baseboard_fab2(sch_1):page110_i14"
				( attribute "BOM_COST" "TEST_MFG"
					( Origin gFrontEnd )
				)
				( attribute "CDS_LIB" "mstr_misc"
					( Origin gPackager )
				)
				( attribute "CDS_LOCATION" "LB5B1"
					( Origin gPackager )
				)
				( attribute "LOCATION" "LB5B1"
					( Origin gFrontEnd )
				)
				( attribute "MATERIAL" "EMPTY"
					( Origin gFrontEnd )
				)
				( attribute "PACK_TYPE" "LABEL"
					( Origin gFrontEnd )
				)
				( attribute "PART_NUMBER" "N_A"
					( Origin gFrontEnd )
				)
				( attribute "PHYS_PAGE" "110"
					( Origin gFrontEnd )
				)
				( attribute "ROOM" "LABELS"
					( Origin gFrontEnd )
				)
				( attribute "ROT" "0"
					( Origin gFrontEnd )
				)
				( attribute "VER" "1"
					( Origin gFrontEnd )
				)
				( attribute "XY" "(-1500,2425)"
					( Origin gFrontEnd )
				)
				( attribute "CHIPS_PART_NAME" "SNLABEL_A"
					( Origin gPackager )
				)
				( attribute "CDS_PART_NAME" "SNLABEL_A_LABEL-EMPTY,N_A"
					( Origin gPackager )
				)
				( objectStatus "LB5B1" )
			)
			( gate "@baseboard_fab2_lib.baseboard_fab2(sch_1):page110_i15"
				( attribute "BOM_COST" "TEST_MFG"
					( Origin gFrontEnd )
				)
				( attribute "CDS_LIB" "mstr_misc"
					( Origin gPackager )
				)
				( attribute "CDS_LOCATION" "LB6T1"
					( Origin gPackager )
				)
				( attribute "LOCATION" "LB6T1"
					( Origin gFrontEnd )
				)
				( attribute "MATERIAL" "EMPTY"
					( Origin gFrontEnd )
				)
				( attribute "PACK_TYPE" "LABEL"
					( Origin gFrontEnd )
				)
				( attribute "PART_NUMBER" "N_A"
					( Origin gFrontEnd )
				)
				( attribute "PHYS_PAGE" "110"
					( Origin gFrontEnd )
				)
				( attribute "ROOM" "LABELS"
					( Origin gFrontEnd )
				)
				( attribute "ROT" "0"
					( Origin gFrontEnd )
				)
				( attribute "VER" "1"
					( Origin gFrontEnd )
				)
				( attribute "XY" "(-1525,1900)"
					( Origin gFrontEnd )
				)
				( attribute "CHIPS_PART_NAME" "SNLABEL_A"
					( Origin gPackager )
				)
				( attribute "CDS_PART_NAME" "SNLABEL_A_LABEL-EMPTY,N_A"
					( Origin gPackager )
				)
				( objectStatus "LB6T1" )
			)
			( gate "@baseboard_fab2_lib.baseboard_fab2(sch_1):page111_i6"
				( attribute "BOM_COST" "DEBUG"
					( Origin gFrontEnd )
				)
				( attribute "CDS_LIB" "mstr_discrete"
					( Origin gPackager )
				)
				( attribute "CDS_LOCATION" "R1L13"
					( Origin gPackager )
				)
				( attribute "CDS_SEC" "1"
					( Origin gPackager )
				)
				( attribute "LOCATION" "R1L13"
					( Origin gFrontEnd )
				)
				( attribute "MATERIAL" "CHIP"
					( Origin gFrontEnd )
				)
				( attribute "PACK_TYPE" "0402"
					( Origin gFrontEnd )
				)
				( attribute "PART_NUMBER" "G21796-026"
					( Origin gFrontEnd )
				)
				( attribute "PHYS_PAGE" "111"
					( Origin gFrontEnd )
				)
				( attribute "ROOM" "DEBUG"
					( Origin gFrontEnd )
				)
				( attribute "ROT" "0"
					( Origin gFrontEnd )
				)
				( attribute "SEC" "1"
					( Origin gFrontEnd )
				)
				( attribute "SEC_TYPE" "0402"
					( Origin gFrontEnd )
				)
				( attribute "TOLERANCE" "1%"
					( Origin gFrontEnd )
				)
				( attribute "VALUE" "1.00K"
					( Origin gFrontEnd )
				)
				( attribute "VER" "1"
					( Origin gFrontEnd )
				)
				( attribute "WATTAGE" "1/16W"
					( Origin gFrontEnd )
				)
				( attribute "XY" "(2725,2150)"
					( Origin gFrontEnd )
				)
				( attribute "CHIPS_PART_NAME" "RES"
					( Origin gPackager )
				)
				( attribute "CDS_PART_NAME" "RES_0402-1.00K,1%,1/16W,CHIP,GA"
					( Origin gPackager )
				)
				( objectStatus "R1L13" )
				( pin "a"
					( attribute "PN" "1"
						( Origin gPackager )
					)
					( objectStatus "R1L13.1" )
				)
				( pin "b"
					( attribute "PN" "2"
						( Origin gPackager )
					)
					( objectStatus "R1L13.2" )
				)
			)
			( gate "@baseboard_fab2_lib.baseboard_fab2(sch_1):page111_i10"
				( attribute "BOM_COST" "DEBUG"
					( Origin gFrontEnd )
				)
				( attribute "CDS_LIB" "dev_discrete"
					( Origin gPackager )
				)
				( attribute "CDS_LOCATION" "C9A2"
					( Origin gPackager )
				)
				( attribute "CDS_SEC" "1"
					( Origin gPackager )
				)
				( attribute "LOCATION" "C9A2"
					( Origin gFrontEnd )
				)
				( attribute "MATERIAL" "X7R"
					( Origin gFrontEnd )
				)
				( attribute "PACK_TYPE" "0402V"
					( Origin gFrontEnd )
				)
				( attribute "PART_NUMBER" "A36096-030"
					( Origin gFrontEnd )
				)
				( attribute "PHYS_PAGE" "111"
					( Origin gFrontEnd )
				)
				( attribute "ROOM" "DEBUG"
					( Origin gFrontEnd )
				)
				( attribute "ROT" "1"
					( Origin gFrontEnd )
				)
				( attribute "SEC" "1"
					( Origin gFrontEnd )
				)
				( attribute "SEC_TYPE" "0402V"
					( Origin gFrontEnd )
				)
				( attribute "TOLERANCE" "10%"
					( Origin gFrontEnd )
				)
				( attribute "VALUE" "0.1UF"
					( Origin gFrontEnd )
				)
				( attribute "VER" "1"
					( Origin gFrontEnd )
				)
				( attribute "VOLTAGE" "16V"
					( Units "uVoltage" "V" 1.000000)
					( Origin gFrontEnd )
				)
				( attribute "XY" "(2750,1900)"
					( Origin gFrontEnd )
				)
				( attribute "CHIPS_PART_NAME" "CAP_A"
					( Origin gPackager )
				)
				( attribute "CDS_PART_NAME" "CAP_A_0402V-0.1UF,16V,10%,X7R,A"
					( Origin gPackager )
				)
				( objectStatus "C9A2" )
				( pin "a"
					( attribute "PN" "1"
						( Origin gPackager )
					)
					( objectStatus "C9A2.1" )
				)
				( pin "b"
					( attribute "PN" "2"
						( Origin gPackager )
					)
					( objectStatus "C9A2.2" )
				)
			)
			( gate "@baseboard_fab2_lib.baseboard_fab2(sch_1):page111_i11"
				( attribute "BOM_COST" "DEBUG"
					( Origin gFrontEnd )
				)
				( attribute "CDS_LIB" "mstr_discrete"
					( Origin gPackager )
				)
				( attribute "CDS_LOCATION" "R9A14"
					( Origin gPackager )
				)
				( attribute "CDS_SEC" "1"
					( Origin gPackager )
				)
				( attribute "LOCATION" "R9A14"
					( Origin gFrontEnd )
				)
				( attribute "MATERIAL" "CHIP"
					( Origin gFrontEnd )
				)
				( attribute "PACK_TYPE" "0402"
					( Origin gFrontEnd )
				)
				( attribute "PART_NUMBER" "G21796-026"
					( Origin gFrontEnd )
				)
				( attribute "PHYS_PAGE" "111"
					( Origin gFrontEnd )
				)
				( attribute "ROOM" "DEBUG"
					( Origin gFrontEnd )
				)
				( attribute "ROT" "0"
					( Origin gFrontEnd )
				)
				( attribute "SEC" "1"
					( Origin gFrontEnd )
				)
				( attribute "SEC_TYPE" "0402"
					( Origin gFrontEnd )
				)
				( attribute "TOLERANCE" "1%"
					( Origin gFrontEnd )
				)
				( attribute "VALUE" "1.00K"
					( Origin gFrontEnd )
				)
				( attribute "VER" "1"
					( Origin gFrontEnd )
				)
				( attribute "WATTAGE" "1/16W"
					( Origin gFrontEnd )
				)
				( attribute "XY" "(2725,1700)"
					( Origin gFrontEnd )
				)
				( attribute "CHIPS_PART_NAME" "RES"
					( Origin gPackager )
				)
				( attribute "CDS_PART_NAME" "RES_0402-1.00K,1%,1/16W,CHIP,GA"
					( Origin gPackager )
				)
				( objectStatus "R9A14" )
				( pin "a"
					( attribute "PN" "1"
						( Origin gPackager )
					)
					( objectStatus "R9A14.1" )
				)
				( pin "b"
					( attribute "PN" "2"
						( Origin gPackager )
					)
					( objectStatus "R9A14.2" )
				)
			)
			( gate "@baseboard_fab2_lib.baseboard_fab2(sch_1):page111_i12"
				( attribute "BOM_COST" "DEBUG"
					( Origin gFrontEnd )
				)
				( attribute "CDS_LIB" "dev_discrete"
					( Origin gPackager )
				)
				( attribute "CDS_LOCATION" "C9A5"
					( Origin gPackager )
				)
				( attribute "CDS_SEC" "1"
					( Origin gPackager )
				)
				( attribute "LOCATION" "C9A5"
					( Origin gFrontEnd )
				)
				( attribute "MATERIAL" "X7R"
					( Origin gFrontEnd )
				)
				( attribute "PACK_TYPE" "0402V"
					( Origin gFrontEnd )
				)
				( attribute "PART_NUMBER" "A36096-030"
					( Origin gFrontEnd )
				)
				( attribute "PHYS_PAGE" "111"
					( Origin gFrontEnd )
				)
				( attribute "ROOM" "DEBUG"
					( Origin gFrontEnd )
				)
				( attribute "ROT" "1"
					( Origin gFrontEnd )
				)
				( attribute "SEC" "1"
					( Origin gFrontEnd )
				)
				( attribute "SEC_TYPE" "0402V"
					( Origin gFrontEnd )
				)
				( attribute "TOLERANCE" "10%"
					( Origin gFrontEnd )
				)
				( attribute "VALUE" "0.1UF"
					( Origin gFrontEnd )
				)
				( attribute "VER" "1"
					( Origin gFrontEnd )
				)
				( attribute "VOLTAGE" "16V"
					( Units "uVoltage" "V" 1.000000)
					( Origin gFrontEnd )
				)
				( attribute "XY" "(2800,1450)"
					( Origin gFrontEnd )
				)
				( attribute "CHIPS_PART_NAME" "CAP_A"
					( Origin gPackager )
				)
				( attribute "CDS_PART_NAME" "CAP_A_0402V-0.1UF,16V,10%,X7R,A"
					( Origin gPackager )
				)
				( objectStatus "C9A5" )
				( pin "a"
					( attribute "PN" "1"
						( Origin gPackager )
					)
					( objectStatus "C9A5.1" )
				)
				( pin "b"
					( attribute "PN" "2"
						( Origin gPackager )
					)
					( objectStatus "C9A5.2" )
				)
			)
			( gate "@baseboard_fab2_lib.baseboard_fab2(sch_1):page111_i13"
				( attribute "BOM_COST" "DEBUG"
					( Origin gFrontEnd )
				)
				( attribute "CDS_LIB" "mstr_discrete"
					( Origin gPackager )
				)
				( attribute "CDS_LOCATION" "R1L23"
					( Origin gPackager )
				)
				( attribute "CDS_SEC" "1"
					( Origin gPackager )
				)
				( attribute "LOCATION" "R1L23"
					( Origin gFrontEnd )
				)
				( attribute "MATERIAL" "CHIP"
					( Origin gFrontEnd )
				)
				( attribute "PACK_TYPE" "0402"
					( Origin gFrontEnd )
				)
				( attribute "PART_NUMBER" "G21796-026"
					( Origin gFrontEnd )
				)
				( attribute "PHYS_PAGE" "111"
					( Origin gFrontEnd )
				)
				( attribute "ROOM" "DEBUG"
					( Origin gFrontEnd )
				)
				( attribute "ROT" "0"
					( Origin gFrontEnd )
				)
				( attribute "SEC" "1"
					( Origin gFrontEnd )
				)
				( attribute "SEC_TYPE" "0402"
					( Origin gFrontEnd )
				)
				( attribute "TOLERANCE" "1%"
					( Origin gFrontEnd )
				)
				( attribute "VALUE" "1.00K"
					( Origin gFrontEnd )
				)
				( attribute "VER" "1"
					( Origin gFrontEnd )
				)
				( attribute "WATTAGE" "1/16W"
					( Origin gFrontEnd )
				)
				( attribute "XY" "(2725,1125)"
					( Origin gFrontEnd )
				)
				( attribute "CHIPS_PART_NAME" "RES"
					( Origin gPackager )
				)
				( attribute "CDS_PART_NAME" "RES_0402-1.00K,1%,1/16W,CHIP,GA"
					( Origin gPackager )
				)
				( objectStatus "R1L23" )
				( pin "a"
					( attribute "PN" "1"
						( Origin gPackager )
					)
					( objectStatus "R1L23.1" )
				)
				( pin "b"
					( attribute "PN" "2"
						( Origin gPackager )
					)
					( objectStatus "R1L23.2" )
				)
			)
			( gate "@baseboard_fab2_lib.baseboard_fab2(sch_1):page111_i14"
				( attribute "BOM_COST" "DEBUG"
					( Origin gFrontEnd )
				)
				( attribute "CDS_LIB" "dev_discrete"
					( Origin gPackager )
				)
				( attribute "CDS_LOCATION" "C1L8"
					( Origin gPackager )
				)
				( attribute "CDS_SEC" "1"
					( Origin gPackager )
				)
				( attribute "LOCATION" "C1L8"
					( Origin gFrontEnd )
				)
				( attribute "MATERIAL" "X7R"
					( Origin gFrontEnd )
				)
				( attribute "PACK_TYPE" "0402V"
					( Origin gFrontEnd )
				)
				( attribute "PART_NUMBER" "A36096-030"
					( Origin gFrontEnd )
				)
				( attribute "PHYS_PAGE" "111"
					( Origin gFrontEnd )
				)
				( attribute "ROOM" "DEBUG"
					( Origin gFrontEnd )
				)
				( attribute "ROT" "1"
					( Origin gFrontEnd )
				)
				( attribute "SEC" "1"
					( Origin gFrontEnd )
				)
				( attribute "SEC_TYPE" "0402V"
					( Origin gFrontEnd )
				)
				( attribute "TOLERANCE" "10%"
					( Origin gFrontEnd )
				)
				( attribute "VALUE" "0.1UF"
					( Origin gFrontEnd )
				)
				( attribute "VER" "1"
					( Origin gFrontEnd )
				)
				( attribute "VOLTAGE" "16V"
					( Units "uVoltage" "V" 1.000000)
					( Origin gFrontEnd )
				)
				( attribute "XY" "(2825,925)"
					( Origin gFrontEnd )
				)
				( attribute "CHIPS_PART_NAME" "CAP_A"
					( Origin gPackager )
				)
				( attribute "CDS_PART_NAME" "CAP_A_0402V-0.1UF,16V,10%,X7R,A"
					( Origin gPackager )
				)
				( objectStatus "C1L8" )
				( pin "a"
					( attribute "PN" "1"
						( Origin gPackager )
					)
					( objectStatus "C1L8.1" )
				)
				( pin "b"
					( attribute "PN" "2"
						( Origin gPackager )
					)
					( objectStatus "C1L8.2" )
				)
			)
			( gate "@baseboard_fab2_lib.baseboard_fab2(sch_1):page111_i25"
				( attribute "BOM_COST" "DEBUG"
					( Origin gFrontEnd )
				)
				( attribute "CDS_LIB" "dev_discrete"
					( Origin gPackager )
				)
				( attribute "CDS_LOCATION" "C9A6"
					( Origin gPackager )
				)
				( attribute "CDS_SEC" "1"
					( Origin gPackager )
				)
				( attribute "LOCATION" "C9A6"
					( Origin gFrontEnd )
				)
				( attribute "MATERIAL" "X6S"
					( Origin gFrontEnd )
				)
				( attribute "PACK_TYPE" "0402V"
					( Origin gFrontEnd )
				)
				( attribute "PART_NUMBER" "D97712-004"
					( Origin gFrontEnd )
				)
				( attribute "PHYS_PAGE" "111"
					( Origin gFrontEnd )
				)
				( attribute "ROOM" "DEBUG"
					( Origin gFrontEnd )
				)
				( attribute "ROT" "2"
					( Origin gFrontEnd )
				)
				( attribute "SEC" "1"
					( Origin gPackager )
				)
				( attribute "TOLERANCE" "10%"
					( Origin gFrontEnd )
				)
				( attribute "VALUE" "1.0UF"
					( Origin gFrontEnd )
				)
				( attribute "VER" "1"
					( Origin gFrontEnd )
				)
				( attribute "VOLTAGE" "6.3V"
					( Units "uVoltage" "V" 1.000000)
					( Origin gFrontEnd )
				)
				( attribute "XY" "(750,2925)"
					( Origin gFrontEnd )
				)
				( attribute "CHIPS_PART_NAME" "CAP_A"
					( Origin gPackager )
				)
				( attribute "CDS_PART_NAME" "CAP_A_0402V-1.0UF,6.3V,10%,X6SA"
					( Origin gPackager )
				)
				( objectStatus "C9A6" )
				( pin "a"
					( attribute "PN" "1"
						( Origin gPackager )
					)
					( objectStatus "C9A6.1" )
				)
				( pin "b"
					( attribute "PN" "2"
						( Origin gPackager )
					)
					( objectStatus "C9A6.2" )
				)
			)
			( gate "@baseboard_fab2_lib.baseboard_fab2(sch_1):page111_i26"
				( attribute "ALLOW_CONNECT" "TRUE"
					( Origin gFrontEnd )
				)
				( attribute "BOM_COST" "DEBUG"
					( Origin gFrontEnd )
				)
				( attribute "CDS_LIB" "mstr_sconn"
					( Origin gPackager )
				)
				( attribute "CDS_LOCATION" "J9A3"
					( Origin gPackager )
				)
				( attribute "CDS_SEC" "1"
					( Origin gPackager )
				)
				( attribute "LOCATION" "J9A3"
					( Origin gFrontEnd )
				)
				( attribute "MATERIAL" "CONN"
					( Origin gFrontEnd )
				)
				( attribute "PACK_TYPE" "SMLF"
					( Origin gFrontEnd )
				)
				( attribute "PART_NUMBER" "C21100-002"
					( Origin gFrontEnd )
				)
				( attribute "PHYS_PAGE" "111"
					( Origin gFrontEnd )
				)
				( attribute "ROOM" "DEBUG"
					( Origin gFrontEnd )
				)
				( attribute "ROT" "0"
					( Origin gFrontEnd )
				)
				( attribute "SEC" "1"
					( Origin gFrontEnd )
				)
				( attribute "SEC_TYPE" "SMLF"
					( Origin gFrontEnd )
				)
				( attribute "VER" "1"
					( Origin gFrontEnd )
				)
				( attribute "XY" "(350,3950)"
					( Origin gFrontEnd )
				)
				( attribute "CHIPS_PART_NAME" "SCONN60_C21100002"
					( Origin gPackager )
				)
				( attribute "CDS_PART_NAME" "SCONN60_C21100002_SMLF-CONN,C2A"
					( Origin gPackager )
				)
				( objectStatus "J9A3" )
				( pin "io1"
					( attribute "PN" "1"
						( Origin gPackager )
					)
					( objectStatus "J9A3.1" )
				)
				( pin "io2"
					( attribute "PN" "2"
						( Origin gPackager )
					)
					( objectStatus "J9A3.2" )
				)
				( pin "io3"
					( attribute "PN" "3"
						( Origin gPackager )
					)
					( objectStatus "J9A3.3" )
				)
				( pin "io4"
					( attribute "PN" "4"
						( Origin gPackager )
					)
					( objectStatus "J9A3.4" )
				)
				( pin "io5"
					( attribute "PN" "5"
						( Origin gPackager )
					)
					( objectStatus "J9A3.5" )
				)
				( pin "io6"
					( attribute "PN" "6"
						( Origin gPackager )
					)
					( objectStatus "J9A3.6" )
				)
				( pin "io7"
					( attribute "PN" "7"
						( Origin gPackager )
					)
					( objectStatus "J9A3.7" )
				)
				( pin "io8"
					( attribute "PN" "8"
						( Origin gPackager )
					)
					( objectStatus "J9A3.8" )
				)
				( pin "io9"
					( attribute "PN" "9"
						( Origin gPackager )
					)
					( objectStatus "J9A3.9" )
				)
				( pin "io10"
					( attribute "PN" "10"
						( Origin gPackager )
					)
					( objectStatus "J9A3.10" )
				)
				( pin "io11"
					( attribute "PN" "11"
						( Origin gPackager )
					)
					( objectStatus "J9A3.11" )
				)
				( pin "io12"
					( attribute "PN" "12"
						( Origin gPackager )
					)
					( objectStatus "J9A3.12" )
				)
				( pin "io13"
					( attribute "PN" "13"
						( Origin gPackager )
					)
					( objectStatus "J9A3.13" )
				)
				( pin "io14"
					( attribute "PN" "14"
						( Origin gPackager )
					)
					( objectStatus "J9A3.14" )
				)
				( pin "io15"
					( attribute "PN" "15"
						( Origin gPackager )
					)
					( objectStatus "J9A3.15" )
				)
				( pin "io16"
					( attribute "PN" "16"
						( Origin gPackager )
					)
					( objectStatus "J9A3.16" )
				)
				( pin "io17"
					( attribute "PN" "17"
						( Origin gPackager )
					)
					( objectStatus "J9A3.17" )
				)
				( pin "io18"
					( attribute "PN" "18"
						( Origin gPackager )
					)
					( objectStatus "J9A3.18" )
				)
				( pin "io19"
					( attribute "PN" "19"
						( Origin gPackager )
					)
					( objectStatus "J9A3.19" )
				)
				( pin "io20"
					( attribute "PN" "20"
						( Origin gPackager )
					)
					( objectStatus "J9A3.20" )
				)
				( pin "io21"
					( attribute "PN" "21"
						( Origin gPackager )
					)
					( objectStatus "J9A3.21" )
				)
				( pin "io22"
					( attribute "PN" "22"
						( Origin gPackager )
					)
					( objectStatus "J9A3.22" )
				)
				( pin "io23"
					( attribute "PN" "23"
						( Origin gPackager )
					)
					( objectStatus "J9A3.23" )
				)
				( pin "io24"
					( attribute "PN" "24"
						( Origin gPackager )
					)
					( objectStatus "J9A3.24" )
				)
				( pin "io25"
					( attribute "PN" "25"
						( Origin gPackager )
					)
					( objectStatus "J9A3.25" )
				)
				( pin "io26"
					( attribute "PN" "26"
						( Origin gPackager )
					)
					( objectStatus "J9A3.26" )
				)
				( pin "io27"
					( attribute "PN" "27"
						( Origin gPackager )
					)
					( objectStatus "J9A3.27" )
				)
				( pin "io28"
					( attribute "PN" "28"
						( Origin gPackager )
					)
					( objectStatus "J9A3.28" )
				)
				( pin "io29"
					( attribute "PN" "29"
						( Origin gPackager )
					)
					( objectStatus "J9A3.29" )
				)
				( pin "io30"
					( attribute "PN" "30"
						( Origin gPackager )
					)
					( objectStatus "J9A3.30" )
				)
				( pin "io31"
					( attribute "PN" "31"
						( Origin gPackager )
					)
					( objectStatus "J9A3.31" )
				)
				( pin "io32"
					( attribute "PN" "32"
						( Origin gPackager )
					)
					( objectStatus "J9A3.32" )
				)
				( pin "io33"
					( attribute "PN" "33"
						( Origin gPackager )
					)
					( objectStatus "J9A3.33" )
				)
				( pin "io34"
					( attribute "PN" "34"
						( Origin gPackager )
					)
					( objectStatus "J9A3.34" )
				)
				( pin "io35"
					( attribute "PN" "35"
						( Origin gPackager )
					)
					( objectStatus "J9A3.35" )
				)
				( pin "io36"
					( attribute "PN" "36"
						( Origin gPackager )
					)
					( objectStatus "J9A3.36" )
				)
				( pin "io37"
					( attribute "PN" "37"
						( Origin gPackager )
					)
					( objectStatus "J9A3.37" )
				)
				( pin "io38"
					( attribute "PN" "38"
						( Origin gPackager )
					)
					( objectStatus "J9A3.38" )
				)
				( pin "io39"
					( attribute "PN" "39"
						( Origin gPackager )
					)
					( objectStatus "J9A3.39" )
				)
				( pin "io40"
					( attribute "PN" "40"
						( Origin gPackager )
					)
					( objectStatus "J9A3.40" )
				)
				( pin "io41"
					( attribute "PN" "41"
						( Origin gPackager )
					)
					( objectStatus "J9A3.41" )
				)
				( pin "io42"
					( attribute "PN" "42"
						( Origin gPackager )
					)
					( objectStatus "J9A3.42" )
				)
				( pin "io43"
					( attribute "PN" "43"
						( Origin gPackager )
					)
					( objectStatus "J9A3.43" )
				)
				( pin "io44"
					( attribute "PN" "44"
						( Origin gPackager )
					)
					( objectStatus "J9A3.44" )
				)
				( pin "io45"
					( attribute "PN" "45"
						( Origin gPackager )
					)
					( objectStatus "J9A3.45" )
				)
				( pin "io46"
					( attribute "PN" "46"
						( Origin gPackager )
					)
					( objectStatus "J9A3.46" )
				)
				( pin "io47"
					( attribute "PN" "47"
						( Origin gPackager )
					)
					( objectStatus "J9A3.47" )
				)
				( pin "io48"
					( attribute "PN" "48"
						( Origin gPackager )
					)
					( objectStatus "J9A3.48" )
				)
				( pin "io49"
					( attribute "PN" "49"
						( Origin gPackager )
					)
					( objectStatus "J9A3.49" )
				)
				( pin "io50"
					( attribute "PN" "50"
						( Origin gPackager )
					)
					( objectStatus "J9A3.50" )
				)
				( pin "io51"
					( attribute "PN" "51"
						( Origin gPackager )
					)
					( objectStatus "J9A3.51" )
				)
				( pin "io52"
					( attribute "PN" "52"
						( Origin gPackager )
					)
					( objectStatus "J9A3.52" )
				)
				( pin "io53"
					( attribute "PN" "53"
						( Origin gPackager )
					)
					( objectStatus "J9A3.53" )
				)
				( pin "io54"
					( attribute "PN" "54"
						( Origin gPackager )
					)
					( objectStatus "J9A3.54" )
				)
				( pin "io55"
					( attribute "PN" "55"
						( Origin gPackager )
					)
					( objectStatus "J9A3.55" )
				)
				( pin "io56"
					( attribute "PN" "56"
						( Origin gPackager )
					)
					( objectStatus "J9A3.56" )
				)
				( pin "io57"
					( attribute "PN" "57"
						( Origin gPackager )
					)
					( objectStatus "J9A3.57" )
				)
				( pin "io58"
					( attribute "PN" "58"
						( Origin gPackager )
					)
					( objectStatus "J9A3.58" )
				)
				( pin "io59"
					( attribute "PN" "59"
						( Origin gPackager )
					)
					( objectStatus "J9A3.59" )
				)
				( pin "io60"
					( attribute "PN" "60"
						( Origin gPackager )
					)
					( objectStatus "J9A3.60" )
				)
			)
			( gate "@baseboard_fab2_lib.baseboard_fab2(sch_1):page111_i30"
				( attribute "BOM_COST" "DEBUG"
					( Origin gFrontEnd )
				)
				( attribute "CDS_LIB" "dev_discrete"
					( Origin gPackager )
				)
				( attribute "CDS_LOCATION" "C1L5"
					( Origin gPackager )
				)
				( attribute "CDS_SEC" "1"
					( Origin gPackager )
				)
				( attribute "LOCATION" "C1L5"
					( Origin gFrontEnd )
				)
				( attribute "MATERIAL" "X6S"
					( Origin gFrontEnd )
				)
				( attribute "PACK_TYPE" "0402V"
					( Origin gFrontEnd )
				)
				( attribute "PART_NUMBER" "D97712-004"
					( Origin gFrontEnd )
				)
				( attribute "PHYS_PAGE" "111"
					( Origin gFrontEnd )
				)
				( attribute "ROOM" "DEBUG"
					( Origin gFrontEnd )
				)
				( attribute "ROT" "0"
					( Origin gFrontEnd )
				)
				( attribute "SEC" "1"
					( Origin gPackager )
				)
				( attribute "TOLERANCE" "10%"
					( Origin gFrontEnd )
				)
				( attribute "VALUE" "1.0UF"
					( Origin gFrontEnd )
				)
				( attribute "VER" "1"
					( Origin gFrontEnd )
				)
				( attribute "VOLTAGE" "6.3V"
					( Units "uVoltage" "V" 1.000000)
					( Origin gFrontEnd )
				)
				( attribute "XY" "(0,2925)"
					( Origin gFrontEnd )
				)
				( attribute "CHIPS_PART_NAME" "CAP_A"
					( Origin gPackager )
				)
				( attribute "CDS_PART_NAME" "CAP_A_0402V-1.0UF,6.3V,10%,X6SA"
					( Origin gPackager )
				)
				( objectStatus "C1L5" )
				( pin "a"
					( attribute "PN" "1"
						( Origin gPackager )
					)
					( objectStatus "C1L5.1" )
				)
				( pin "b"
					( attribute "PN" "2"
						( Origin gPackager )
					)
					( objectStatus "C1L5.2" )
				)
			)
			( gate "@baseboard_fab2_lib.baseboard_fab2(sch_1):page111_i37"
				( attribute "BOM_COST" "DEBUG"
					( Origin gFrontEnd )
				)
				( attribute "CDS_LIB" "mstr_discrete"
					( Origin gPackager )
				)
				( attribute "CDS_LOCATION" "R2P2"
					( Origin gPackager )
				)
				( attribute "CDS_SEC" "1"
					( Origin gPackager )
				)
				( attribute "LOCATION" "R2P2"
					( Origin gFrontEnd )
				)
				( attribute "MATERIAL" "CHIP"
					( Origin gFrontEnd )
				)
				( attribute "PACK_TYPE" "0402"
					( Origin gFrontEnd )
				)
				( attribute "PART_NUMBER" "G21796-026"
					( Origin gFrontEnd )
				)
				( attribute "PHYS_PAGE" "111"
					( Origin gFrontEnd )
				)
				( attribute "ROOM" "DEBUG"
					( Origin gFrontEnd )
				)
				( attribute "ROT" "0"
					( Origin gFrontEnd )
				)
				( attribute "SEC" "1"
					( Origin gFrontEnd )
				)
				( attribute "SEC_TYPE" "0402"
					( Origin gFrontEnd )
				)
				( attribute "TOLERANCE" "1%"
					( Origin gFrontEnd )
				)
				( attribute "VALUE" "1.00K"
					( Origin gFrontEnd )
				)
				( attribute "VER" "1"
					( Origin gFrontEnd )
				)
				( attribute "WATTAGE" "1/16W"
					( Origin gFrontEnd )
				)
				( attribute "XY" "(-2250,4650)"
					( Origin gFrontEnd )
				)
				( attribute "CHIPS_PART_NAME" "RES"
					( Origin gPackager )
				)
				( attribute "CDS_PART_NAME" "RES_0402-1.00K,1%,1/16W,CHIP,GA"
					( Origin gPackager )
				)
				( objectStatus "R2P2" )
				( pin "a"
					( attribute "PN" "1"
						( Origin gPackager )
					)
					( objectStatus "R2P2.1" )
				)
				( pin "b"
					( attribute "PN" "2"
						( Origin gPackager )
					)
					( objectStatus "R2P2.2" )
				)
			)
			( gate "@baseboard_fab2_lib.baseboard_fab2(sch_1):page111_i55"
				( attribute "BOM_COST" "DEBUG"
					( Origin gFrontEnd )
				)
				( attribute "CDS_LIB" "mstr_discrete"
					( Origin gPackager )
				)
				( attribute "CDS_LOCATION" "R9A4"
					( Origin gPackager )
				)
				( attribute "CDS_SEC" "1"
					( Origin gPackager )
				)
				( attribute "LOCATION" "R9A4"
					( Origin gFrontEnd )
				)
				( attribute "MATERIAL" "CHIP"
					( Origin gFrontEnd )
				)
				( attribute "PACK_TYPE" "0402"
					( Origin gFrontEnd )
				)
				( attribute "PART_NUMBER" "G21796-077"
					( Origin gFrontEnd )
				)
				( attribute "PHYS_PAGE" "111"
					( Origin gFrontEnd )
				)
				( attribute "ROOM" "DEBUG"
					( Origin gFrontEnd )
				)
				( attribute "ROT" "0"
					( Origin gFrontEnd )
				)
				( attribute "SEC" "1"
					( Origin gFrontEnd )
				)
				( attribute "SEC_TYPE" "0402"
					( Origin gFrontEnd )
				)
				( attribute "TOLERANCE" "1%"
					( Origin gFrontEnd )
				)
				( attribute "VALUE" "475.0"
					( Origin gFrontEnd )
				)
				( attribute "VER" "1"
					( Origin gFrontEnd )
				)
				( attribute "WATTAGE" "1/16W"
					( Origin gFrontEnd )
				)
				( attribute "XY" "(-1475,1425)"
					( Origin gFrontEnd )
				)
				( attribute "CHIPS_PART_NAME" "RES"
					( Origin gPackager )
				)
				( attribute "CDS_PART_NAME" "RES_0402-475.0,1%,1/16W,CHIP,GA"
					( Origin gPackager )
				)
				( objectStatus "R9A4" )
				( pin "a"
					( attribute "PN" "1"
						( Origin gPackager )
					)
					( objectStatus "R9A4.1" )
				)
				( pin "b"
					( attribute "PN" "2"
						( Origin gPackager )
					)
					( objectStatus "R9A4.2" )
				)
			)
			( gate "@baseboard_fab2_lib.baseboard_fab2(sch_1):page111_i56"
				( attribute "BOM_COST" "DEBUG"
					( Origin gFrontEnd )
				)
				( attribute "CDS_LIB" "mstr_discrete"
					( Origin gPackager )
				)
				( attribute "CDS_LOCATION" "R1L17"
					( Origin gPackager )
				)
				( attribute "CDS_SEC" "1"
					( Origin gPackager )
				)
				( attribute "LOCATION" "R1L17"
					( Origin gFrontEnd )
				)
				( attribute "MATERIAL" "CHIP"
					( Origin gFrontEnd )
				)
				( attribute "PACK_TYPE" "0402"
					( Origin gFrontEnd )
				)
				( attribute "PART_NUMBER" "G21796-009"
					( Origin gFrontEnd )
				)
				( attribute "PHYS_PAGE" "111"
					( Origin gFrontEnd )
				)
				( attribute "ROOM" "DEBUG"
					( Origin gFrontEnd )
				)
				( attribute "ROT" "0"
					( Origin gFrontEnd )
				)
				( attribute "SEC" "1"
					( Origin gFrontEnd )
				)
				( attribute "SEC_TYPE" "0402"
					( Origin gFrontEnd )
				)
				( attribute "TOLERANCE" "1%"
					( Origin gFrontEnd )
				)
				( attribute "VALUE" "150.0"
					( Origin gFrontEnd )
				)
				( attribute "VER" "1"
					( Origin gFrontEnd )
				)
				( attribute "WATTAGE" "1/16W"
					( Origin gFrontEnd )
				)
				( attribute "XY" "(-1475,1100)"
					( Origin gFrontEnd )
				)
				( attribute "CHIPS_PART_NAME" "RES"
					( Origin gPackager )
				)
				( attribute "CDS_PART_NAME" "RES_0402-150.0,1%,1/16W,CHIP,GA"
					( Origin gPackager )
				)
				( objectStatus "R1L17" )
				( pin "a"
					( attribute "PN" "1"
						( Origin gPackager )
					)
					( objectStatus "R1L17.1" )
				)
				( pin "b"
					( attribute "PN" "2"
						( Origin gPackager )
					)
					( objectStatus "R1L17.2" )
				)
			)
			( gate "@baseboard_fab2_lib.baseboard_fab2(sch_1):page111_i57"
				( attribute "BOM_COST" "DEBUG"
					( Origin gFrontEnd )
				)
				( attribute "CDS_LIB" "mstr_discrete"
					( Origin gPackager )
				)
				( attribute "CDS_LOCATION" "R9A17"
					( Origin gPackager )
				)
				( attribute "CDS_SEC" "1"
					( Origin gPackager )
				)
				( attribute "LOCATION" "R9A17"
					( Origin gFrontEnd )
				)
				( attribute "MATERIAL" "CHIP"
					( Origin gFrontEnd )
				)
				( attribute "PACK_TYPE" "0402"
					( Origin gFrontEnd )
				)
				( attribute "PART_NUMBER" "G21796-026"
					( Origin gFrontEnd )
				)
				( attribute "PHYS_PAGE" "111"
					( Origin gFrontEnd )
				)
				( attribute "ROOM" "DEBUG"
					( Origin gFrontEnd )
				)
				( attribute "ROT" "0"
					( Origin gFrontEnd )
				)
				( attribute "SEC" "1"
					( Origin gFrontEnd )
				)
				( attribute "SEC_TYPE" "0402"
					( Origin gFrontEnd )
				)
				( attribute "TOLERANCE" "1%"
					( Origin gFrontEnd )
				)
				( attribute "VALUE" "1.00K"
					( Origin gFrontEnd )
				)
				( attribute "VER" "1"
					( Origin gFrontEnd )
				)
				( attribute "WATTAGE" "1/16W"
					( Origin gFrontEnd )
				)
				( attribute "XY" "(-1375,500)"
					( Origin gFrontEnd )
				)
				( attribute "CHIPS_PART_NAME" "RES"
					( Origin gPackager )
				)
				( attribute "CDS_PART_NAME" "RES_0402-1.00K,1%,1/16W,CHIP,GA"
					( Origin gPackager )
				)
				( objectStatus "R9A17" )
				( pin "a"
					( attribute "PN" "1"
						( Origin gPackager )
					)
					( objectStatus "R9A17.1" )
				)
				( pin "b"
					( attribute "PN" "2"
						( Origin gPackager )
					)
					( objectStatus "R9A17.2" )
				)
			)
			( gate "@baseboard_fab2_lib.baseboard_fab2(sch_1):page111_i59"
				( attribute "BOM_COST" "DEBUG"
					( Origin gFrontEnd )
				)
				( attribute "CDS_LIB" "dev_discrete"
					( Origin gPackager )
				)
				( attribute "CDS_LOCATION" "C9A4"
					( Origin gPackager )
				)
				( attribute "CDS_SEC" "1"
					( Origin gPackager )
				)
				( attribute "LOCATION" "C9A4"
					( Origin gFrontEnd )
				)
				( attribute "MATERIAL" "X7R"
					( Origin gFrontEnd )
				)
				( attribute "PACK_TYPE" "0402V"
					( Origin gFrontEnd )
				)
				( attribute "PART_NUMBER" "A36096-030"
					( Origin gFrontEnd )
				)
				( attribute "PHYS_PAGE" "111"
					( Origin gFrontEnd )
				)
				( attribute "ROOM" "DEBUG"
					( Origin gFrontEnd )
				)
				( attribute "ROT" "1"
					( Origin gFrontEnd )
				)
				( attribute "SEC" "1"
					( Origin gFrontEnd )
				)
				( attribute "SEC_TYPE" "0402V"
					( Origin gFrontEnd )
				)
				( attribute "TOLERANCE" "10%"
					( Origin gFrontEnd )
				)
				( attribute "VALUE" "0.1UF"
					( Origin gFrontEnd )
				)
				( attribute "VER" "1"
					( Origin gFrontEnd )
				)
				( attribute "VOLTAGE" "16V"
					( Units "uVoltage" "V" 1.000000)
					( Origin gFrontEnd )
				)
				( attribute "XY" "(-1475,875)"
					( Origin gFrontEnd )
				)
				( attribute "CHIPS_PART_NAME" "CAP_A"
					( Origin gPackager )
				)
				( attribute "CDS_PART_NAME" "CAP_A_0402V-0.1UF,16V,10%,X7R,A"
					( Origin gPackager )
				)
				( objectStatus "C9A4" )
				( pin "a"
					( attribute "PN" "1"
						( Origin gPackager )
					)
					( objectStatus "C9A4.1" )
				)
				( pin "b"
					( attribute "PN" "2"
						( Origin gPackager )
					)
					( objectStatus "C9A4.2" )
				)
			)
			( gate "@baseboard_fab2_lib.baseboard_fab2(sch_1):page111_i60"
				( attribute "BOM_COST" "DEBUG"
					( Origin gFrontEnd )
				)
				( attribute "CDS_LIB" "mstr_discrete"
					( Origin gPackager )
				)
				( attribute "CDS_LOCATION" "R9A15"
					( Origin gPackager )
				)
				( attribute "CDS_SEC" "1"
					( Origin gPackager )
				)
				( attribute "LOCATION" "R9A15"
					( Origin gFrontEnd )
				)
				( attribute "MATERIAL" "CHIP"
					( Origin gFrontEnd )
				)
				( attribute "PACK_TYPE" "0402"
					( Origin gFrontEnd )
				)
				( attribute "PART_NUMBER" "G21796-026"
					( Origin gFrontEnd )
				)
				( attribute "PHYS_PAGE" "111"
					( Origin gFrontEnd )
				)
				( attribute "ROOM" "DEBUG"
					( Origin gFrontEnd )
				)
				( attribute "ROT" "0"
					( Origin gFrontEnd )
				)
				( attribute "SEC" "1"
					( Origin gFrontEnd )
				)
				( attribute "SEC_TYPE" "0402"
					( Origin gFrontEnd )
				)
				( attribute "TOLERANCE" "1%"
					( Origin gFrontEnd )
				)
				( attribute "VALUE" "1.00K"
					( Origin gFrontEnd )
				)
				( attribute "VER" "1"
					( Origin gFrontEnd )
				)
				( attribute "WATTAGE" "1/16W"
					( Origin gFrontEnd )
				)
				( attribute "XY" "(-2175,3700)"
					( Origin gFrontEnd )
				)
				( attribute "CHIPS_PART_NAME" "RES"
					( Origin gPackager )
				)
				( attribute "CDS_PART_NAME" "RES_0402-1.00K,1%,1/16W,CHIP,GA"
					( Origin gPackager )
				)
				( objectStatus "R9A15" )
				( pin "a"
					( attribute "PN" "1"
						( Origin gPackager )
					)
					( objectStatus "R9A15.1" )
				)
				( pin "b"
					( attribute "PN" "2"
						( Origin gPackager )
					)
					( objectStatus "R9A15.2" )
				)
			)
			( gate "@baseboard_fab2_lib.baseboard_fab2(sch_1):page111_i66"
				( attribute "BOM_COST" "M-SATA"
					( Origin gFrontEnd )
				)
				( attribute "CDS_LIB" "mstr_discrete"
					( Origin gPackager )
				)
				( attribute "CDS_LOCATION" "R1L28"
					( Origin gPackager )
				)
				( attribute "CDS_SEC" "1"
					( Origin gPackager )
				)
				( attribute "LOCATION" "R1L28"
					( Origin gFrontEnd )
				)
				( attribute "MATERIAL" "CHIP"
					( Origin gFrontEnd )
				)
				( attribute "PACK_TYPE" "0402"
					( Origin gFrontEnd )
				)
				( attribute "PART_NUMBER" "G21796-072"
					( Origin gFrontEnd )
				)
				( attribute "PHYS_PAGE" "111"
					( Origin gFrontEnd )
				)
				( attribute "ROOM" "M-SATA"
					( Origin gFrontEnd )
				)
				( attribute "ROT" "0"
					( Origin gFrontEnd )
				)
				( attribute "SEC" "1"
					( Origin gFrontEnd )
				)
				( attribute "SEC_TYPE" "0402"
					( Origin gFrontEnd )
				)
				( attribute "TOLERANCE" "1%"
					( Origin gFrontEnd )
				)
				( attribute "VALUE" "4.75K"
					( Origin gFrontEnd )
				)
				( attribute "VER" "2"
					( Origin gFrontEnd )
				)
				( attribute "WATTAGE" "1/16W"
					( Origin gFrontEnd )
				)
				( attribute "XY" "(2175,2800)"
					( Origin gFrontEnd )
				)
				( attribute "CHIPS_PART_NAME" "RES"
					( Origin gPackager )
				)
				( attribute "CDS_PART_NAME" "RES_0402-4.75K,1%,1/16W,CHIP,GA"
					( Origin gPackager )
				)
				( objectStatus "R1L28" )
				( pin "a"
					( attribute "PN" "1"
						( Origin gPackager )
					)
					( objectStatus "R1L28.1" )
				)
				( pin "b"
					( attribute "PN" "2"
						( Origin gPackager )
					)
					( objectStatus "R1L28.2" )
				)
			)
			( gate "@baseboard_fab2_lib.baseboard_fab2(sch_1):page111_i68"
				( attribute "CDS_LIB" "mstr_discrete"
					( Origin gPackager )
				)
				( attribute "CDS_LOCATION" "R1L29"
					( Origin gPackager )
				)
				( attribute "CDS_SEC" "1"
					( Origin gPackager )
				)
				( attribute "LOCATION" "R1L29"
					( Origin gFrontEnd )
				)
				( attribute "MATERIAL" "CHIP"
					( Origin gFrontEnd )
				)
				( attribute "PACK_TYPE" "0402"
					( Origin gFrontEnd )
				)
				( attribute "PART_NUMBER" "G21796-074"
					( Origin gFrontEnd )
				)
				( attribute "PHYS_PAGE" "111"
					( Origin gFrontEnd )
				)
				( attribute "ROOM" "M-SATA"
					( Origin gFrontEnd )
				)
				( attribute "ROT" "0"
					( Origin gFrontEnd )
				)
				( attribute "SEC" "1"
					( Origin gFrontEnd )
				)
				( attribute "SEC_TYPE" "0402"
					( Origin gFrontEnd )
				)
				( attribute "TOLERANCE" "1%"
					( Origin gFrontEnd )
				)
				( attribute "VALUE" "33.2"
					( Origin gFrontEnd )
				)
				( attribute "VER" "1"
					( Origin gFrontEnd )
				)
				( attribute "WATTAGE" "1/16W"
					( Origin gFrontEnd )
				)
				( attribute "XY" "(2950,2600)"
					( Origin gFrontEnd )
				)
				( attribute "CHIPS_PART_NAME" "RES"
					( Origin gPackager )
				)
				( attribute "CDS_PART_NAME" "RES_0402-33.2,1%,1/16W,CHIP,G2A"
					( Origin gPackager )
				)
				( objectStatus "R1L29" )
				( pin "a"
					( attribute "PN" "1"
						( Origin gPackager )
					)
					( objectStatus "R1L29.1" )
				)
				( pin "b"
					( attribute "PN" "2"
						( Origin gPackager )
					)
					( objectStatus "R1L29.2" )
				)
			)
			( gate "@baseboard_fab2_lib.baseboard_fab2(sch_1):page111_i74"
				( attribute "CDS_LIB" "mstr_discrete"
					( Origin gPackager )
				)
				( attribute "CDS_LOCATION" "R9A3"
					( Origin gPackager )
				)
				( attribute "CDS_SEC" "1"
					( Origin gPackager )
				)
				( attribute "LOCATION" "R9A3"
					( Origin gFrontEnd )
				)
				( attribute "MATERIAL" "CHIP"
					( Origin gFrontEnd )
				)
				( attribute "PACK_TYPE" "0402"
					( Origin gFrontEnd )
				)
				( attribute "PART_NUMBER" "G21497-005"
					( Origin gFrontEnd )
				)
				( attribute "PHYS_PAGE" "111"
					( Origin gFrontEnd )
				)
				( attribute "ROOM" "DEBUG"
					( Origin gFrontEnd )
				)
				( attribute "ROT" "0"
					( Origin gFrontEnd )
				)
				( attribute "SEC" "1"
					( Origin gFrontEnd )
				)
				( attribute "SEC_TYPE" "0402"
					( Origin gFrontEnd )
				)
				( attribute "TOLERANCE" "5%"
					( Origin gFrontEnd )
				)
				( attribute "VALUE" "0.0"
					( Origin gFrontEnd )
				)
				( attribute "VER" "1"
					( Origin gFrontEnd )
				)
				( attribute "WATTAGE" "1/16W"
					( Origin gFrontEnd )
				)
				( attribute "XY" "(-1900,3075)"
					( Origin gFrontEnd )
				)
				( attribute "CHIPS_PART_NAME" "RES"
					( Origin gPackager )
				)
				( attribute "CDS_PART_NAME" "RES_0402-0.0,5%,1/16W,CHIP,G21A"
					( Origin gPackager )
				)
				( objectStatus "R9A3" )
				( pin "a"
					( attribute "PN" "1"
						( Origin gPackager )
					)
					( objectStatus "R9A3.1" )
				)
				( pin "b"
					( attribute "PN" "2"
						( Origin gPackager )
					)
					( objectStatus "R9A3.2" )
				)
			)
			( gate "@baseboard_fab2_lib.baseboard_fab2(sch_1):page111_i83"
				( attribute "CDS_LIB" "mstr_discrete"
					( Origin gPackager )
				)
				( attribute "CDS_LOCATION" "R9A2"
					( Origin gPackager )
				)
				( attribute "CDS_SEC" "1"
					( Origin gPackager )
				)
				( attribute "LOCATION" "R9A2"
					( Origin gFrontEnd )
				)
				( attribute "MATERIAL" "EMPTY"
					( Origin gFrontEnd )
				)
				( attribute "PACK_TYPE" "0402"
					( Origin gFrontEnd )
				)
				( attribute "PART_NUMBER" "G21796-074"
					( Origin gFrontEnd )
				)
				( attribute "PHYS_PAGE" "111"
					( Origin gFrontEnd )
				)
				( attribute "ROOM" "DEBUG"
					( Origin gFrontEnd )
				)
				( attribute "ROT" "0"
					( Origin gFrontEnd )
				)
				( attribute "SEC" "1"
					( Origin gFrontEnd )
				)
				( attribute "SEC_TYPE" "0402"
					( Origin gFrontEnd )
				)
				( attribute "TOLERANCE" "1%"
					( Origin gFrontEnd )
				)
				( attribute "VALUE" "33.2"
					( Origin gFrontEnd )
				)
				( attribute "VER" "2"
					( Origin gFrontEnd )
				)
				( attribute "WATTAGE" "1/16W"
					( Origin gFrontEnd )
				)
				( attribute "XY" "(-2925,2675)"
					( Origin gFrontEnd )
				)
				( attribute "CHIPS_PART_NAME" "RES"
					( Origin gPackager )
				)
				( attribute "CDS_PART_NAME" "RES_0402-33.2,1%,1/16W,EMPTY,GA"
					( Origin gPackager )
				)
				( objectStatus "R9A2" )
				( pin "a"
					( attribute "PN" "1"
						( Origin gPackager )
					)
					( objectStatus "R9A2.1" )
				)
				( pin "b"
					( attribute "PN" "2"
						( Origin gPackager )
					)
					( objectStatus "R9A2.2" )
				)
			)
			( gate "@baseboard_fab2_lib.baseboard_fab2(sch_1):page111_i85"
				( attribute "BOM_COST" "M-SATA"
					( Origin gFrontEnd )
				)
				( attribute "CDS_LIB" "mstr_ttl"
					( Origin gPackager )
				)
				( attribute "CDS_LOCATION" "U1L4"
					( Origin gPackager )
				)
				( attribute "CDS_SEC" "1"
					( Origin gPackager )
				)
				( attribute "LOCATION" "U1L4"
					( Origin gFrontEnd )
				)
				( attribute "MATERIAL" "IC"
					( Origin gFrontEnd )
				)
				( attribute "PACK_TYPE" "SOP"
					( Origin gFrontEnd )
				)
				( attribute "PART_NUMBER" "C88419-001"
					( Origin gFrontEnd )
				)
				( attribute "PHYS_PAGE" "111"
					( Origin gFrontEnd )
				)
				( attribute "ROOM" "M-SATA"
					( Origin gFrontEnd )
				)
				( attribute "ROT" "0"
					( Origin gFrontEnd )
				)
				( attribute "SEC" "1"
					( Origin gFrontEnd )
				)
				( attribute "SEC_TYPE" "SOP"
					( Origin gFrontEnd )
				)
				( attribute "VALUE" "74LVC1G07"
					( Origin gFrontEnd )
				)
				( attribute "VER" "1"
					( Origin gFrontEnd )
				)
				( attribute "XY" "(1775,2600)"
					( Origin gFrontEnd )
				)
				( attribute "CHIPS_PART_NAME" "TTL1G07_A"
					( Origin gPackager )
				)
				( attribute "CDS_PART_NAME" "TTL1G07_A_SOP-74LVC1G07,IC,C88B"
					( Origin gPackager )
				)
				( objectStatus "U1L4" )
				( pin "a"
					( attribute "PN" "2"
						( Origin gPackager )
					)
					( objectStatus "U1L4.2" )
				)
				( pin "y"
					( attribute "PN" "4"
						( Origin gPackager )
					)
					( objectStatus "U1L4.4" )
				)
			)
			( gate "@baseboard_fab2_lib.baseboard_fab2(sch_1):page111_i87"
				( attribute "BOM_COST" "DEBUG"
					( Origin gFrontEnd )
				)
				( attribute "CDS_LIB" "dev_discrete"
					( Origin gPackager )
				)
				( attribute "CDS_LOCATION" "C1L11"
					( Origin gPackager )
				)
				( attribute "CDS_SEC" "1"
					( Origin gPackager )
				)
				( attribute "LOCATION" "C1L11"
					( Origin gFrontEnd )
				)
				( attribute "MATERIAL" "X7R"
					( Origin gFrontEnd )
				)
				( attribute "PACK_TYPE" "0402V"
					( Origin gFrontEnd )
				)
				( attribute "PART_NUMBER" "A36096-030"
					( Origin gFrontEnd )
				)
				( attribute "PHYS_PAGE" "111"
					( Origin gFrontEnd )
				)
				( attribute "ROOM" "DEBUG"
					( Origin gFrontEnd )
				)
				( attribute "ROT" "0"
					( Origin gFrontEnd )
				)
				( attribute "SEC" "1"
					( Origin gFrontEnd )
				)
				( attribute "SEC_TYPE" "0402V"
					( Origin gFrontEnd )
				)
				( attribute "TOLERANCE" "10%"
					( Origin gFrontEnd )
				)
				( attribute "VALUE" "0.1UF"
					( Origin gFrontEnd )
				)
				( attribute "VER" "1"
					( Origin gFrontEnd )
				)
				( attribute "VOLTAGE" "16V"
					( Units "uVoltage" "V" 1.000000)
					( Origin gFrontEnd )
				)
				( attribute "XY" "(3900,3625)"
					( Origin gFrontEnd )
				)
				( attribute "CHIPS_PART_NAME" "CAP_A"
					( Origin gPackager )
				)
				( attribute "CDS_PART_NAME" "CAP_A_0402V-0.1UF,16V,10%,X7R,A"
					( Origin gPackager )
				)
				( objectStatus "C1L11" )
				( pin "a"
					( attribute "PN" "1"
						( Origin gPackager )
					)
					( objectStatus "C1L11.1" )
				)
				( pin "b"
					( attribute "PN" "2"
						( Origin gPackager )
					)
					( objectStatus "C1L11.2" )
				)
			)
			( gate "@baseboard_fab2_lib.baseboard_fab2(sch_1):page111_i89"
				( attribute "BOM_COST" "DEBUG"
					( Origin gFrontEnd )
				)
				( attribute "CDS_LIB" "mstr_discrete"
					( Origin gPackager )
				)
				( attribute "CDS_LOCATION" "R8E2"
					( Origin gPackager )
				)
				( attribute "CDS_SEC" "1"
					( Origin gPackager )
				)
				( attribute "LOCATION" "R8E2"
					( Origin gFrontEnd )
				)
				( attribute "MATERIAL" "CHIP"
					( Origin gFrontEnd )
				)
				( attribute "PACK_TYPE" "0402"
					( Origin gFrontEnd )
				)
				( attribute "PART_NUMBER" "G21796-026"
					( Origin gFrontEnd )
				)
				( attribute "PHYS_PAGE" "111"
					( Origin gFrontEnd )
				)
				( attribute "ROOM" "DEBUG"
					( Origin gFrontEnd )
				)
				( attribute "ROT" "0"
					( Origin gFrontEnd )
				)
				( attribute "SEC" "1"
					( Origin gFrontEnd )
				)
				( attribute "SEC_TYPE" "0402"
					( Origin gFrontEnd )
				)
				( attribute "TOLERANCE" "1%"
					( Origin gFrontEnd )
				)
				( attribute "VALUE" "1.00K"
					( Origin gFrontEnd )
				)
				( attribute "VER" "1"
					( Origin gFrontEnd )
				)
				( attribute "WATTAGE" "1/16W"
					( Origin gFrontEnd )
				)
				( attribute "XY" "(2050,4550)"
					( Origin gFrontEnd )
				)
				( attribute "CHIPS_PART_NAME" "RES"
					( Origin gPackager )
				)
				( attribute "CDS_PART_NAME" "RES_0402-1.00K,1%,1/16W,CHIP,GA"
					( Origin gPackager )
				)
				( objectStatus "R8E2" )
				( pin "a"
					( attribute "PN" "1"
						( Origin gPackager )
					)
					( objectStatus "R8E2.1" )
				)
				( pin "b"
					( attribute "PN" "2"
						( Origin gPackager )
					)
					( objectStatus "R8E2.2" )
				)
			)
			( gate "@baseboard_fab2_lib.baseboard_fab2(sch_1):page111_i93"
				( attribute "CDS_LIB" "mstr_discrete"
					( Origin gPackager )
				)
				( attribute "CDS_LOCATION" "Q9A1"
					( Origin gPackager )
				)
				( attribute "CDS_SEC" "2"
					( Origin gPackager )
				)
				( attribute "LOCATION" "Q9A1"
					( Origin gFrontEnd )
				)
				( attribute "MATERIAL" "EMPTY"
					( Origin gFrontEnd )
				)
				( attribute "PACK_TYPE" "SSOPLF"
					( Origin gFrontEnd )
				)
				( attribute "PART_NUMBER" "C52264-001"
					( Origin gFrontEnd )
				)
				( attribute "PHYS_PAGE" "111"
					( Origin gFrontEnd )
				)
				( attribute "ROOM" "DEBUG"
					( Origin gFrontEnd )
				)
				( attribute "ROT" "0"
					( Origin gFrontEnd )
				)
				( attribute "SEC" "2"
					( Origin gFrontEnd )
				)
				( attribute "SEC_TYPE" "SSOPLF"
					( Origin gFrontEnd )
				)
				( attribute "VALUE" "MBT3904"
					( Origin gFrontEnd )
				)
				( attribute "VER" "2"
					( Origin gFrontEnd )
				)
				( attribute "XY" "(-2300,2325)"
					( Origin gFrontEnd )
				)
				( attribute "CHIPS_PART_NAME" "NPN_DUAL"
					( Origin gPackager )
				)
				( attribute "CDS_PART_NAME" "NPN_DUAL_SSOPLF-MBT3904,EMPTY,A"
					( Origin gPackager )
				)
				( objectStatus "Q9A1" )
				( pin "b(0)"
					( attribute "PN" "2"
						( Origin gPackager )
					)
					( objectStatus "Q9A1.2" )
				)
				( pin "c(0)"
					( attribute "PN" "6"
						( Origin gPackager )
					)
					( objectStatus "Q9A1.6" )
				)
				( pin "e(0)"
					( attribute "PN" "1"
						( Origin gPackager )
					)
					( objectStatus "Q9A1.1" )
				)
			)
			( gate "@baseboard_fab2_lib.baseboard_fab2(sch_1):page111_i94"
				( attribute "CDS_LIB" "mstr_discrete"
					( Origin gPackager )
				)
				( attribute "CDS_LOCATION" "Q9A1"
					( Origin gPackager )
				)
				( attribute "CDS_SEC" "1"
					( Origin gPackager )
				)
				( attribute "LOCATION" "Q9A1"
					( Origin gFrontEnd )
				)
				( attribute "MATERIAL" "EMPTY"
					( Origin gFrontEnd )
				)
				( attribute "PACK_TYPE" "SSOPLF"
					( Origin gFrontEnd )
				)
				( attribute "PART_NUMBER" "C52264-001"
					( Origin gFrontEnd )
				)
				( attribute "PHYS_PAGE" "111"
					( Origin gFrontEnd )
				)
				( attribute "ROOM" "DEBUG"
					( Origin gFrontEnd )
				)
				( attribute "ROT" "0"
					( Origin gFrontEnd )
				)
				( attribute "SEC" "1"
					( Origin gFrontEnd )
				)
				( attribute "SEC_TYPE" "SSOPLF"
					( Origin gFrontEnd )
				)
				( attribute "VALUE" "MBT3904"
					( Origin gFrontEnd )
				)
				( attribute "VER" "1"
					( Origin gFrontEnd )
				)
				( attribute "XY" "(-1650,2275)"
					( Origin gFrontEnd )
				)
				( attribute "CHIPS_PART_NAME" "NPN_DUAL"
					( Origin gPackager )
				)
				( attribute "CDS_PART_NAME" "NPN_DUAL_SSOPLF-MBT3904,EMPTY,A"
					( Origin gPackager )
				)
				( objectStatus "Q9A1" )
				( pin "b(0)"
					( attribute "PN" "5"
						( Origin gPackager )
					)
					( objectStatus "Q9A1.5" )
				)
				( pin "c(0)"
					( attribute "PN" "3"
						( Origin gPackager )
					)
					( objectStatus "Q9A1.3" )
				)
				( pin "e(0)"
					( attribute "PN" "4"
						( Origin gPackager )
					)
					( objectStatus "Q9A1.4" )
				)
			)
			( gate "@baseboard_fab2_lib.baseboard_fab2(sch_1):page111_i95"
				( attribute "CDS_LIB" "mstr_discrete"
					( Origin gPackager )
				)
				( attribute "CDS_LOCATION" "R9A1"
					( Origin gPackager )
				)
				( attribute "CDS_SEC" "1"
					( Origin gPackager )
				)
				( attribute "LOCATION" "R9A1"
					( Origin gFrontEnd )
				)
				( attribute "MATERIAL" "EMPTY"
					( Origin gFrontEnd )
				)
				( attribute "PACK_TYPE" "0402"
					( Origin gFrontEnd )
				)
				( attribute "PART_NUMBER" "G21796-026"
					( Origin gFrontEnd )
				)
				( attribute "PHYS_PAGE" "111"
					( Origin gFrontEnd )
				)
				( attribute "ROOM" "DEBUG"
					( Origin gFrontEnd )
				)
				( attribute "ROT" "2"
					( Origin gFrontEnd )
				)
				( attribute "SEC" "1"
					( Origin gFrontEnd )
				)
				( attribute "SEC_TYPE" "0402"
					( Origin gFrontEnd )
				)
				( attribute "TOLERANCE" "1%"
					( Origin gFrontEnd )
				)
				( attribute "VALUE" "1.00K"
					( Origin gFrontEnd )
				)
				( attribute "VER" "2"
					( Origin gFrontEnd )
				)
				( attribute "WATTAGE" "1/16W"
					( Origin gFrontEnd )
				)
				( attribute "XY" "(-2075,2675)"
					( Origin gFrontEnd )
				)
				( attribute "CHIPS_PART_NAME" "RES"
					( Origin gPackager )
				)
				( attribute "CDS_PART_NAME" "RES_0402-1.00K,1%,1/16W,EMPTY,A"
					( Origin gPackager )
				)
				( objectStatus "R9A1" )
				( pin "a"
					( attribute "PN" "1"
						( Origin gPackager )
					)
					( objectStatus "R9A1.1" )
				)
				( pin "b"
					( attribute "PN" "2"
						( Origin gPackager )
					)
					( objectStatus "R9A1.2" )
				)
			)
			( gate "@baseboard_fab2_lib.baseboard_fab2(sch_1):page112_i40"
				( attribute "BOM_COST" "DEBUG"
					( Origin gFrontEnd )
				)
				( attribute "CDS_LIB" "mstr_analog"
					( Origin gPackager )
				)
				( attribute "CDS_LOCATION" "U1M7"
					( Origin gPackager )
				)
				( attribute "CDS_SEC" "1"
					( Origin gPackager )
				)
				( attribute "LOCATION" "U1M7"
					( Origin gFrontEnd )
				)
				( attribute "MATERIAL" "IC"
					( Origin gFrontEnd )
				)
				( attribute "PACK_TYPE" "SMLF"
					( Origin gFrontEnd )
				)
				( attribute "PART_NUMBER" "C99406-001"
					( Origin gFrontEnd )
				)
				( attribute "PHYS_PAGE" "112"
					( Origin gFrontEnd )
				)
				( attribute "ROOM" "DEBUG"
					( Origin gFrontEnd )
				)
				( attribute "ROT" "2"
					( Origin gFrontEnd )
				)
				( attribute "SEC" "1"
					( Origin gPackager )
				)
				( attribute "VER" "1"
					( Origin gFrontEnd )
				)
				( attribute "XY" "(2600,4675)"
					( Origin gFrontEnd )
				)
				( attribute "CHIPS_PART_NAME" "NC7SB3157"
					( Origin gPackager )
				)
				( attribute "CDS_PART_NAME" "NC7SB3157_SMLF-IC,C99406-001"
					( Origin gPackager )
				)
				( objectStatus "U1M7" )
				( pin "a"
					( attribute "PN" "4"
						( Origin gPackager )
					)
					( objectStatus "U1M7.4" )
				)
				( pin "b0"
					( attribute "PN" "3"
						( Origin gPackager )
					)
					( objectStatus "U1M7.3" )
				)
				( pin "b1"
					( attribute "PN" "1"
						( Origin gPackager )
					)
					( objectStatus "U1M7.1" )
				)
				( pin "gnd"
					( attribute "PN" "2"
						( Origin gPackager )
					)
					( objectStatus "U1M7.2" )
				)
				( pin "s"
					( attribute "PN" "6"
						( Origin gPackager )
					)
					( objectStatus "U1M7.6" )
				)
				( pin "vcc"
					( attribute "PN" "5"
						( Origin gPackager )
					)
					( objectStatus "U1M7.5" )
				)
			)
			( gate "@baseboard_fab2_lib.baseboard_fab2(sch_1):page112_i42"
				( attribute "BOM_COST" "DEBUG"
					( Origin gFrontEnd )
				)
				( attribute "CDS_LIB" "dev_discrete"
					( Origin gPackager )
				)
				( attribute "CDS_LOCATION" "C1M36"
					( Origin gPackager )
				)
				( attribute "CDS_SEC" "1"
					( Origin gPackager )
				)
				( attribute "LOCATION" "C1M36"
					( Origin gFrontEnd )
				)
				( attribute "MATERIAL" "X7R"
					( Origin gFrontEnd )
				)
				( attribute "PACK_TYPE" "0402V"
					( Origin gFrontEnd )
				)
				( attribute "PART_NUMBER" "A36096-045"
					( Origin gFrontEnd )
				)
				( attribute "PHYS_PAGE" "112"
					( Origin gFrontEnd )
				)
				( attribute "ROOM" "DEBUG"
					( Origin gFrontEnd )
				)
				( attribute "ROT" "2"
					( Origin gFrontEnd )
				)
				( attribute "SEC" "1"
					( Origin gFrontEnd )
				)
				( attribute "SEC_TYPE" "0402V"
					( Origin gFrontEnd )
				)
				( attribute "TOLERANCE" "10%"
					( Origin gFrontEnd )
				)
				( attribute "VALUE" "0.01UF"
					( Origin gFrontEnd )
				)
				( attribute "VER" "1"
					( Origin gFrontEnd )
				)
				( attribute "VOLTAGE" "25V"
					( Units "uVoltage" "V" 1.000000)
					( Origin gFrontEnd )
				)
				( attribute "XY" "(3100,4025)"
					( Origin gFrontEnd )
				)
				( attribute "CHIPS_PART_NAME" "CAP_A"
					( Origin gPackager )
				)
				( attribute "CDS_PART_NAME" "CAP_A_0402V-0.01UF,25V,10%,X7RA"
					( Origin gPackager )
				)
				( objectStatus "C1M36" )
				( pin "a"
					( attribute "PN" "1"
						( Origin gPackager )
					)
					( objectStatus "C1M36.1" )
				)
				( pin "b"
					( attribute "PN" "2"
						( Origin gPackager )
					)
					( objectStatus "C1M36.2" )
				)
			)
			( gate "@baseboard_fab2_lib.baseboard_fab2(sch_1):page112_i47"
				( attribute "BOM_COST" "DEBUG"
					( Origin gFrontEnd )
				)
				( attribute "CDS_LIB" "dev_discrete"
					( Origin gPackager )
				)
				( attribute "CDS_LOCATION" "C1M37"
					( Origin gPackager )
				)
				( attribute "CDS_SEC" "1"
					( Origin gPackager )
				)
				( attribute "LOCATION" "C1M37"
					( Origin gFrontEnd )
				)
				( attribute "MATERIAL" "X6S"
					( Origin gFrontEnd )
				)
				( attribute "PACK_TYPE" "0402V"
					( Origin gFrontEnd )
				)
				( attribute "PART_NUMBER" "D97712-004"
					( Origin gFrontEnd )
				)
				( attribute "PHYS_PAGE" "112"
					( Origin gFrontEnd )
				)
				( attribute "ROOM" "DEBUG"
					( Origin gFrontEnd )
				)
				( attribute "ROT" "2"
					( Origin gFrontEnd )
				)
				( attribute "SEC" "1"
					( Origin gPackager )
				)
				( attribute "TOLERANCE" "10%"
					( Origin gFrontEnd )
				)
				( attribute "VALUE" "1.0UF"
					( Origin gFrontEnd )
				)
				( attribute "VER" "1"
					( Origin gFrontEnd )
				)
				( attribute "VOLTAGE" "6.3V"
					( Units "uVoltage" "V" 1.000000)
					( Origin gFrontEnd )
				)
				( attribute "XY" "(2700,4025)"
					( Origin gFrontEnd )
				)
				( attribute "CHIPS_PART_NAME" "CAP_A"
					( Origin gPackager )
				)
				( attribute "CDS_PART_NAME" "CAP_A_0402V-1.0UF,6.3V,10%,X6SA"
					( Origin gPackager )
				)
				( objectStatus "C1M37" )
				( pin "a"
					( attribute "PN" "1"
						( Origin gPackager )
					)
					( objectStatus "C1M37.1" )
				)
				( pin "b"
					( attribute "PN" "2"
						( Origin gPackager )
					)
					( objectStatus "C1M37.2" )
				)
			)
			( gate "@baseboard_fab2_lib.baseboard_fab2(sch_1):page112_i49"
				( attribute "CDS_LIB" "mstr_discrete"
					( Origin gPackager )
				)
				( attribute "CDS_LOCATION" "R6P46"
					( Origin gPackager )
				)
				( attribute "CDS_SEC" "1"
					( Origin gPackager )
				)
				( attribute "LOCATION" "R6P46"
					( Origin gFrontEnd )
				)
				( attribute "MATERIAL" "CHIP"
					( Origin gFrontEnd )
				)
				( attribute "PACK_TYPE" "0402"
					( Origin gFrontEnd )
				)
				( attribute "PART_NUMBER" "G21796-017"
					( Origin gFrontEnd )
				)
				( attribute "PHYS_PAGE" "112"
					( Origin gFrontEnd )
				)
				( attribute "ROOM" "DEBUG"
					( Origin gFrontEnd )
				)
				( attribute "ROT" "0"
					( Origin gFrontEnd )
				)
				( attribute "SEC" "1"
					( Origin gFrontEnd )
				)
				( attribute "SEC_TYPE" "0402"
					( Origin gFrontEnd )
				)
				( attribute "TOLERANCE" "1%"
					( Origin gFrontEnd )
				)
				( attribute "VALUE" "100.0"
					( Origin gFrontEnd )
				)
				( attribute "VER" "2"
					( Origin gFrontEnd )
				)
				( attribute "WATTAGE" "1/16W"
					( Origin gFrontEnd )
				)
				( attribute "XY" "(2675,2400)"
					( Origin gFrontEnd )
				)
				( attribute "CHIPS_PART_NAME" "RES"
					( Origin gPackager )
				)
				( attribute "CDS_PART_NAME" "RES_0402-100.0,1%,1/16W,CHIP,GA"
					( Origin gPackager )
				)
				( objectStatus "R6P46" )
				( pin "a"
					( attribute "PN" "1"
						( Origin gPackager )
					)
					( objectStatus "R6P46.1" )
				)
				( pin "b"
					( attribute "PN" "2"
						( Origin gPackager )
					)
					( objectStatus "R6P46.2" )
				)
			)
			( gate "@baseboard_fab2_lib.baseboard_fab2(sch_1):page112_i50"
				( attribute "CDS_LIB" "mstr_discrete"
					( Origin gPackager )
				)
				( attribute "CDS_LOCATION" "R7P30"
					( Origin gPackager )
				)
				( attribute "CDS_SEC" "1"
					( Origin gPackager )
				)
				( attribute "LOCATION" "R7P30"
					( Origin gFrontEnd )
				)
				( attribute "MATERIAL" "CHIP"
					( Origin gFrontEnd )
				)
				( attribute "PACK_TYPE" "0402"
					( Origin gFrontEnd )
				)
				( attribute "PART_NUMBER" "G21796-017"
					( Origin gFrontEnd )
				)
				( attribute "PHYS_PAGE" "112"
					( Origin gFrontEnd )
				)
				( attribute "ROOM" "DEBUG"
					( Origin gFrontEnd )
				)
				( attribute "ROT" "0"
					( Origin gFrontEnd )
				)
				( attribute "SEC" "1"
					( Origin gFrontEnd )
				)
				( attribute "SEC_TYPE" "0402"
					( Origin gFrontEnd )
				)
				( attribute "TOLERANCE" "1%"
					( Origin gFrontEnd )
				)
				( attribute "VALUE" "100.0"
					( Origin gFrontEnd )
				)
				( attribute "VER" "2"
					( Origin gFrontEnd )
				)
				( attribute "WATTAGE" "1/16W"
					( Origin gFrontEnd )
				)
				( attribute "XY" "(2325,2400)"
					( Origin gFrontEnd )
				)
				( attribute "CHIPS_PART_NAME" "RES"
					( Origin gPackager )
				)
				( attribute "CDS_PART_NAME" "RES_0402-100.0,1%,1/16W,CHIP,GA"
					( Origin gPackager )
				)
				( objectStatus "R7P30" )
				( pin "a"
					( attribute "PN" "1"
						( Origin gPackager )
					)
					( objectStatus "R7P30.1" )
				)
				( pin "b"
					( attribute "PN" "2"
						( Origin gPackager )
					)
					( objectStatus "R7P30.2" )
				)
			)
			( gate "@baseboard_fab2_lib.baseboard_fab2(sch_1):page112_i51"
				( attribute "CDS_LIB" "mstr_discrete"
					( Origin gPackager )
				)
				( attribute "CDS_LOCATION" "R1M3"
					( Origin gPackager )
				)
				( attribute "CDS_SEC" "1"
					( Origin gPackager )
				)
				( attribute "LOCATION" "R1M3"
					( Origin gFrontEnd )
				)
				( attribute "MATERIAL" "CHIP"
					( Origin gFrontEnd )
				)
				( attribute "PACK_TYPE" "0402"
					( Origin gFrontEnd )
				)
				( attribute "PART_NUMBER" "G21796-017"
					( Origin gFrontEnd )
				)
				( attribute "PHYS_PAGE" "112"
					( Origin gFrontEnd )
				)
				( attribute "ROOM" "DEBUG"
					( Origin gFrontEnd )
				)
				( attribute "ROT" "0"
					( Origin gFrontEnd )
				)
				( attribute "SEC" "1"
					( Origin gFrontEnd )
				)
				( attribute "SEC_TYPE" "0402"
					( Origin gFrontEnd )
				)
				( attribute "TOLERANCE" "1%"
					( Origin gFrontEnd )
				)
				( attribute "VALUE" "100.0"
					( Origin gFrontEnd )
				)
				( attribute "VER" "2"
					( Origin gFrontEnd )
				)
				( attribute "WATTAGE" "1/16W"
					( Origin gFrontEnd )
				)
				( attribute "XY" "(1950,2400)"
					( Origin gFrontEnd )
				)
				( attribute "CHIPS_PART_NAME" "RES"
					( Origin gPackager )
				)
				( attribute "CDS_PART_NAME" "RES_0402-100.0,1%,1/16W,CHIP,GA"
					( Origin gPackager )
				)
				( objectStatus "R1M3" )
				( pin "a"
					( attribute "PN" "1"
						( Origin gPackager )
					)
					( objectStatus "R1M3.1" )
				)
				( pin "b"
					( attribute "PN" "2"
						( Origin gPackager )
					)
					( objectStatus "R1M3.2" )
				)
			)
			( gate "@baseboard_fab2_lib.baseboard_fab2(sch_1):page112_i53"
				( attribute "CDS_LIB" "mstr_discrete"
					( Origin gPackager )
				)
				( attribute "CDS_LOCATION" "R4P15"
					( Origin gPackager )
				)
				( attribute "CDS_SEC" "1"
					( Origin gPackager )
				)
				( attribute "LOCATION" "R4P15"
					( Origin gFrontEnd )
				)
				( attribute "MATERIAL" "CHIP"
					( Origin gFrontEnd )
				)
				( attribute "PACK_TYPE" "0402"
					( Origin gFrontEnd )
				)
				( attribute "PART_NUMBER" "G21796-017"
					( Origin gFrontEnd )
				)
				( attribute "PHYS_PAGE" "112"
					( Origin gFrontEnd )
				)
				( attribute "ROOM" "DEBUG"
					( Origin gFrontEnd )
				)
				( attribute "ROT" "0"
					( Origin gFrontEnd )
				)
				( attribute "SEC" "1"
					( Origin gFrontEnd )
				)
				( attribute "SEC_TYPE" "0402"
					( Origin gFrontEnd )
				)
				( attribute "TOLERANCE" "1%"
					( Origin gFrontEnd )
				)
				( attribute "VALUE" "100.0"
					( Origin gFrontEnd )
				)
				( attribute "VER" "2"
					( Origin gFrontEnd )
				)
				( attribute "WATTAGE" "1/16W"
					( Origin gFrontEnd )
				)
				( attribute "XY" "(1175,3800)"
					( Origin gFrontEnd )
				)
				( attribute "CHIPS_PART_NAME" "RES"
					( Origin gPackager )
				)
				( attribute "CDS_PART_NAME" "RES_0402-100.0,1%,1/16W,CHIP,GA"
					( Origin gPackager )
				)
				( objectStatus "R4P15" )
				( pin "a"
					( attribute "PN" "1"
						( Origin gPackager )
					)
					( objectStatus "R4P15.1" )
				)
				( pin "b"
					( attribute "PN" "2"
						( Origin gPackager )
					)
					( objectStatus "R4P15.2" )
				)
			)
			( gate "@baseboard_fab2_lib.baseboard_fab2(sch_1):page112_i54"
				( attribute "CDS_LIB" "mstr_discrete"
					( Origin gPackager )
				)
				( attribute "CDS_LOCATION" "R1M4"
					( Origin gPackager )
				)
				( attribute "CDS_SEC" "1"
					( Origin gPackager )
				)
				( attribute "LOCATION" "R1M4"
					( Origin gFrontEnd )
				)
				( attribute "MATERIAL" "CHIP"
					( Origin gFrontEnd )
				)
				( attribute "PACK_TYPE" "0402"
					( Origin gFrontEnd )
				)
				( attribute "PART_NUMBER" "G21796-017"
					( Origin gFrontEnd )
				)
				( attribute "PHYS_PAGE" "112"
					( Origin gFrontEnd )
				)
				( attribute "ROOM" "DEBUG"
					( Origin gFrontEnd )
				)
				( attribute "ROT" "0"
					( Origin gFrontEnd )
				)
				( attribute "SEC" "1"
					( Origin gFrontEnd )
				)
				( attribute "SEC_TYPE" "0402"
					( Origin gFrontEnd )
				)
				( attribute "TOLERANCE" "1%"
					( Origin gFrontEnd )
				)
				( attribute "VALUE" "100.0"
					( Origin gFrontEnd )
				)
				( attribute "VER" "2"
					( Origin gFrontEnd )
				)
				( attribute "WATTAGE" "1/16W"
					( Origin gFrontEnd )
				)
				( attribute "XY" "(1600,2400)"
					( Origin gFrontEnd )
				)
				( attribute "CHIPS_PART_NAME" "RES"
					( Origin gPackager )
				)
				( attribute "CDS_PART_NAME" "RES_0402-100.0,1%,1/16W,CHIP,GA"
					( Origin gPackager )
				)
				( objectStatus "R1M4" )
				( pin "a"
					( attribute "PN" "1"
						( Origin gPackager )
					)
					( objectStatus "R1M4.1" )
				)
				( pin "b"
					( attribute "PN" "2"
						( Origin gPackager )
					)
					( objectStatus "R1M4.2" )
				)
			)
			( gate "@baseboard_fab2_lib.baseboard_fab2(sch_1):page112_i55"
				( attribute "CDS_LIB" "mstr_discrete"
					( Origin gPackager )
				)
				( attribute "CDS_LOCATION" "R6T7"
					( Origin gPackager )
				)
				( attribute "CDS_SEC" "1"
					( Origin gPackager )
				)
				( attribute "LOCATION" "R6T7"
					( Origin gFrontEnd )
				)
				( attribute "MATERIAL" "CHIP"
					( Origin gFrontEnd )
				)
				( attribute "PACK_TYPE" "0402"
					( Origin gFrontEnd )
				)
				( attribute "PART_NUMBER" "G21796-009"
					( Origin gFrontEnd )
				)
				( attribute "PHYS_PAGE" "112"
					( Origin gFrontEnd )
				)
				( attribute "ROOM" "DEBUG"
					( Origin gFrontEnd )
				)
				( attribute "ROT" "0"
					( Origin gFrontEnd )
				)
				( attribute "SEC" "1"
					( Origin gFrontEnd )
				)
				( attribute "SEC_TYPE" "0402"
					( Origin gFrontEnd )
				)
				( attribute "TOLERANCE" "1%"
					( Origin gFrontEnd )
				)
				( attribute "VALUE" "150.0"
					( Origin gFrontEnd )
				)
				( attribute "VER" "2"
					( Origin gFrontEnd )
				)
				( attribute "WATTAGE" "1/16W"
					( Origin gFrontEnd )
				)
				( attribute "XY" "(1225,2400)"
					( Origin gFrontEnd )
				)
				( attribute "CHIPS_PART_NAME" "RES"
					( Origin gPackager )
				)
				( attribute "CDS_PART_NAME" "RES_0402-150.0,1%,1/16W,CHIP,GA"
					( Origin gPackager )
				)
				( objectStatus "R6T7" )
				( pin "a"
					( attribute "PN" "1"
						( Origin gPackager )
					)
					( objectStatus "R6T7.1" )
				)
				( pin "b"
					( attribute "PN" "2"
						( Origin gPackager )
					)
					( objectStatus "R6T7.2" )
				)
			)
			( gate "@baseboard_fab2_lib.baseboard_fab2(sch_1):page112_i56"
				( attribute "CDS_LIB" "mstr_discrete"
					( Origin gPackager )
				)
				( attribute "CDS_LOCATION" "R6T6"
					( Origin gPackager )
				)
				( attribute "CDS_SEC" "1"
					( Origin gPackager )
				)
				( attribute "LOCATION" "R6T6"
					( Origin gFrontEnd )
				)
				( attribute "MATERIAL" "CHIP"
					( Origin gFrontEnd )
				)
				( attribute "PACK_TYPE" "0402"
					( Origin gFrontEnd )
				)
				( attribute "PART_NUMBER" "G21796-009"
					( Origin gFrontEnd )
				)
				( attribute "PHYS_PAGE" "112"
					( Origin gFrontEnd )
				)
				( attribute "ROOM" "DEBUG"
					( Origin gFrontEnd )
				)
				( attribute "ROT" "0"
					( Origin gFrontEnd )
				)
				( attribute "SEC" "1"
					( Origin gFrontEnd )
				)
				( attribute "SEC_TYPE" "0402"
					( Origin gFrontEnd )
				)
				( attribute "TOLERANCE" "1%"
					( Origin gFrontEnd )
				)
				( attribute "VALUE" "150.0"
					( Origin gFrontEnd )
				)
				( attribute "VER" "2"
					( Origin gFrontEnd )
				)
				( attribute "WATTAGE" "1/16W"
					( Origin gFrontEnd )
				)
				( attribute "XY" "(875,2400)"
					( Origin gFrontEnd )
				)
				( attribute "CHIPS_PART_NAME" "RES"
					( Origin gPackager )
				)
				( attribute "CDS_PART_NAME" "RES_0402-150.0,1%,1/16W,CHIP,GA"
					( Origin gPackager )
				)
				( objectStatus "R6T6" )
				( pin "a"
					( attribute "PN" "1"
						( Origin gPackager )
					)
					( objectStatus "R6T6.1" )
				)
				( pin "b"
					( attribute "PN" "2"
						( Origin gPackager )
					)
					( objectStatus "R6T6.2" )
				)
			)
			( gate "@baseboard_fab2_lib.baseboard_fab2(sch_1):page112_i57"
				( attribute "CDS_LIB" "mstr_discrete"
					( Origin gPackager )
				)
				( attribute "CDS_LOCATION" "R4P12"
					( Origin gPackager )
				)
				( attribute "CDS_SEC" "1"
					( Origin gPackager )
				)
				( attribute "LOCATION" "R4P12"
					( Origin gFrontEnd )
				)
				( attribute "MATERIAL" "CHIP"
					( Origin gFrontEnd )
				)
				( attribute "PACK_TYPE" "0402"
					( Origin gFrontEnd )
				)
				( attribute "PART_NUMBER" "G21796-017"
					( Origin gFrontEnd )
				)
				( attribute "PHYS_PAGE" "112"
					( Origin gFrontEnd )
				)
				( attribute "ROOM" "DEBUG"
					( Origin gFrontEnd )
				)
				( attribute "ROT" "0"
					( Origin gFrontEnd )
				)
				( attribute "SEC" "1"
					( Origin gFrontEnd )
				)
				( attribute "SEC_TYPE" "0402"
					( Origin gFrontEnd )
				)
				( attribute "TOLERANCE" "1%"
					( Origin gFrontEnd )
				)
				( attribute "VALUE" "100.0"
					( Origin gFrontEnd )
				)
				( attribute "VER" "2"
					( Origin gFrontEnd )
				)
				( attribute "WATTAGE" "1/16W"
					( Origin gFrontEnd )
				)
				( attribute "XY" "(875,3825)"
					( Origin gFrontEnd )
				)
				( attribute "CHIPS_PART_NAME" "RES"
					( Origin gPackager )
				)
				( attribute "CDS_PART_NAME" "RES_0402-100.0,1%,1/16W,CHIP,GA"
					( Origin gPackager )
				)
				( objectStatus "R4P12" )
				( pin "a"
					( attribute "PN" "1"
						( Origin gPackager )
					)
					( objectStatus "R4P12.1" )
				)
				( pin "b"
					( attribute "PN" "2"
						( Origin gPackager )
					)
					( objectStatus "R4P12.2" )
				)
			)
			( gate "@baseboard_fab2_lib.baseboard_fab2(sch_1):page112_i58"
				( attribute "CDS_LIB" "mstr_discrete"
					( Origin gPackager )
				)
				( attribute "CDS_LOCATION" "R4P23"
					( Origin gPackager )
				)
				( attribute "CDS_SEC" "1"
					( Origin gPackager )
				)
				( attribute "LOCATION" "R4P23"
					( Origin gFrontEnd )
				)
				( attribute "MATERIAL" "CHIP"
					( Origin gFrontEnd )
				)
				( attribute "PACK_TYPE" "0402"
					( Origin gFrontEnd )
				)
				( attribute "PART_NUMBER" "G21796-009"
					( Origin gFrontEnd )
				)
				( attribute "PHYS_PAGE" "112"
					( Origin gFrontEnd )
				)
				( attribute "ROOM" "DEBUG"
					( Origin gFrontEnd )
				)
				( attribute "ROT" "0"
					( Origin gFrontEnd )
				)
				( attribute "SEC" "1"
					( Origin gFrontEnd )
				)
				( attribute "SEC_TYPE" "0402"
					( Origin gFrontEnd )
				)
				( attribute "TOLERANCE" "1%"
					( Origin gFrontEnd )
				)
				( attribute "VALUE" "150.0"
					( Origin gFrontEnd )
				)
				( attribute "VER" "2"
					( Origin gFrontEnd )
				)
				( attribute "WATTAGE" "1/16W"
					( Origin gFrontEnd )
				)
				( attribute "XY" "(575,3800)"
					( Origin gFrontEnd )
				)
				( attribute "CHIPS_PART_NAME" "RES"
					( Origin gPackager )
				)
				( attribute "CDS_PART_NAME" "RES_0402-150.0,1%,1/16W,CHIP,GA"
					( Origin gPackager )
				)
				( objectStatus "R4P23" )
				( pin "a"
					( attribute "PN" "1"
						( Origin gPackager )
					)
					( objectStatus "R4P23.1" )
				)
				( pin "b"
					( attribute "PN" "2"
						( Origin gPackager )
					)
					( objectStatus "R4P23.2" )
				)
			)
			( gate "@baseboard_fab2_lib.baseboard_fab2(sch_1):page112_i59"
				( attribute "CDS_LIB" "mstr_discrete"
					( Origin gPackager )
				)
				( attribute "CDS_LOCATION" "R4P24"
					( Origin gPackager )
				)
				( attribute "CDS_SEC" "1"
					( Origin gPackager )
				)
				( attribute "LOCATION" "R4P24"
					( Origin gFrontEnd )
				)
				( attribute "MATERIAL" "CHIP"
					( Origin gFrontEnd )
				)
				( attribute "PACK_TYPE" "0402"
					( Origin gFrontEnd )
				)
				( attribute "PART_NUMBER" "G21796-009"
					( Origin gFrontEnd )
				)
				( attribute "PHYS_PAGE" "112"
					( Origin gFrontEnd )
				)
				( attribute "ROOM" "DEBUG"
					( Origin gFrontEnd )
				)
				( attribute "ROT" "0"
					( Origin gFrontEnd )
				)
				( attribute "SEC" "1"
					( Origin gFrontEnd )
				)
				( attribute "SEC_TYPE" "0402"
					( Origin gFrontEnd )
				)
				( attribute "TOLERANCE" "1%"
					( Origin gFrontEnd )
				)
				( attribute "VALUE" "150.0"
					( Origin gFrontEnd )
				)
				( attribute "VER" "2"
					( Origin gFrontEnd )
				)
				( attribute "WATTAGE" "1/16W"
					( Origin gFrontEnd )
				)
				( attribute "XY" "(275,3800)"
					( Origin gFrontEnd )
				)
				( attribute "CHIPS_PART_NAME" "RES"
					( Origin gPackager )
				)
				( attribute "CDS_PART_NAME" "RES_0402-150.0,1%,1/16W,CHIP,GA"
					( Origin gPackager )
				)
				( objectStatus "R4P24" )
				( pin "a"
					( attribute "PN" "1"
						( Origin gPackager )
					)
					( objectStatus "R4P24.1" )
				)
				( pin "b"
					( attribute "PN" "2"
						( Origin gPackager )
					)
					( objectStatus "R4P24.2" )
				)
			)
			( gate "@baseboard_fab2_lib.baseboard_fab2(sch_1):page112_i60"
				( attribute "CDS_LIB" "mstr_discrete"
					( Origin gPackager )
				)
				( attribute "CDS_LOCATION" "R1L15"
					( Origin gPackager )
				)
				( attribute "CDS_SEC" "1"
					( Origin gPackager )
				)
				( attribute "LOCATION" "R1L15"
					( Origin gFrontEnd )
				)
				( attribute "MATERIAL" "CHIP"
					( Origin gFrontEnd )
				)
				( attribute "PACK_TYPE" "0402"
					( Origin gFrontEnd )
				)
				( attribute "PART_NUMBER" "G21796-009"
					( Origin gFrontEnd )
				)
				( attribute "PHYS_PAGE" "112"
					( Origin gFrontEnd )
				)
				( attribute "ROOM" "DEBUG"
					( Origin gFrontEnd )
				)
				( attribute "ROT" "0"
					( Origin gFrontEnd )
				)
				( attribute "SEC" "1"
					( Origin gFrontEnd )
				)
				( attribute "SEC_TYPE" "0402"
					( Origin gFrontEnd )
				)
				( attribute "TOLERANCE" "1%"
					( Origin gFrontEnd )
				)
				( attribute "VALUE" "150.0"
					( Origin gFrontEnd )
				)
				( attribute "VER" "2"
					( Origin gFrontEnd )
				)
				( attribute "WATTAGE" "1/16W"
					( Origin gFrontEnd )
				)
				( attribute "XY" "(500,2400)"
					( Origin gFrontEnd )
				)
				( attribute "CHIPS_PART_NAME" "RES"
					( Origin gPackager )
				)
				( attribute "CDS_PART_NAME" "RES_0402-150.0,1%,1/16W,CHIP,GA"
					( Origin gPackager )
				)
				( objectStatus "R1L15" )
				( pin "a"
					( attribute "PN" "1"
						( Origin gPackager )
					)
					( objectStatus "R1L15.1" )
				)
				( pin "b"
					( attribute "PN" "2"
						( Origin gPackager )
					)
					( objectStatus "R1L15.2" )
				)
			)
			( gate "@baseboard_fab2_lib.baseboard_fab2(sch_1):page112_i61"
				( attribute "BOM_COST" "DEBUG"
					( Origin gFrontEnd )
				)
				( attribute "CDS_LIB" "mstr_discrete"
					( Origin gPackager )
				)
				( attribute "CDS_LOCATION" "R7P29"
					( Origin gPackager )
				)
				( attribute "CDS_SEC" "1"
					( Origin gPackager )
				)
				( attribute "LOCATION" "R7P29"
					( Origin gFrontEnd )
				)
				( attribute "MATERIAL" "CHIP"
					( Origin gFrontEnd )
				)
				( attribute "PACK_TYPE" "0402"
					( Origin gFrontEnd )
				)
				( attribute "PART_NUMBER" "G21796-208"
					( Origin gFrontEnd )
				)
				( attribute "PHYS_PAGE" "112"
					( Origin gFrontEnd )
				)
				( attribute "ROOM" "DEBUG"
					( Origin gFrontEnd )
				)
				( attribute "ROT" "0"
					( Origin gFrontEnd )
				)
				( attribute "SEC" "1"
					( Origin gPackager )
				)
				( attribute "TOLERANCE" "1.0%"
					( Origin gFrontEnd )
				)
				( attribute "VALUE" "51.1"
					( Origin gFrontEnd )
				)
				( attribute "VER" "2"
					( Origin gFrontEnd )
				)
				( attribute "WATTAGE" "1/16W"
					( Origin gFrontEnd )
				)
				( attribute "XY" "(875,1100)"
					( Origin gFrontEnd )
				)
				( attribute "CHIPS_PART_NAME" "RES"
					( Origin gPackager )
				)
				( attribute "CDS_PART_NAME" "RES_0402-51.1,1.0%,1/16W,CHIP,A"
					( Origin gPackager )
				)
				( objectStatus "R7P29" )
				( pin "a"
					( attribute "PN" "1"
						( Origin gPackager )
					)
					( objectStatus "R7P29.1" )
				)
				( pin "b"
					( attribute "PN" "2"
						( Origin gPackager )
					)
					( objectStatus "R7P29.2" )
				)
			)
			( gate "@baseboard_fab2_lib.baseboard_fab2(sch_1):page112_i62"
				( attribute "BOM_COST" "DEBUG"
					( Origin gFrontEnd )
				)
				( attribute "CDS_LIB" "mstr_discrete"
					( Origin gPackager )
				)
				( attribute "CDS_LOCATION" "R6T5"
					( Origin gPackager )
				)
				( attribute "CDS_SEC" "1"
					( Origin gPackager )
				)
				( attribute "LOCATION" "R6T5"
					( Origin gFrontEnd )
				)
				( attribute "MATERIAL" "CHIP"
					( Origin gFrontEnd )
				)
				( attribute "PACK_TYPE" "0402"
					( Origin gFrontEnd )
				)
				( attribute "PART_NUMBER" "G21796-026"
					( Origin gFrontEnd )
				)
				( attribute "PHYS_PAGE" "112"
					( Origin gFrontEnd )
				)
				( attribute "ROOM" "DEBUG"
					( Origin gFrontEnd )
				)
				( attribute "ROT" "0"
					( Origin gFrontEnd )
				)
				( attribute "SEC" "1"
					( Origin gFrontEnd )
				)
				( attribute "SEC_TYPE" "0402"
					( Origin gFrontEnd )
				)
				( attribute "TOLERANCE" "1%"
					( Origin gFrontEnd )
				)
				( attribute "VALUE" "1.00K"
					( Origin gFrontEnd )
				)
				( attribute "VER" "2"
					( Origin gFrontEnd )
				)
				( attribute "WATTAGE" "1/16W"
					( Origin gFrontEnd )
				)
				( attribute "XY" "(500,1100)"
					( Origin gFrontEnd )
				)
				( attribute "CHIPS_PART_NAME" "RES"
					( Origin gPackager )
				)
				( attribute "CDS_PART_NAME" "RES_0402-1.00K,1%,1/16W,CHIP,GA"
					( Origin gPackager )
				)
				( objectStatus "R6T5" )
				( pin "a"
					( attribute "PN" "1"
						( Origin gPackager )
					)
					( objectStatus "R6T5.1" )
				)
				( pin "b"
					( attribute "PN" "2"
						( Origin gPackager )
					)
					( objectStatus "R6T5.2" )
				)
			)
			( gate "@baseboard_fab2_lib.baseboard_fab2(sch_1):page112_i76"
				( attribute "CDS_LIB" "mstr_discrete"
					( Origin gPackager )
				)
				( attribute "CDS_LOCATION" "R1L39"
					( Origin gPackager )
				)
				( attribute "CDS_SEC" "1"
					( Origin gPackager )
				)
				( attribute "LOCATION" "R1L39"
					( Origin gFrontEnd )
				)
				( attribute "MATERIAL" "CHIP"
					( Origin gFrontEnd )
				)
				( attribute "PACK_TYPE" "0402"
					( Origin gFrontEnd )
				)
				( attribute "PART_NUMBER" "G21796-017"
					( Origin gFrontEnd )
				)
				( attribute "PHYS_PAGE" "112"
					( Origin gFrontEnd )
				)
				( attribute "ROOM" "DEBUG"
					( Origin gFrontEnd )
				)
				( attribute "ROT" "0"
					( Origin gFrontEnd )
				)
				( attribute "SEC" "1"
					( Origin gFrontEnd )
				)
				( attribute "SEC_TYPE" "0402"
					( Origin gFrontEnd )
				)
				( attribute "TOLERANCE" "1%"
					( Origin gFrontEnd )
				)
				( attribute "VALUE" "100.0"
					( Origin gFrontEnd )
				)
				( attribute "VER" "2"
					( Origin gFrontEnd )
				)
				( attribute "WATTAGE" "1/16W"
					( Origin gFrontEnd )
				)
				( attribute "XY" "(-1200,4425)"
					( Origin gFrontEnd )
				)
				( attribute "CHIPS_PART_NAME" "RES"
					( Origin gPackager )
				)
				( attribute "CDS_PART_NAME" "RES_0402-100.0,1%,1/16W,CHIP,GA"
					( Origin gPackager )
				)
				( objectStatus "R1L39" )
				( pin "a"
					( attribute "PN" "1"
						( Origin gPackager )
					)
					( objectStatus "R1L39.1" )
				)
				( pin "b"
					( attribute "PN" "2"
						( Origin gPackager )
					)
					( objectStatus "R1L39.2" )
				)
			)
			( gate "@baseboard_fab2_lib.baseboard_fab2(sch_1):page112_i77"
				( attribute "CDS_LIB" "mstr_discrete"
					( Origin gPackager )
				)
				( attribute "CDS_LOCATION" "R1L41"
					( Origin gPackager )
				)
				( attribute "CDS_SEC" "1"
					( Origin gPackager )
				)
				( attribute "LOCATION" "R1L41"
					( Origin gFrontEnd )
				)
				( attribute "MATERIAL" "CHIP"
					( Origin gFrontEnd )
				)
				( attribute "PACK_TYPE" "0402"
					( Origin gFrontEnd )
				)
				( attribute "PART_NUMBER" "G21796-017"
					( Origin gFrontEnd )
				)
				( attribute "PHYS_PAGE" "112"
					( Origin gFrontEnd )
				)
				( attribute "ROOM" "DEBUG"
					( Origin gFrontEnd )
				)
				( attribute "ROT" "0"
					( Origin gFrontEnd )
				)
				( attribute "SEC" "1"
					( Origin gFrontEnd )
				)
				( attribute "SEC_TYPE" "0402"
					( Origin gFrontEnd )
				)
				( attribute "TOLERANCE" "1%"
					( Origin gFrontEnd )
				)
				( attribute "VALUE" "100.0"
					( Origin gFrontEnd )
				)
				( attribute "VER" "2"
					( Origin gFrontEnd )
				)
				( attribute "WATTAGE" "1/16W"
					( Origin gFrontEnd )
				)
				( attribute "XY" "(-1575,4425)"
					( Origin gFrontEnd )
				)
				( attribute "CHIPS_PART_NAME" "RES"
					( Origin gPackager )
				)
				( attribute "CDS_PART_NAME" "RES_0402-100.0,1%,1/16W,CHIP,GA"
					( Origin gPackager )
				)
				( objectStatus "R1L41" )
				( pin "a"
					( attribute "PN" "1"
						( Origin gPackager )
					)
					( objectStatus "R1L41.1" )
				)
				( pin "b"
					( attribute "PN" "2"
						( Origin gPackager )
					)
					( objectStatus "R1L41.2" )
				)
			)
			( gate "@baseboard_fab2_lib.baseboard_fab2(sch_1):page112_i78"
				( attribute "CDS_LIB" "mstr_discrete"
					( Origin gPackager )
				)
				( attribute "CDS_LOCATION" "R9A11"
					( Origin gPackager )
				)
				( attribute "CDS_SEC" "1"
					( Origin gPackager )
				)
				( attribute "LOCATION" "R9A11"
					( Origin gFrontEnd )
				)
				( attribute "MATERIAL" "CHIP"
					( Origin gFrontEnd )
				)
				( attribute "PACK_TYPE" "0402"
					( Origin gFrontEnd )
				)
				( attribute "PART_NUMBER" "G21796-009"
					( Origin gFrontEnd )
				)
				( attribute "PHYS_PAGE" "112"
					( Origin gFrontEnd )
				)
				( attribute "ROOM" "DEBUG"
					( Origin gFrontEnd )
				)
				( attribute "ROT" "0"
					( Origin gFrontEnd )
				)
				( attribute "SEC" "1"
					( Origin gFrontEnd )
				)
				( attribute "SEC_TYPE" "0402"
					( Origin gFrontEnd )
				)
				( attribute "TOLERANCE" "1%"
					( Origin gFrontEnd )
				)
				( attribute "VALUE" "150.0"
					( Origin gFrontEnd )
				)
				( attribute "VER" "2"
					( Origin gFrontEnd )
				)
				( attribute "WATTAGE" "1/16W"
					( Origin gFrontEnd )
				)
				( attribute "XY" "(-1950,4425)"
					( Origin gFrontEnd )
				)
				( attribute "CHIPS_PART_NAME" "RES"
					( Origin gPackager )
				)
				( attribute "CDS_PART_NAME" "RES_0402-150.0,1%,1/16W,CHIP,GA"
					( Origin gPackager )
				)
				( objectStatus "R9A11" )
				( pin "a"
					( attribute "PN" "1"
						( Origin gPackager )
					)
					( objectStatus "R9A11.1" )
				)
				( pin "b"
					( attribute "PN" "2"
						( Origin gPackager )
					)
					( objectStatus "R9A11.2" )
				)
			)
			( gate "@baseboard_fab2_lib.baseboard_fab2(sch_1):page112_i79"
				( attribute "CDS_LIB" "mstr_discrete"
					( Origin gPackager )
				)
				( attribute "CDS_LOCATION" "R8A13"
					( Origin gPackager )
				)
				( attribute "CDS_SEC" "1"
					( Origin gPackager )
				)
				( attribute "LOCATION" "R8A13"
					( Origin gFrontEnd )
				)
				( attribute "MATERIAL" "CHIP"
					( Origin gFrontEnd )
				)
				( attribute "PACK_TYPE" "0402"
					( Origin gFrontEnd )
				)
				( attribute "PART_NUMBER" "G21796-009"
					( Origin gFrontEnd )
				)
				( attribute "PHYS_PAGE" "112"
					( Origin gFrontEnd )
				)
				( attribute "ROOM" "DEBUG"
					( Origin gFrontEnd )
				)
				( attribute "ROT" "0"
					( Origin gFrontEnd )
				)
				( attribute "SEC" "1"
					( Origin gFrontEnd )
				)
				( attribute "SEC_TYPE" "0402"
					( Origin gFrontEnd )
				)
				( attribute "TOLERANCE" "1%"
					( Origin gFrontEnd )
				)
				( attribute "VALUE" "150.0"
					( Origin gFrontEnd )
				)
				( attribute "VER" "2"
					( Origin gFrontEnd )
				)
				( attribute "WATTAGE" "1/16W"
					( Origin gFrontEnd )
				)
				( attribute "XY" "(-2325,4425)"
					( Origin gFrontEnd )
				)
				( attribute "CHIPS_PART_NAME" "RES"
					( Origin gPackager )
				)
				( attribute "CDS_PART_NAME" "RES_0402-150.0,1%,1/16W,CHIP,GA"
					( Origin gPackager )
				)
				( objectStatus "R8A13" )
				( pin "a"
					( attribute "PN" "1"
						( Origin gPackager )
					)
					( objectStatus "R8A13.1" )
				)
				( pin "b"
					( attribute "PN" "2"
						( Origin gPackager )
					)
					( objectStatus "R8A13.2" )
				)
			)
			( gate "@baseboard_fab2_lib.baseboard_fab2(sch_1):page112_i80"
				( attribute "CDS_LIB" "mstr_discrete"
					( Origin gPackager )
				)
				( attribute "CDS_LOCATION" "R8A14"
					( Origin gPackager )
				)
				( attribute "CDS_SEC" "1"
					( Origin gPackager )
				)
				( attribute "LOCATION" "R8A14"
					( Origin gFrontEnd )
				)
				( attribute "MATERIAL" "CHIP"
					( Origin gFrontEnd )
				)
				( attribute "PACK_TYPE" "0402"
					( Origin gFrontEnd )
				)
				( attribute "PART_NUMBER" "G21796-009"
					( Origin gFrontEnd )
				)
				( attribute "PHYS_PAGE" "112"
					( Origin gFrontEnd )
				)
				( attribute "ROOM" "DEBUG"
					( Origin gFrontEnd )
				)
				( attribute "ROT" "0"
					( Origin gFrontEnd )
				)
				( attribute "SEC" "1"
					( Origin gFrontEnd )
				)
				( attribute "SEC_TYPE" "0402"
					( Origin gFrontEnd )
				)
				( attribute "TOLERANCE" "1%"
					( Origin gFrontEnd )
				)
				( attribute "VALUE" "150.0"
					( Origin gFrontEnd )
				)
				( attribute "VER" "2"
					( Origin gFrontEnd )
				)
				( attribute "WATTAGE" "1/16W"
					( Origin gFrontEnd )
				)
				( attribute "XY" "(-2700,4425)"
					( Origin gFrontEnd )
				)
				( attribute "CHIPS_PART_NAME" "RES"
					( Origin gPackager )
				)
				( attribute "CDS_PART_NAME" "RES_0402-150.0,1%,1/16W,CHIP,GA"
					( Origin gPackager )
				)
				( objectStatus "R8A14" )
				( pin "a"
					( attribute "PN" "1"
						( Origin gPackager )
					)
					( objectStatus "R8A14.1" )
				)
				( pin "b"
					( attribute "PN" "2"
						( Origin gPackager )
					)
					( objectStatus "R8A14.2" )
				)
			)
			( gate "@baseboard_fab2_lib.baseboard_fab2(sch_1):page112_i85"
				( attribute "BOM_COST" "DEBUG"
					( Origin gFrontEnd )
				)
				( attribute "CDS_LIB" "mstr_discrete"
					( Origin gPackager )
				)
				( attribute "CDS_LOCATION" "R3M10"
					( Origin gPackager )
				)
				( attribute "CDS_SEC" "1"
					( Origin gPackager )
				)
				( attribute "LOCATION" "R3M10"
					( Origin gFrontEnd )
				)
				( attribute "MATERIAL" "CHIP"
					( Origin gFrontEnd )
				)
				( attribute "PACK_TYPE" "0402"
					( Origin gFrontEnd )
				)
				( attribute "PART_NUMBER" "G21796-026"
					( Origin gFrontEnd )
				)
				( attribute "PHYS_PAGE" "112"
					( Origin gFrontEnd )
				)
				( attribute "ROOM" "DEBUG"
					( Origin gFrontEnd )
				)
				( attribute "ROT" "0"
					( Origin gFrontEnd )
				)
				( attribute "SEC" "1"
					( Origin gFrontEnd )
				)
				( attribute "SEC_TYPE" "0402"
					( Origin gFrontEnd )
				)
				( attribute "TOLERANCE" "1%"
					( Origin gFrontEnd )
				)
				( attribute "VALUE" "1.00K"
					( Origin gFrontEnd )
				)
				( attribute "VER" "2"
					( Origin gFrontEnd )
				)
				( attribute "WATTAGE" "1/16W"
					( Origin gFrontEnd )
				)
				( attribute "XY" "(-1950,3600)"
					( Origin gFrontEnd )
				)
				( attribute "CHIPS_PART_NAME" "RES"
					( Origin gPackager )
				)
				( attribute "CDS_PART_NAME" "RES_0402-1.00K,1%,1/16W,CHIP,GA"
					( Origin gPackager )
				)
				( objectStatus "R3M10" )
				( pin "a"
					( attribute "PN" "1"
						( Origin gPackager )
					)
					( objectStatus "R3M10.1" )
				)
				( pin "b"
					( attribute "PN" "2"
						( Origin gPackager )
					)
					( objectStatus "R3M10.2" )
				)
			)
			( gate "@baseboard_fab2_lib.baseboard_fab2(sch_1):page112_i94"
				( attribute "BOM_COST" "DEBUG"
					( Origin gFrontEnd )
				)
				( attribute "CDS_LIB" "mstr_discrete"
					( Origin gPackager )
				)
				( attribute "CDS_LOCATION" "R8B2"
					( Origin gPackager )
				)
				( attribute "CDS_SEC" "1"
					( Origin gPackager )
				)
				( attribute "LOCATION" "R8B2"
					( Origin gFrontEnd )
				)
				( attribute "MATERIAL" "CHIP"
					( Origin gFrontEnd )
				)
				( attribute "PACK_TYPE" "0402"
					( Origin gFrontEnd )
				)
				( attribute "PART_NUMBER" "G21796-026"
					( Origin gFrontEnd )
				)
				( attribute "PHYS_PAGE" "112"
					( Origin gFrontEnd )
				)
				( attribute "ROOM" "DEBUG"
					( Origin gFrontEnd )
				)
				( attribute "ROT" "0"
					( Origin gFrontEnd )
				)
				( attribute "SEC" "1"
					( Origin gFrontEnd )
				)
				( attribute "SEC_TYPE" "0402"
					( Origin gFrontEnd )
				)
				( attribute "TOLERANCE" "1%"
					( Origin gFrontEnd )
				)
				( attribute "VALUE" "1.00K"
					( Origin gFrontEnd )
				)
				( attribute "VER" "2"
					( Origin gFrontEnd )
				)
				( attribute "WATTAGE" "1/16W"
					( Origin gFrontEnd )
				)
				( attribute "XY" "(-2325,3600)"
					( Origin gFrontEnd )
				)
				( attribute "CHIPS_PART_NAME" "RES"
					( Origin gPackager )
				)
				( attribute "CDS_PART_NAME" "RES_0402-1.00K,1%,1/16W,CHIP,GA"
					( Origin gPackager )
				)
				( objectStatus "R8B2" )
				( pin "a"
					( attribute "PN" "1"
						( Origin gPackager )
					)
					( objectStatus "R8B2.1" )
				)
				( pin "b"
					( attribute "PN" "2"
						( Origin gPackager )
					)
					( objectStatus "R8B2.2" )
				)
			)
			( gate "@baseboard_fab2_lib.baseboard_fab2(sch_1):page112_i95"
				( attribute "BOM_COST" "DEBUG"
					( Origin gFrontEnd )
				)
				( attribute "CDS_LIB" "mstr_discrete"
					( Origin gPackager )
				)
				( attribute "CDS_LOCATION" "R8B1"
					( Origin gPackager )
				)
				( attribute "CDS_SEC" "1"
					( Origin gPackager )
				)
				( attribute "LOCATION" "R8B1"
					( Origin gFrontEnd )
				)
				( attribute "MATERIAL" "CHIP"
					( Origin gFrontEnd )
				)
				( attribute "PACK_TYPE" "0402"
					( Origin gFrontEnd )
				)
				( attribute "PART_NUMBER" "G21796-208"
					( Origin gFrontEnd )
				)
				( attribute "PHYS_PAGE" "112"
					( Origin gFrontEnd )
				)
				( attribute "ROOM" "DEBUG"
					( Origin gFrontEnd )
				)
				( attribute "ROT" "0"
					( Origin gFrontEnd )
				)
				( attribute "SEC" "1"
					( Origin gPackager )
				)
				( attribute "TOLERANCE" "1.0%"
					( Origin gFrontEnd )
				)
				( attribute "VALUE" "51.1"
					( Origin gFrontEnd )
				)
				( attribute "VER" "2"
					( Origin gFrontEnd )
				)
				( attribute "WATTAGE" "1/16W"
					( Origin gFrontEnd )
				)
				( attribute "XY" "(-2700,3600)"
					( Origin gFrontEnd )
				)
				( attribute "CHIPS_PART_NAME" "RES"
					( Origin gPackager )
				)
				( attribute "CDS_PART_NAME" "RES_0402-51.1,1.0%,1/16W,CHIP,A"
					( Origin gPackager )
				)
				( objectStatus "R8B1" )
				( pin "a"
					( attribute "PN" "1"
						( Origin gPackager )
					)
					( objectStatus "R8B1.1" )
				)
				( pin "b"
					( attribute "PN" "2"
						( Origin gPackager )
					)
					( objectStatus "R8B1.2" )
				)
			)
			( gate "@baseboard_fab2_lib.baseboard_fab2(sch_1):page112_i108"
				( attribute "CDS_LIB" "mstr_ttl"
					( Origin gPackager )
				)
				( attribute "CDS_LOCATION" "U1L1"
					( Origin gPackager )
				)
				( attribute "HAS_FIXED_SIZE" "4"
					( Origin gFrontEnd )
				)
				( attribute "LOCATION" "U1L1"
					( Origin gFrontEnd )
				)
				( attribute "MATERIAL" "IC"
					( Origin gFrontEnd )
				)
				( attribute "PACK_TYPE" "QFNLF"
					( Origin gFrontEnd )
				)
				( attribute "PART_NUMBER" "D18317-001"
					( Origin gFrontEnd )
				)
				( attribute "PHYS_PAGE" "112"
					( Origin gFrontEnd )
				)
				( attribute "ROOM" "DEBUG"
					( Origin gFrontEnd )
				)
				( attribute "ROT" "0"
					( Origin gFrontEnd )
				)
				( attribute "SIZE" "4"
					( Origin gFrontEnd )
				)
				( attribute "VALUE" "74CBTLV3126"
					( Origin gFrontEnd )
				)
				( attribute "VER" "3"
					( Origin gFrontEnd )
				)
				( attribute "XY" "(-2200,2425)"
					( Origin gFrontEnd )
				)
				( attribute "CHIPS_PART_NAME" "TTL3126"
					( Origin gPackager )
				)
				( attribute "CDS_PART_NAME" "TTL3126_QFNLF-74CBTLV3126,IC,DB"
					( Origin gPackager )
				)
				( objectStatus "U1L1" )
				( pin "a(0)"
					( attribute "CDS_SEC" "4"
						( Origin gPackager )
					)
					( attribute "PN" "12"
						( Origin gPackager )
					)
					( attribute "SEC" "4"
						( Origin gPackager )
					)
					( objectStatus "U1L1.12" )
				)
				( pin "a(1)"
					( attribute "CDS_SEC" "3"
						( Origin gPackager )
					)
					( attribute "PN" "9"
						( Origin gPackager )
					)
					( attribute "SEC" "3"
						( Origin gPackager )
					)
					( objectStatus "U1L1.9" )
				)
				( pin "a(2)"
					( attribute "CDS_SEC" "2"
						( Origin gPackager )
					)
					( attribute "PN" "5"
						( Origin gPackager )
					)
					( attribute "SEC" "2"
						( Origin gPackager )
					)
					( objectStatus "U1L1.5" )
				)
				( pin "a(3)"
					( attribute "CDS_SEC" "1"
						( Origin gPackager )
					)
					( attribute "PN" "2"
						( Origin gPackager )
					)
					( attribute "SEC" "1"
						( Origin gPackager )
					)
					( objectStatus "U1L1.2" )
				)
				( pin "b(0)"
					( attribute "CDS_SEC" "4"
						( Origin gPackager )
					)
					( attribute "PN" "11"
						( Origin gPackager )
					)
					( attribute "SEC" "4"
						( Origin gPackager )
					)
					( objectStatus "U1L1.11" )
				)
				( pin "b(1)"
					( attribute "CDS_SEC" "3"
						( Origin gPackager )
					)
					( attribute "PN" "8"
						( Origin gPackager )
					)
					( attribute "SEC" "3"
						( Origin gPackager )
					)
					( objectStatus "U1L1.8" )
				)
				( pin "b(2)"
					( attribute "CDS_SEC" "2"
						( Origin gPackager )
					)
					( attribute "PN" "6"
						( Origin gPackager )
					)
					( attribute "SEC" "2"
						( Origin gPackager )
					)
					( objectStatus "U1L1.6" )
				)
				( pin "b(3)"
					( attribute "CDS_SEC" "1"
						( Origin gPackager )
					)
					( attribute "PN" "3"
						( Origin gPackager )
					)
					( attribute "SEC" "1"
						( Origin gPackager )
					)
					( objectStatus "U1L1.3" )
				)
				( pin "oe(0)"
					( attribute "CDS_SEC" "4"
						( Origin gPackager )
					)
					( attribute "PN" "13"
						( Origin gPackager )
					)
					( attribute "SEC" "4"
						( Origin gPackager )
					)
					( objectStatus "U1L1.13" )
				)
				( pin "oe(1)"
					( attribute "CDS_SEC" "3"
						( Origin gPackager )
					)
					( attribute "PN" "10"
						( Origin gPackager )
					)
					( attribute "SEC" "3"
						( Origin gPackager )
					)
					( objectStatus "U1L1.10" )
				)
				( pin "oe(2)"
					( attribute "CDS_SEC" "2"
						( Origin gPackager )
					)
					( attribute "PN" "4"
						( Origin gPackager )
					)
					( attribute "SEC" "2"
						( Origin gPackager )
					)
					( objectStatus "U1L1.4" )
				)
				( pin "oe(3)"
					( attribute "CDS_SEC" "1"
						( Origin gPackager )
					)
					( attribute "PN" "1"
						( Origin gPackager )
					)
					( attribute "SEC" "1"
						( Origin gPackager )
					)
					( objectStatus "U1L1.1" )
				)
			)
			( gate "@baseboard_fab2_lib.baseboard_fab2(sch_1):page112_i109"
				( attribute "CDS_LIB" "mstr_ttl"
					( Origin gPackager )
				)
				( attribute "CDS_LOCATION" "U1L5"
					( Origin gPackager )
				)
				( attribute "HAS_FIXED_SIZE" "4"
					( Origin gFrontEnd )
				)
				( attribute "LOCATION" "U1L5"
					( Origin gFrontEnd )
				)
				( attribute "MATERIAL" "IC"
					( Origin gFrontEnd )
				)
				( attribute "PACK_TYPE" "QFNLF"
					( Origin gFrontEnd )
				)
				( attribute "PART_NUMBER" "D18317-001"
					( Origin gFrontEnd )
				)
				( attribute "PHYS_PAGE" "112"
					( Origin gFrontEnd )
				)
				( attribute "ROOM" "DEBUG"
					( Origin gFrontEnd )
				)
				( attribute "ROT" "0"
					( Origin gFrontEnd )
				)
				( attribute "SIZE" "4"
					( Origin gFrontEnd )
				)
				( attribute "VALUE" "74CBTLV3126"
					( Origin gFrontEnd )
				)
				( attribute "VER" "3"
					( Origin gFrontEnd )
				)
				( attribute "XY" "(-2200,1200)"
					( Origin gFrontEnd )
				)
				( attribute "CHIPS_PART_NAME" "TTL3126"
					( Origin gPackager )
				)
				( attribute "CDS_PART_NAME" "TTL3126_QFNLF-74CBTLV3126,IC,DB"
					( Origin gPackager )
				)
				( objectStatus "U1L5" )
				( pin "a(0)"
					( attribute "CDS_SEC" "4"
						( Origin gPackager )
					)
					( attribute "PN" "12"
						( Origin gPackager )
					)
					( attribute "SEC" "4"
						( Origin gPackager )
					)
					( objectStatus "U1L5.12" )
				)
				( pin "a(1)"
					( attribute "CDS_SEC" "3"
						( Origin gPackager )
					)
					( attribute "PN" "9"
						( Origin gPackager )
					)
					( attribute "SEC" "3"
						( Origin gPackager )
					)
					( objectStatus "U1L5.9" )
				)
				( pin "a(2)"
					( attribute "CDS_SEC" "2"
						( Origin gPackager )
					)
					( attribute "PN" "5"
						( Origin gPackager )
					)
					( attribute "SEC" "2"
						( Origin gPackager )
					)
					( objectStatus "U1L5.5" )
				)
				( pin "a(3)"
					( attribute "CDS_SEC" "1"
						( Origin gPackager )
					)
					( attribute "PN" "2"
						( Origin gPackager )
					)
					( attribute "SEC" "1"
						( Origin gPackager )
					)
					( objectStatus "U1L5.2" )
				)
				( pin "b(0)"
					( attribute "CDS_SEC" "4"
						( Origin gPackager )
					)
					( attribute "PN" "11"
						( Origin gPackager )
					)
					( attribute "SEC" "4"
						( Origin gPackager )
					)
					( objectStatus "U1L5.11" )
				)
				( pin "b(1)"
					( attribute "CDS_SEC" "3"
						( Origin gPackager )
					)
					( attribute "PN" "8"
						( Origin gPackager )
					)
					( attribute "SEC" "3"
						( Origin gPackager )
					)
					( objectStatus "U1L5.8" )
				)
				( pin "b(2)"
					( attribute "CDS_SEC" "2"
						( Origin gPackager )
					)
					( attribute "PN" "6"
						( Origin gPackager )
					)
					( attribute "SEC" "2"
						( Origin gPackager )
					)
					( objectStatus "U1L5.6" )
				)
				( pin "b(3)"
					( attribute "CDS_SEC" "1"
						( Origin gPackager )
					)
					( attribute "PN" "3"
						( Origin gPackager )
					)
					( attribute "SEC" "1"
						( Origin gPackager )
					)
					( objectStatus "U1L5.3" )
				)
				( pin "oe(0)"
					( attribute "CDS_SEC" "4"
						( Origin gPackager )
					)
					( attribute "PN" "13"
						( Origin gPackager )
					)
					( attribute "SEC" "4"
						( Origin gPackager )
					)
					( objectStatus "U1L5.13" )
				)
				( pin "oe(1)"
					( attribute "CDS_SEC" "3"
						( Origin gPackager )
					)
					( attribute "PN" "10"
						( Origin gPackager )
					)
					( attribute "SEC" "3"
						( Origin gPackager )
					)
					( objectStatus "U1L5.10" )
				)
				( pin "oe(2)"
					( attribute "CDS_SEC" "2"
						( Origin gPackager )
					)
					( attribute "PN" "4"
						( Origin gPackager )
					)
					( attribute "SEC" "2"
						( Origin gPackager )
					)
					( objectStatus "U1L5.4" )
				)
				( pin "oe(3)"
					( attribute "CDS_SEC" "1"
						( Origin gPackager )
					)
					( attribute "PN" "1"
						( Origin gPackager )
					)
					( attribute "SEC" "1"
						( Origin gPackager )
					)
					( objectStatus "U1L5.1" )
				)
			)
			( gate "@baseboard_fab2_lib.baseboard_fab2(sch_1):page112_i120"
				( attribute "CDS_LIB" "mstr_discrete"
					( Origin gPackager )
				)
				( attribute "CDS_LOCATION" "R6T9"
					( Origin gPackager )
				)
				( attribute "CDS_SEC" "1"
					( Origin gPackager )
				)
				( attribute "LOCATION" "R6T9"
					( Origin gFrontEnd )
				)
				( attribute "MATERIAL" "CHIP"
					( Origin gFrontEnd )
				)
				( attribute "PACK_TYPE" "0402"
					( Origin gFrontEnd )
				)
				( attribute "PART_NUMBER" "G21796-017"
					( Origin gFrontEnd )
				)
				( attribute "PHYS_PAGE" "112"
					( Origin gFrontEnd )
				)
				( attribute "ROOM" "DEBUG"
					( Origin gFrontEnd )
				)
				( attribute "ROT" "0"
					( Origin gFrontEnd )
				)
				( attribute "SEC" "1"
					( Origin gFrontEnd )
				)
				( attribute "SEC_TYPE" "0402"
					( Origin gFrontEnd )
				)
				( attribute "TOLERANCE" "1%"
					( Origin gFrontEnd )
				)
				( attribute "VALUE" "100.0"
					( Origin gFrontEnd )
				)
				( attribute "VER" "2"
					( Origin gFrontEnd )
				)
				( attribute "WATTAGE" "1/16W"
					( Origin gFrontEnd )
				)
				( attribute "XY" "(3500,2400)"
					( Origin gFrontEnd )
				)
				( attribute "CHIPS_PART_NAME" "RES"
					( Origin gPackager )
				)
				( attribute "CDS_PART_NAME" "RES_0402-100.0,1%,1/16W,CHIP,GA"
					( Origin gPackager )
				)
				( objectStatus "R6T9" )
				( pin "a"
					( attribute "PN" "1"
						( Origin gPackager )
					)
					( objectStatus "R6T9.1" )
				)
				( pin "b"
					( attribute "PN" "2"
						( Origin gPackager )
					)
					( objectStatus "R6T9.2" )
				)
			)
			( gate "@baseboard_fab2_lib.baseboard_fab2(sch_1):page112_i121"
				( attribute "CDS_LIB" "mstr_discrete"
					( Origin gPackager )
				)
				( attribute "CDS_LOCATION" "R6T8"
					( Origin gPackager )
				)
				( attribute "CDS_SEC" "1"
					( Origin gPackager )
				)
				( attribute "LOCATION" "R6T8"
					( Origin gFrontEnd )
				)
				( attribute "MATERIAL" "CHIP"
					( Origin gFrontEnd )
				)
				( attribute "PACK_TYPE" "0402"
					( Origin gFrontEnd )
				)
				( attribute "PART_NUMBER" "G21796-017"
					( Origin gFrontEnd )
				)
				( attribute "PHYS_PAGE" "112"
					( Origin gFrontEnd )
				)
				( attribute "ROOM" "DEBUG"
					( Origin gFrontEnd )
				)
				( attribute "ROT" "0"
					( Origin gFrontEnd )
				)
				( attribute "SEC" "1"
					( Origin gFrontEnd )
				)
				( attribute "SEC_TYPE" "0402"
					( Origin gFrontEnd )
				)
				( attribute "TOLERANCE" "1%"
					( Origin gFrontEnd )
				)
				( attribute "VALUE" "100.0"
					( Origin gFrontEnd )
				)
				( attribute "VER" "2"
					( Origin gFrontEnd )
				)
				( attribute "WATTAGE" "1/16W"
					( Origin gFrontEnd )
				)
				( attribute "XY" "(3175,2400)"
					( Origin gFrontEnd )
				)
				( attribute "CHIPS_PART_NAME" "RES"
					( Origin gPackager )
				)
				( attribute "CDS_PART_NAME" "RES_0402-100.0,1%,1/16W,CHIP,GA"
					( Origin gPackager )
				)
				( objectStatus "R6T8" )
				( pin "a"
					( attribute "PN" "1"
						( Origin gPackager )
					)
					( objectStatus "R6T8.1" )
				)
				( pin "b"
					( attribute "PN" "2"
						( Origin gPackager )
					)
					( objectStatus "R6T8.2" )
				)
			)
			( gate "@baseboard_fab2_lib.baseboard_fab2(sch_1):page112_i127"
				( attribute "BOM_COST" "DEBUG"
					( Origin gFrontEnd )
				)
				( attribute "CDS_LIB" "mstr_ttl"
					( Origin gPackager )
				)
				( attribute "CDS_LOCATION" "U1M4"
					( Origin gPackager )
				)
				( attribute "CDS_SEC" "1"
					( Origin gPackager )
				)
				( attribute "LOCATION" "U1M4"
					( Origin gFrontEnd )
				)
				( attribute "MATERIAL" "IC"
					( Origin gFrontEnd )
				)
				( attribute "PACK_TYPE" "SMLF"
					( Origin gFrontEnd )
				)
				( attribute "PART_NUMBER" "C88177-001"
					( Origin gFrontEnd )
				)
				( attribute "PHYS_PAGE" "112"
					( Origin gFrontEnd )
				)
				( attribute "ROOM" "DEBUG"
					( Origin gFrontEnd )
				)
				( attribute "ROT" "0"
					( Origin gFrontEnd )
				)
				( attribute "SEC" "1"
					( Origin gFrontEnd )
				)
				( attribute "SEC_TYPE" "SMLF"
					( Origin gFrontEnd )
				)
				( attribute "VER" "1"
					( Origin gFrontEnd )
				)
				( attribute "XY" "(3075,3425)"
					( Origin gFrontEnd )
				)
				( attribute "CHIPS_PART_NAME" "74CBTLV1G125"
					( Origin gPackager )
				)
				( attribute "CDS_PART_NAME" "74CBTLV1G125_SMLF-IC,C88177-00A"
					( Origin gPackager )
				)
				( objectStatus "U1M4" )
				( pin "a"
					( attribute "PN" "2"
						( Origin gPackager )
					)
					( objectStatus "U1M4.2" )
				)
				( pin "b"
					( attribute "PN" "4"
						( Origin gPackager )
					)
					( objectStatus "U1M4.4" )
				)
				( pin "oe_n"
					( attribute "PN" "1"
						( Origin gPackager )
					)
					( objectStatus "U1M4.1" )
				)
			)
			( gate "@baseboard_fab2_lib.baseboard_fab2(sch_1):page112_i131"
				( attribute "BOM_COST" "DEBUG"
					( Origin gFrontEnd )
				)
				( attribute "CDS_LIB" "dev_discrete"
					( Origin gPackager )
				)
				( attribute "CDS_LOCATION" "C1M30"
					( Origin gPackager )
				)
				( attribute "CDS_SEC" "1"
					( Origin gPackager )
				)
				( attribute "LOCATION" "C1M30"
					( Origin gFrontEnd )
				)
				( attribute "MATERIAL" "X7R"
					( Origin gFrontEnd )
				)
				( attribute "PACK_TYPE" "0402V"
					( Origin gFrontEnd )
				)
				( attribute "PART_NUMBER" "A36096-045"
					( Origin gFrontEnd )
				)
				( attribute "PHYS_PAGE" "112"
					( Origin gFrontEnd )
				)
				( attribute "ROOM" "DEBUG"
					( Origin gFrontEnd )
				)
				( attribute "ROT" "2"
					( Origin gFrontEnd )
				)
				( attribute "SEC" "1"
					( Origin gFrontEnd )
				)
				( attribute "SEC_TYPE" "0402V"
					( Origin gFrontEnd )
				)
				( attribute "TOLERANCE" "10%"
					( Origin gFrontEnd )
				)
				( attribute "VALUE" "0.01UF"
					( Origin gFrontEnd )
				)
				( attribute "VER" "1"
					( Origin gFrontEnd )
				)
				( attribute "VOLTAGE" "25V"
					( Units "uVoltage" "V" 1.000000)
					( Origin gFrontEnd )
				)
				( attribute "XY" "(3550,3725)"
					( Origin gFrontEnd )
				)
				( attribute "CHIPS_PART_NAME" "CAP_A"
					( Origin gPackager )
				)
				( attribute "CDS_PART_NAME" "CAP_A_0402V-0.01UF,25V,10%,X7RA"
					( Origin gPackager )
				)
				( objectStatus "C1M30" )
				( pin "a"
					( attribute "PN" "1"
						( Origin gPackager )
					)
					( objectStatus "C1M30.1" )
				)
				( pin "b"
					( attribute "PN" "2"
						( Origin gPackager )
					)
					( objectStatus "C1M30.2" )
				)
			)
			( gate "@baseboard_fab2_lib.baseboard_fab2(sch_1):page112_i136"
				( attribute "CDS_LIB" "mstr_discrete"
					( Origin gPackager )
				)
				( attribute "CDS_LOCATION" "C1L1"
					( Origin gPackager )
				)
				( attribute "CDS_SEC" "1"
					( Origin gPackager )
				)
				( attribute "LOCATION" "C1L1"
					( Origin gFrontEnd )
				)
				( attribute "MATERIAL" "X6S"
					( Origin gFrontEnd )
				)
				( attribute "PACK_TYPE" "0402"
					( Origin gFrontEnd )
				)
				( attribute "PART_NUMBER" "D97712-011"
					( Origin gFrontEnd )
				)
				( attribute "PHYS_PAGE" "112"
					( Origin gFrontEnd )
				)
				( attribute "ROOM" "DEBUG"
					( Origin gFrontEnd )
				)
				( attribute "ROT" "0"
					( Origin gFrontEnd )
				)
				( attribute "SEC" "1"
					( Origin gFrontEnd )
				)
				( attribute "SEC_TYPE" "0402"
					( Origin gFrontEnd )
				)
				( attribute "TOLERANCE" "10%"
					( Origin gFrontEnd )
				)
				( attribute "VALUE" "1.0UF"
					( Origin gFrontEnd )
				)
				( attribute "VER" "1"
					( Origin gFrontEnd )
				)
				( attribute "VOLTAGE" "16V"
					( Units "uVoltage" "V" 1.000000)
					( Origin gFrontEnd )
				)
				( attribute "XY" "(-1125,1850)"
					( Origin gFrontEnd )
				)
				( attribute "CHIPS_PART_NAME" "CAP"
					( Origin gPackager )
				)
				( attribute "CDS_PART_NAME" "CAP_0402-1.0UF,16V,10%,X6S,D97A"
					( Origin gPackager )
				)
				( objectStatus "C1L1" )
				( pin "a"
					( attribute "PN" "1"
						( Origin gPackager )
					)
					( objectStatus "C1L1.1" )
				)
				( pin "b"
					( attribute "PN" "2"
						( Origin gPackager )
					)
					( objectStatus "C1L1.2" )
				)
			)
			( gate "@baseboard_fab2_lib.baseboard_fab2(sch_1):page112_i140"
				( attribute "CDS_LIB" "mstr_discrete"
					( Origin gPackager )
				)
				( attribute "CDS_LOCATION" "C1L19"
					( Origin gPackager )
				)
				( attribute "CDS_SEC" "1"
					( Origin gPackager )
				)
				( attribute "LOCATION" "C1L19"
					( Origin gFrontEnd )
				)
				( attribute "MATERIAL" "X6S"
					( Origin gFrontEnd )
				)
				( attribute "PACK_TYPE" "0402"
					( Origin gFrontEnd )
				)
				( attribute "PART_NUMBER" "D97712-011"
					( Origin gFrontEnd )
				)
				( attribute "PHYS_PAGE" "112"
					( Origin gFrontEnd )
				)
				( attribute "ROOM" "DEBUG"
					( Origin gFrontEnd )
				)
				( attribute "ROT" "0"
					( Origin gFrontEnd )
				)
				( attribute "SEC" "1"
					( Origin gFrontEnd )
				)
				( attribute "SEC_TYPE" "0402"
					( Origin gFrontEnd )
				)
				( attribute "TOLERANCE" "10%"
					( Origin gFrontEnd )
				)
				( attribute "VALUE" "1.0UF"
					( Origin gFrontEnd )
				)
				( attribute "VER" "1"
					( Origin gFrontEnd )
				)
				( attribute "VOLTAGE" "16V"
					( Units "uVoltage" "V" 1.000000)
					( Origin gFrontEnd )
				)
				( attribute "XY" "(-1350,625)"
					( Origin gFrontEnd )
				)
				( attribute "CHIPS_PART_NAME" "CAP"
					( Origin gPackager )
				)
				( attribute "CDS_PART_NAME" "CAP_0402-1.0UF,16V,10%,X6S,D97A"
					( Origin gPackager )
				)
				( objectStatus "C1L19" )
				( pin "a"
					( attribute "PN" "1"
						( Origin gPackager )
					)
					( objectStatus "C1L19.1" )
				)
				( pin "b"
					( attribute "PN" "2"
						( Origin gPackager )
					)
					( objectStatus "C1L19.2" )
				)
			)
			( gate "@baseboard_fab2_lib.baseboard_fab2(sch_1):page113_i107"
				( attribute "BOM_COST" "DEBUG"
					( Origin gFrontEnd )
				)
				( attribute "CDS_LIB" "mstr_analog"
					( Origin gPackager )
				)
				( attribute "CDS_LOCATION" "U1M2"
					( Origin gPackager )
				)
				( attribute "CDS_SEC" "1"
					( Origin gPackager )
				)
				( attribute "LOCATION" "U1M2"
					( Origin gFrontEnd )
				)
				( attribute "MATERIAL" "IC"
					( Origin gFrontEnd )
				)
				( attribute "PACK_TYPE" "SMLF"
					( Origin gFrontEnd )
				)
				( attribute "PART_NUMBER" "C99406-001"
					( Origin gFrontEnd )
				)
				( attribute "PHYS_PAGE" "113"
					( Origin gFrontEnd )
				)
				( attribute "ROOM" "DEBUG"
					( Origin gFrontEnd )
				)
				( attribute "ROT" "2"
					( Origin gFrontEnd )
				)
				( attribute "SEC" "1"
					( Origin gFrontEnd )
				)
				( attribute "SEC_TYPE" "SMLF"
					( Origin gFrontEnd )
				)
				( attribute "VER" "1"
					( Origin gFrontEnd )
				)
				( attribute "XY" "(-2075,3525)"
					( Origin gFrontEnd )
				)
				( attribute "CHIPS_PART_NAME" "NC7SB3157"
					( Origin gPackager )
				)
				( attribute "CDS_PART_NAME" "NC7SB3157_SMLF-IC,C99406-001"
					( Origin gPackager )
				)
				( objectStatus "U1M2" )
				( pin "a"
					( attribute "PN" "4"
						( Origin gPackager )
					)
					( objectStatus "U1M2.4" )
				)
				( pin "b0"
					( attribute "PN" "3"
						( Origin gPackager )
					)
					( objectStatus "U1M2.3" )
				)
				( pin "b1"
					( attribute "PN" "1"
						( Origin gPackager )
					)
					( objectStatus "U1M2.1" )
				)
				( pin "gnd"
					( attribute "PN" "2"
						( Origin gPackager )
					)
					( objectStatus "U1M2.2" )
				)
				( pin "s"
					( attribute "PN" "6"
						( Origin gPackager )
					)
					( objectStatus "U1M2.6" )
				)
				( pin "vcc"
					( attribute "PN" "5"
						( Origin gPackager )
					)
					( objectStatus "U1M2.5" )
				)
			)
			( gate "@baseboard_fab2_lib.baseboard_fab2(sch_1):page113_i116"
				( attribute "BOM_COST" "DEBUG"
					( Origin gFrontEnd )
				)
				( attribute "CDS_LIB" "dev_discrete"
					( Origin gPackager )
				)
				( attribute "CDS_LOCATION" "C1M31"
					( Origin gPackager )
				)
				( attribute "CDS_SEC" "1"
					( Origin gPackager )
				)
				( attribute "LOCATION" "C1M31"
					( Origin gFrontEnd )
				)
				( attribute "MATERIAL" "X7R"
					( Origin gFrontEnd )
				)
				( attribute "PACK_TYPE" "0402V"
					( Origin gFrontEnd )
				)
				( attribute "PART_NUMBER" "A36096-045"
					( Origin gFrontEnd )
				)
				( attribute "PHYS_PAGE" "113"
					( Origin gFrontEnd )
				)
				( attribute "ROOM" "DEBUG"
					( Origin gFrontEnd )
				)
				( attribute "ROT" "2"
					( Origin gFrontEnd )
				)
				( attribute "SEC" "1"
					( Origin gFrontEnd )
				)
				( attribute "SEC_TYPE" "0402V"
					( Origin gFrontEnd )
				)
				( attribute "TOLERANCE" "10%"
					( Origin gFrontEnd )
				)
				( attribute "VALUE" "0.01UF"
					( Origin gFrontEnd )
				)
				( attribute "VER" "1"
					( Origin gFrontEnd )
				)
				( attribute "VOLTAGE" "25V"
					( Units "uVoltage" "V" 1.000000)
					( Origin gFrontEnd )
				)
				( attribute "XY" "(-1550,3025)"
					( Origin gFrontEnd )
				)
				( attribute "CHIPS_PART_NAME" "CAP_A"
					( Origin gPackager )
				)
				( attribute "CDS_PART_NAME" "CAP_A_0402V-0.01UF,25V,10%,X7RA"
					( Origin gPackager )
				)
				( objectStatus "C1M31" )
				( pin "a"
					( attribute "PN" "1"
						( Origin gPackager )
					)
					( objectStatus "C1M31.1" )
				)
				( pin "b"
					( attribute "PN" "2"
						( Origin gPackager )
					)
					( objectStatus "C1M31.2" )
				)
			)
			( gate "@baseboard_fab2_lib.baseboard_fab2(sch_1):page113_i117"
				( attribute "BOM_COST" "DEBUG"
					( Origin gFrontEnd )
				)
				( attribute "CDS_LIB" "dev_discrete"
					( Origin gPackager )
				)
				( attribute "CDS_LOCATION" "C1M32"
					( Origin gPackager )
				)
				( attribute "CDS_SEC" "1"
					( Origin gPackager )
				)
				( attribute "LOCATION" "C1M32"
					( Origin gFrontEnd )
				)
				( attribute "MATERIAL" "X6S"
					( Origin gFrontEnd )
				)
				( attribute "PACK_TYPE" "0402V"
					( Origin gFrontEnd )
				)
				( attribute "PART_NUMBER" "D97712-004"
					( Origin gFrontEnd )
				)
				( attribute "PHYS_PAGE" "113"
					( Origin gFrontEnd )
				)
				( attribute "ROOM" "DEBUG"
					( Origin gFrontEnd )
				)
				( attribute "ROT" "2"
					( Origin gFrontEnd )
				)
				( attribute "SEC" "1"
					( Origin gFrontEnd )
				)
				( attribute "SEC_TYPE" "0402V"
					( Origin gFrontEnd )
				)
				( attribute "TOLERANCE" "10%"
					( Origin gFrontEnd )
				)
				( attribute "VALUE" "1.0UF"
					( Origin gFrontEnd )
				)
				( attribute "VER" "1"
					( Origin gFrontEnd )
				)
				( attribute "VOLTAGE" "6.3V"
					( Units "uVoltage" "V" 1.000000)
					( Origin gFrontEnd )
				)
				( attribute "XY" "(-1250,3025)"
					( Origin gFrontEnd )
				)
				( attribute "CHIPS_PART_NAME" "CAP_A"
					( Origin gPackager )
				)
				( attribute "CDS_PART_NAME" "CAP_A_0402V-1.0UF,6.3V,10%,X6SA"
					( Origin gPackager )
				)
				( objectStatus "C1M32" )
				( pin "a"
					( attribute "PN" "1"
						( Origin gPackager )
					)
					( objectStatus "C1M32.1" )
				)
				( pin "b"
					( attribute "PN" "2"
						( Origin gPackager )
					)
					( objectStatus "C1M32.2" )
				)
			)
			( gate "@baseboard_fab2_lib.baseboard_fab2(sch_1):page113_i119"
				( attribute "BOM_COST" "DEBUG"
					( Origin gFrontEnd )
				)
				( attribute "CDS_LIB" "dev_discrete"
					( Origin gPackager )
				)
				( attribute "CDS_LOCATION" "C1M28"
					( Origin gPackager )
				)
				( attribute "CDS_SEC" "1"
					( Origin gPackager )
				)
				( attribute "LOCATION" "C1M28"
					( Origin gFrontEnd )
				)
				( attribute "MATERIAL" "X7R"
					( Origin gFrontEnd )
				)
				( attribute "PACK_TYPE" "0402V"
					( Origin gFrontEnd )
				)
				( attribute "PART_NUMBER" "A36096-045"
					( Origin gFrontEnd )
				)
				( attribute "PHYS_PAGE" "113"
					( Origin gFrontEnd )
				)
				( attribute "ROOM" "DEBUG"
					( Origin gFrontEnd )
				)
				( attribute "ROT" "2"
					( Origin gFrontEnd )
				)
				( attribute "SEC" "1"
					( Origin gFrontEnd )
				)
				( attribute "SEC_TYPE" "0402V"
					( Origin gFrontEnd )
				)
				( attribute "TOLERANCE" "10%"
					( Origin gFrontEnd )
				)
				( attribute "VALUE" "0.01UF"
					( Origin gFrontEnd )
				)
				( attribute "VER" "1"
					( Origin gFrontEnd )
				)
				( attribute "VOLTAGE" "25V"
					( Units "uVoltage" "V" 1.000000)
					( Origin gFrontEnd )
				)
				( attribute "XY" "(-2250,1250)"
					( Origin gFrontEnd )
				)
				( attribute "CHIPS_PART_NAME" "CAP_A"
					( Origin gPackager )
				)
				( attribute "CDS_PART_NAME" "CAP_A_0402V-0.01UF,25V,10%,X7RA"
					( Origin gPackager )
				)
				( objectStatus "C1M28" )
				( pin "a"
					( attribute "PN" "1"
						( Origin gPackager )
					)
					( objectStatus "C1M28.1" )
				)
				( pin "b"
					( attribute "PN" "2"
						( Origin gPackager )
					)
					( objectStatus "C1M28.2" )
				)
			)
			( gate "@baseboard_fab2_lib.baseboard_fab2(sch_1):page113_i127"
				( attribute "BOM_COST" "DEBUG"
					( Origin gFrontEnd )
				)
				( attribute "CDS_LIB" "mstr_ttl"
					( Origin gPackager )
				)
				( attribute "CDS_LOCATION" "U1M6"
					( Origin gPackager )
				)
				( attribute "CDS_SEC" "1"
					( Origin gPackager )
				)
				( attribute "LOCATION" "U1M6"
					( Origin gFrontEnd )
				)
				( attribute "MATERIAL" "IC"
					( Origin gFrontEnd )
				)
				( attribute "PACK_TYPE" "SMLF"
					( Origin gFrontEnd )
				)
				( attribute "PART_NUMBER" "C88177-001"
					( Origin gFrontEnd )
				)
				( attribute "PHYS_PAGE" "113"
					( Origin gFrontEnd )
				)
				( attribute "ROOM" "DEBUG"
					( Origin gFrontEnd )
				)
				( attribute "ROT" "0"
					( Origin gFrontEnd )
				)
				( attribute "SEC" "1"
					( Origin gFrontEnd )
				)
				( attribute "SEC_TYPE" "SMLF"
					( Origin gFrontEnd )
				)
				( attribute "VER" "1"
					( Origin gFrontEnd )
				)
				( attribute "XY" "(-1500,850)"
					( Origin gFrontEnd )
				)
				( attribute "CHIPS_PART_NAME" "74CBTLV1G125"
					( Origin gPackager )
				)
				( attribute "CDS_PART_NAME" "74CBTLV1G125_SMLF-IC,C88177-00A"
					( Origin gPackager )
				)
				( objectStatus "U1M6" )
				( pin "a"
					( attribute "PN" "2"
						( Origin gPackager )
					)
					( objectStatus "U1M6.2" )
				)
				( pin "b"
					( attribute "PN" "4"
						( Origin gPackager )
					)
					( objectStatus "U1M6.4" )
				)
				( pin "oe_n"
					( attribute "PN" "1"
						( Origin gPackager )
					)
					( objectStatus "U1M6.1" )
				)
			)
			( gate "@baseboard_fab2_lib.baseboard_fab2(sch_1):page113_i134"
				( attribute "CDS_LIB" "mstr_discrete"
					( Origin gPackager )
				)
				( attribute "CDS_LOCATION" "R4R6"
					( Origin gPackager )
				)
				( attribute "CDS_SEC" "1"
					( Origin gPackager )
				)
				( attribute "LOCATION" "R4R6"
					( Origin gFrontEnd )
				)
				( attribute "MATERIAL" "CHIP"
					( Origin gFrontEnd )
				)
				( attribute "PACK_TYPE" "0402"
					( Origin gFrontEnd )
				)
				( attribute "PART_NUMBER" "G21796-047"
					( Origin gFrontEnd )
				)
				( attribute "PHYS_PAGE" "113"
					( Origin gFrontEnd )
				)
				( attribute "ROOM" "DEBUG"
					( Origin gFrontEnd )
				)
				( attribute "ROT" "2"
					( Origin gFrontEnd )
				)
				( attribute "SEC" "1"
					( Origin gFrontEnd )
				)
				( attribute "SEC_TYPE" "0402"
					( Origin gFrontEnd )
				)
				( attribute "TOLERANCE" "1%"
					( Origin gFrontEnd )
				)
				( attribute "VALUE" "49.9"
					( Origin gFrontEnd )
				)
				( attribute "VER" "2"
					( Origin gFrontEnd )
				)
				( attribute "WATTAGE" "1/16W"
					( Origin gFrontEnd )
				)
				( attribute "XY" "(2450,3200)"
					( Origin gFrontEnd )
				)
				( attribute "CHIPS_PART_NAME" "RES"
					( Origin gPackager )
				)
				( attribute "CDS_PART_NAME" "RES_0402-49.9,1%,1/16W,CHIP,G2A"
					( Origin gPackager )
				)
				( objectStatus "R4R6" )
				( pin "a"
					( attribute "PN" "1"
						( Origin gPackager )
					)
					( objectStatus "R4R6.1" )
				)
				( pin "b"
					( attribute "PN" "2"
						( Origin gPackager )
					)
					( objectStatus "R4R6.2" )
				)
			)
			( gate "@baseboard_fab2_lib.baseboard_fab2(sch_1):page113_i147"
				( attribute "CDS_LIB" "dev_discrete"
					( Origin gPackager )
				)
				( attribute "CDS_LOCATION" "C1M29"
					( Origin gPackager )
				)
				( attribute "CDS_SEC" "1"
					( Origin gPackager )
				)
				( attribute "LOCATION" "C1M29"
					( Origin gFrontEnd )
				)
				( attribute "MATERIAL" "X7R"
					( Origin gFrontEnd )
				)
				( attribute "PACK_TYPE" "0402V"
					( Origin gFrontEnd )
				)
				( attribute "PART_NUMBER" "A36096-030"
					( Origin gFrontEnd )
				)
				( attribute "PHYS_PAGE" "113"
					( Origin gFrontEnd )
				)
				( attribute "ROOM" "DEBUG"
					( Origin gFrontEnd )
				)
				( attribute "ROT" "0"
					( Origin gFrontEnd )
				)
				( attribute "SEC" "1"
					( Origin gPackager )
				)
				( attribute "TOLERANCE" "10%"
					( Origin gFrontEnd )
				)
				( attribute "VALUE" "0.1UF"
					( Origin gFrontEnd )
				)
				( attribute "VER" "1"
					( Origin gFrontEnd )
				)
				( attribute "VOLTAGE" "16V"
					( Units "uVoltage" "V" 1.000000)
					( Origin gFrontEnd )
				)
				( attribute "XY" "(-975,4650)"
					( Origin gFrontEnd )
				)
				( attribute "CHIPS_PART_NAME" "CAP_A"
					( Origin gPackager )
				)
				( attribute "CDS_PART_NAME" "CAP_A_0402V-0.1UF,16V,10%,X7R,A"
					( Origin gPackager )
				)
				( objectStatus "C1M29" )
				( pin "a"
					( attribute "PN" "1"
						( Origin gPackager )
					)
					( objectStatus "C1M29.1" )
				)
				( pin "b"
					( attribute "PN" "2"
						( Origin gPackager )
					)
					( objectStatus "C1M29.2" )
				)
			)
			( gate "@baseboard_fab2_lib.baseboard_fab2(sch_1):page113_i168"
				( attribute "CDS_LIB" "mstr_discrete"
					( Origin gPackager )
				)
				( attribute "CDS_LOCATION" "R9B14"
					( Origin gPackager )
				)
				( attribute "CDS_SEC" "1"
					( Origin gPackager )
				)
				( attribute "LOCATION" "R9B14"
					( Origin gFrontEnd )
				)
				( attribute "MATERIAL" "CHIP"
					( Origin gFrontEnd )
				)
				( attribute "PACK_TYPE" "0402"
					( Origin gFrontEnd )
				)
				( attribute "PART_NUMBER" "G21796-026"
					( Origin gFrontEnd )
				)
				( attribute "PHYS_PAGE" "113"
					( Origin gFrontEnd )
				)
				( attribute "ROOM" "DEBUG"
					( Origin gFrontEnd )
				)
				( attribute "ROT" "0"
					( Origin gFrontEnd )
				)
				( attribute "SEC" "1"
					( Origin gFrontEnd )
				)
				( attribute "SEC_TYPE" "0402"
					( Origin gFrontEnd )
				)
				( attribute "TOLERANCE" "1%"
					( Origin gFrontEnd )
				)
				( attribute "VALUE" "1.00K"
					( Origin gFrontEnd )
				)
				( attribute "VER" "1"
					( Origin gFrontEnd )
				)
				( attribute "WATTAGE" "1/16W"
					( Origin gFrontEnd )
				)
				( attribute "XY" "(-2600,4150)"
					( Origin gFrontEnd )
				)
				( attribute "CHIPS_PART_NAME" "RES"
					( Origin gPackager )
				)
				( attribute "CDS_PART_NAME" "RES_0402-1.00K,1%,1/16W,CHIP,GA"
					( Origin gPackager )
				)
				( objectStatus "R9B14" )
				( pin "a"
					( attribute "PN" "1"
						( Origin gPackager )
					)
					( objectStatus "R9B14.1" )
				)
				( pin "b"
					( attribute "PN" "2"
						( Origin gPackager )
					)
					( objectStatus "R9B14.2" )
				)
			)
			( gate "@baseboard_fab2_lib.baseboard_fab2(sch_1):page113_i175"
				( attribute "CDS_LIB" "mstr_sconn"
					( Origin gPackager )
				)
				( attribute "CDS_LOCATION" "J9B4"
					( Origin gPackager )
				)
				( attribute "CDS_SEC" "1"
					( Origin gPackager )
				)
				( attribute "LOCATION" "J9B4"
					( Origin gFrontEnd )
				)
				( attribute "MATERIAL" "CONN"
					( Origin gFrontEnd )
				)
				( attribute "PACK_TYPE" "SMLF"
					( Origin gFrontEnd )
				)
				( attribute "PART_NUMBER" "C12536-004"
					( Origin gFrontEnd )
				)
				( attribute "PHYS_PAGE" "113"
					( Origin gFrontEnd )
				)
				( attribute "ROOM" "DEBUG"
					( Origin gFrontEnd )
				)
				( attribute "ROT" "0"
					( Origin gFrontEnd )
				)
				( attribute "SEC" "1"
					( Origin gFrontEnd )
				)
				( attribute "SEC_TYPE" "SMLF"
					( Origin gFrontEnd )
				)
				( attribute "VER" "1"
					( Origin gFrontEnd )
				)
				( attribute "XY" "(-1375,4375)"
					( Origin gFrontEnd )
				)
				( attribute "CHIPS_PART_NAME" "SCONN10_C12536004"
					( Origin gPackager )
				)
				( attribute "CDS_PART_NAME" "SCONN10_C12536004_SMLF-CONN,C1A"
					( Origin gPackager )
				)
				( objectStatus "J9B4" )
				( pin "io1"
					( attribute "PN" "1"
						( Origin gPackager )
					)
					( objectStatus "J9B4.1" )
				)
				( pin "io2"
					( attribute "PN" "2"
						( Origin gPackager )
					)
					( objectStatus "J9B4.2" )
				)
				( pin "io3"
					( attribute "PN" "3"
						( Origin gPackager )
					)
					( objectStatus "J9B4.3" )
				)
				( pin "io4"
					( attribute "PN" "4"
						( Origin gPackager )
					)
					( objectStatus "J9B4.4" )
				)
				( pin "io5"
					( attribute "PN" "5"
						( Origin gPackager )
					)
					( objectStatus "J9B4.5" )
				)
				( pin "io6"
					( attribute "PN" "6"
						( Origin gPackager )
					)
					( objectStatus "J9B4.6" )
				)
				( pin "io7"
					( attribute "PN" "7"
						( Origin gPackager )
					)
					( objectStatus "J9B4.7" )
				)
				( pin "io8"
					( attribute "PN" "8"
						( Origin gPackager )
					)
					( objectStatus "J9B4.8" )
				)
				( pin "io9"
					( attribute "PN" "9"
						( Origin gPackager )
					)
					( objectStatus "J9B4.9" )
				)
				( pin "io10"
					( attribute "PN" "10"
						( Origin gPackager )
					)
					( objectStatus "J9B4.10" )
				)
			)
			( gate "@baseboard_fab2_lib.baseboard_fab2(sch_1):page113_i179"
				( attribute "CDS_LIB" "mstr_discrete"
					( Origin gPackager )
				)
				( attribute "CDS_LOCATION" "R9B9"
					( Origin gPackager )
				)
				( attribute "CDS_SEC" "1"
					( Origin gPackager )
				)
				( attribute "LOCATION" "R9B9"
					( Origin gFrontEnd )
				)
				( attribute "MATERIAL" "CHIP"
					( Origin gFrontEnd )
				)
				( attribute "PACK_TYPE" "0402"
					( Origin gFrontEnd )
				)
				( attribute "PART_NUMBER" "G21796-026"
					( Origin gFrontEnd )
				)
				( attribute "PHYS_PAGE" "113"
					( Origin gFrontEnd )
				)
				( attribute "ROT" "2"
					( Origin gFrontEnd )
				)
				( attribute "SEC" "1"
					( Origin gFrontEnd )
				)
				( attribute "SEC_TYPE" "0402"
					( Origin gFrontEnd )
				)
				( attribute "TOLERANCE" "1%"
					( Origin gFrontEnd )
				)
				( attribute "VALUE" "1.00K"
					( Origin gFrontEnd )
				)
				( attribute "VER" "2"
					( Origin gFrontEnd )
				)
				( attribute "WATTAGE" "1/16W"
					( Origin gFrontEnd )
				)
				( attribute "XY" "(2600,4150)"
					( Origin gFrontEnd )
				)
				( attribute "CHIPS_PART_NAME" "RES"
					( Origin gPackager )
				)
				( attribute "CDS_PART_NAME" "RES_0402-1.00K,1%,1/16W,CHIP,GA"
					( Origin gPackager )
				)
				( objectStatus "R9B9" )
				( pin "a"
					( attribute "PN" "1"
						( Origin gPackager )
					)
					( objectStatus "R9B9.1" )
				)
				( pin "b"
					( attribute "PN" "2"
						( Origin gPackager )
					)
					( objectStatus "R9B9.2" )
				)
			)
			( gate "@baseboard_fab2_lib.baseboard_fab2(sch_1):page113_i180"
				( attribute "BOM_COST" "DEBUG"
					( Origin gFrontEnd )
				)
				( attribute "CDS_LIB" "mstr_discrete"
					( Origin gPackager )
				)
				( attribute "CDS_LOCATION" "R9B10"
					( Origin gPackager )
				)
				( attribute "CDS_SEC" "1"
					( Origin gPackager )
				)
				( attribute "LOCATION" "R9B10"
					( Origin gFrontEnd )
				)
				( attribute "MATERIAL" "CHIP"
					( Origin gFrontEnd )
				)
				( attribute "PACK_TYPE" "0402"
					( Origin gFrontEnd )
				)
				( attribute "PART_NUMBER" "G21796-047"
					( Origin gFrontEnd )
				)
				( attribute "PHYS_PAGE" "113"
					( Origin gFrontEnd )
				)
				( attribute "ROOM" "DEBUG"
					( Origin gFrontEnd )
				)
				( attribute "ROT" "0"
					( Origin gFrontEnd )
				)
				( attribute "SEC" "1"
					( Origin gFrontEnd )
				)
				( attribute "SEC_TYPE" "0402"
					( Origin gFrontEnd )
				)
				( attribute "TOLERANCE" "1%"
					( Origin gFrontEnd )
				)
				( attribute "VALUE" "49.9"
					( Origin gFrontEnd )
				)
				( attribute "VER" "1"
					( Origin gFrontEnd )
				)
				( attribute "WATTAGE" "1/16W"
					( Origin gFrontEnd )
				)
				( attribute "XY" "(2800,4400)"
					( Origin gFrontEnd )
				)
				( attribute "CHIPS_PART_NAME" "RES"
					( Origin gPackager )
				)
				( attribute "CDS_PART_NAME" "RES_0402-49.9,1%,1/16W,CHIP,G2A"
					( Origin gPackager )
				)
				( objectStatus "R9B10" )
				( pin "a"
					( attribute "PN" "1"
						( Origin gPackager )
					)
					( objectStatus "R9B10.1" )
				)
				( pin "b"
					( attribute "PN" "2"
						( Origin gPackager )
					)
					( objectStatus "R9B10.2" )
				)
			)
			( gate "@baseboard_fab2_lib.baseboard_fab2(sch_1):page113_i185"
				( attribute "BOM_COST" "DEBUG"
					( Origin gFrontEnd )
				)
				( attribute "CDS_LIB" "mstr_ttl"
					( Origin gPackager )
				)
				( attribute "CDS_LOCATION" "U9A5"
					( Origin gPackager )
				)
				( attribute "CDS_SEC" "1"
					( Origin gPackager )
				)
				( attribute "LOCATION" "U9A5"
					( Origin gFrontEnd )
				)
				( attribute "MATERIAL" "IC"
					( Origin gFrontEnd )
				)
				( attribute "PACK_TYPE" "SMLF"
					( Origin gFrontEnd )
				)
				( attribute "PART_NUMBER" "C88177-001"
					( Origin gFrontEnd )
				)
				( attribute "PHYS_PAGE" "113"
					( Origin gFrontEnd )
				)
				( attribute "ROOM" "DEBUG"
					( Origin gFrontEnd )
				)
				( attribute "ROT" "0"
					( Origin gFrontEnd )
				)
				( attribute "SEC" "1"
					( Origin gFrontEnd )
				)
				( attribute "SEC_TYPE" "SMLF"
					( Origin gFrontEnd )
				)
				( attribute "VER" "1"
					( Origin gFrontEnd )
				)
				( attribute "XY" "(3575,4400)"
					( Origin gFrontEnd )
				)
				( attribute "CHIPS_PART_NAME" "74CBTLV1G125"
					( Origin gPackager )
				)
				( attribute "CDS_PART_NAME" "74CBTLV1G125_SMLF-IC,C88177-00A"
					( Origin gPackager )
				)
				( objectStatus "U9A5" )
				( pin "a"
					( attribute "PN" "2"
						( Origin gPackager )
					)
					( objectStatus "U9A5.2" )
				)
				( pin "b"
					( attribute "PN" "4"
						( Origin gPackager )
					)
					( objectStatus "U9A5.4" )
				)
				( pin "oe_n"
					( attribute "PN" "1"
						( Origin gPackager )
					)
					( objectStatus "U9A5.1" )
				)
			)
			( gate "@baseboard_fab2_lib.baseboard_fab2(sch_1):page113_i188"
				( attribute "CDS_LIB" "mstr_discrete"
					( Origin gPackager )
				)
				( attribute "CDS_LOCATION" "R6M8"
					( Origin gPackager )
				)
				( attribute "CDS_SEC" "1"
					( Origin gPackager )
				)
				( attribute "LOCATION" "R6M8"
					( Origin gFrontEnd )
				)
				( attribute "MATERIAL" "CHIP"
					( Origin gFrontEnd )
				)
				( attribute "PACK_TYPE" "0402"
					( Origin gFrontEnd )
				)
				( attribute "PART_NUMBER" "G21796-047"
					( Origin gFrontEnd )
				)
				( attribute "PHYS_PAGE" "113"
					( Origin gFrontEnd )
				)
				( attribute "ROOM" "DEBUG"
					( Origin gFrontEnd )
				)
				( attribute "ROT" "2"
					( Origin gFrontEnd )
				)
				( attribute "SEC" "1"
					( Origin gFrontEnd )
				)
				( attribute "SEC_TYPE" "0402"
					( Origin gFrontEnd )
				)
				( attribute "TOLERANCE" "1%"
					( Origin gFrontEnd )
				)
				( attribute "VALUE" "49.9"
					( Origin gFrontEnd )
				)
				( attribute "VER" "2"
					( Origin gFrontEnd )
				)
				( attribute "WATTAGE" "1/16W"
					( Origin gFrontEnd )
				)
				( attribute "XY" "(2450,2075)"
					( Origin gFrontEnd )
				)
				( attribute "CHIPS_PART_NAME" "RES"
					( Origin gPackager )
				)
				( attribute "CDS_PART_NAME" "RES_0402-49.9,1%,1/16W,CHIP,G2A"
					( Origin gPackager )
				)
				( objectStatus "R6M8" )
				( pin "a"
					( attribute "PN" "1"
						( Origin gPackager )
					)
					( objectStatus "R6M8.1" )
				)
				( pin "b"
					( attribute "PN" "2"
						( Origin gPackager )
					)
					( objectStatus "R6M8.2" )
				)
			)
			( gate "@baseboard_fab2_lib.baseboard_fab2(sch_1):page113_i190"
				( attribute "BOM_COST" "DEBUG"
					( Origin gFrontEnd )
				)
				( attribute "CDS_LIB" "mstr_ttl"
					( Origin gPackager )
				)
				( attribute "CDS_LOCATION" "U6M1"
					( Origin gPackager )
				)
				( attribute "CDS_SEC" "1"
					( Origin gPackager )
				)
				( attribute "LOCATION" "U6M1"
					( Origin gFrontEnd )
				)
				( attribute "MATERIAL" "IC"
					( Origin gFrontEnd )
				)
				( attribute "PACK_TYPE" "SMLF"
					( Origin gFrontEnd )
				)
				( attribute "PART_NUMBER" "C88177-001"
					( Origin gFrontEnd )
				)
				( attribute "PHYS_PAGE" "113"
					( Origin gFrontEnd )
				)
				( attribute "ROOM" "DEBUG"
					( Origin gFrontEnd )
				)
				( attribute "ROT" "0"
					( Origin gFrontEnd )
				)
				( attribute "SEC" "1"
					( Origin gFrontEnd )
				)
				( attribute "SEC_TYPE" "SMLF"
					( Origin gFrontEnd )
				)
				( attribute "VER" "1"
					( Origin gFrontEnd )
				)
				( attribute "XY" "(1600,2250)"
					( Origin gFrontEnd )
				)
				( attribute "CHIPS_PART_NAME" "74CBTLV1G125"
					( Origin gPackager )
				)
				( attribute "CDS_PART_NAME" "74CBTLV1G125_SMLF-IC,C88177-00A"
					( Origin gPackager )
				)
				( objectStatus "U6M1" )
				( pin "a"
					( attribute "PN" "2"
						( Origin gPackager )
					)
					( objectStatus "U6M1.2" )
				)
				( pin "b"
					( attribute "PN" "4"
						( Origin gPackager )
					)
					( objectStatus "U6M1.4" )
				)
				( pin "oe_n"
					( attribute "PN" "1"
						( Origin gPackager )
					)
					( objectStatus "U6M1.1" )
				)
			)
			( gate "@baseboard_fab2_lib.baseboard_fab2(sch_1):page113_i195"
				( attribute "CDS_LIB" "mstr_discrete"
					( Origin gPackager )
				)
				( attribute "CDS_LOCATION" "R1M22"
					( Origin gPackager )
				)
				( attribute "CDS_SEC" "1"
					( Origin gPackager )
				)
				( attribute "LOCATION" "R1M22"
					( Origin gFrontEnd )
				)
				( attribute "MATERIAL" "CHIP"
					( Origin gFrontEnd )
				)
				( attribute "PACK_TYPE" "0402"
					( Origin gFrontEnd )
				)
				( attribute "PART_NUMBER" "G21796-047"
					( Origin gFrontEnd )
				)
				( attribute "PHYS_PAGE" "113"
					( Origin gFrontEnd )
				)
				( attribute "ROOM" "DEBUG"
					( Origin gFrontEnd )
				)
				( attribute "ROT" "2"
					( Origin gFrontEnd )
				)
				( attribute "SEC" "1"
					( Origin gFrontEnd )
				)
				( attribute "SEC_TYPE" "0402"
					( Origin gFrontEnd )
				)
				( attribute "TOLERANCE" "1%"
					( Origin gFrontEnd )
				)
				( attribute "VALUE" "49.9"
					( Origin gFrontEnd )
				)
				( attribute "VER" "2"
					( Origin gFrontEnd )
				)
				( attribute "WATTAGE" "1/16W"
					( Origin gFrontEnd )
				)
				( attribute "XY" "(2450,2650)"
					( Origin gFrontEnd )
				)
				( attribute "CHIPS_PART_NAME" "RES"
					( Origin gPackager )
				)
				( attribute "CDS_PART_NAME" "RES_0402-49.9,1%,1/16W,CHIP,G2A"
					( Origin gPackager )
				)
				( objectStatus "R1M22" )
				( pin "a"
					( attribute "PN" "1"
						( Origin gPackager )
					)
					( objectStatus "R1M22.1" )
				)
				( pin "b"
					( attribute "PN" "2"
						( Origin gPackager )
					)
					( objectStatus "R1M22.2" )
				)
			)
			( gate "@baseboard_fab2_lib.baseboard_fab2(sch_1):page113_i196"
				( attribute "BOM_COST" "DEBUG"
					( Origin gFrontEnd )
				)
				( attribute "CDS_LIB" "mstr_ttl"
					( Origin gPackager )
				)
				( attribute "CDS_LOCATION" "U1M5"
					( Origin gPackager )
				)
				( attribute "CDS_SEC" "1"
					( Origin gPackager )
				)
				( attribute "LOCATION" "U1M5"
					( Origin gFrontEnd )
				)
				( attribute "MATERIAL" "IC"
					( Origin gFrontEnd )
				)
				( attribute "PACK_TYPE" "SMLF"
					( Origin gFrontEnd )
				)
				( attribute "PART_NUMBER" "C88177-001"
					( Origin gFrontEnd )
				)
				( attribute "PHYS_PAGE" "113"
					( Origin gFrontEnd )
				)
				( attribute "ROOM" "DEBUG"
					( Origin gFrontEnd )
				)
				( attribute "ROT" "0"
					( Origin gFrontEnd )
				)
				( attribute "SEC" "1"
					( Origin gFrontEnd )
				)
				( attribute "SEC_TYPE" "SMLF"
					( Origin gFrontEnd )
				)
				( attribute "VER" "1"
					( Origin gFrontEnd )
				)
				( attribute "XY" "(1600,2825)"
					( Origin gFrontEnd )
				)
				( attribute "CHIPS_PART_NAME" "74CBTLV1G125"
					( Origin gPackager )
				)
				( attribute "CDS_PART_NAME" "74CBTLV1G125_SMLF-IC,C88177-00A"
					( Origin gPackager )
				)
				( objectStatus "U1M5" )
				( pin "a"
					( attribute "PN" "2"
						( Origin gPackager )
					)
					( objectStatus "U1M5.2" )
				)
				( pin "b"
					( attribute "PN" "4"
						( Origin gPackager )
					)
					( objectStatus "U1M5.4" )
				)
				( pin "oe_n"
					( attribute "PN" "1"
						( Origin gPackager )
					)
					( objectStatus "U1M5.1" )
				)
			)
			( gate "@baseboard_fab2_lib.baseboard_fab2(sch_1):page113_i199"
				( attribute "BOM_COST" "DEBUG"
					( Origin gFrontEnd )
				)
				( attribute "CDS_LIB" "mstr_discrete"
					( Origin gPackager )
				)
				( attribute "CDS_LOCATION" "R1M23"
					( Origin gPackager )
				)
				( attribute "CDS_SEC" "1"
					( Origin gPackager )
				)
				( attribute "LOCATION" "R1M23"
					( Origin gFrontEnd )
				)
				( attribute "MATERIAL" "EMPTY"
					( Origin gFrontEnd )
				)
				( attribute "PACK_TYPE" "0402"
					( Origin gFrontEnd )
				)
				( attribute "PART_NUMBER" "G21796-026"
					( Origin gFrontEnd )
				)
				( attribute "PHYS_PAGE" "113"
					( Origin gFrontEnd )
				)
				( attribute "ROOM" "DEBUG"
					( Origin gFrontEnd )
				)
				( attribute "ROT" "0"
					( Origin gFrontEnd )
				)
				( attribute "SEC" "1"
					( Origin gFrontEnd )
				)
				( attribute "SEC_TYPE" "0402"
					( Origin gFrontEnd )
				)
				( attribute "TOLERANCE" "1%"
					( Origin gFrontEnd )
				)
				( attribute "VALUE" "1.00K"
					( Origin gFrontEnd )
				)
				( attribute "VER" "2"
					( Origin gFrontEnd )
				)
				( attribute "WATTAGE" "1/16W"
					( Origin gFrontEnd )
				)
				( attribute "XY" "(1400,4225)"
					( Origin gFrontEnd )
				)
				( attribute "CHIPS_PART_NAME" "RES"
					( Origin gPackager )
				)
				( attribute "CDS_PART_NAME" "RES_0402-1.00K,1%,1/16W,EMPTY,A"
					( Origin gPackager )
				)
				( objectStatus "R1M23" )
				( pin "a"
					( attribute "PN" "1"
						( Origin gPackager )
					)
					( objectStatus "R1M23.1" )
				)
				( pin "b"
					( attribute "PN" "2"
						( Origin gPackager )
					)
					( objectStatus "R1M23.2" )
				)
			)
			( gate "@baseboard_fab2_lib.baseboard_fab2(sch_1):page113_i202"
				( attribute "BOM_COST" "DEBUG"
					( Origin gFrontEnd )
				)
				( attribute "CDS_LIB" "mstr_discrete"
					( Origin gPackager )
				)
				( attribute "CDS_LOCATION" "R1M19"
					( Origin gPackager )
				)
				( attribute "CDS_SEC" "1"
					( Origin gPackager )
				)
				( attribute "LOCATION" "R1M19"
					( Origin gFrontEnd )
				)
				( attribute "MATERIAL" "CHIP"
					( Origin gFrontEnd )
				)
				( attribute "PACK_TYPE" "0402"
					( Origin gFrontEnd )
				)
				( attribute "PART_NUMBER" "G21796-026"
					( Origin gFrontEnd )
				)
				( attribute "PHYS_PAGE" "113"
					( Origin gFrontEnd )
				)
				( attribute "ROOM" "DEBUG"
					( Origin gFrontEnd )
				)
				( attribute "ROT" "0"
					( Origin gFrontEnd )
				)
				( attribute "SEC" "1"
					( Origin gFrontEnd )
				)
				( attribute "SEC_TYPE" "0402"
					( Origin gFrontEnd )
				)
				( attribute "TOLERANCE" "1%"
					( Origin gFrontEnd )
				)
				( attribute "VALUE" "1.00K"
					( Origin gFrontEnd )
				)
				( attribute "VER" "2"
					( Origin gFrontEnd )
				)
				( attribute "WATTAGE" "1/16W"
					( Origin gFrontEnd )
				)
				( attribute "XY" "(3175,1025)"
					( Origin gFrontEnd )
				)
				( attribute "CHIPS_PART_NAME" "RES"
					( Origin gPackager )
				)
				( attribute "CDS_PART_NAME" "RES_0402-1.00K,1%,1/16W,CHIP,GA"
					( Origin gPackager )
				)
				( objectStatus "R1M19" )
				( pin "a"
					( attribute "PN" "1"
						( Origin gPackager )
					)
					( objectStatus "R1M19.1" )
				)
				( pin "b"
					( attribute "PN" "2"
						( Origin gPackager )
					)
					( objectStatus "R1M19.2" )
				)
			)
			( gate "@baseboard_fab2_lib.baseboard_fab2(sch_1):page113_i203"
				( attribute "BOM_COST" "DEBUG"
					( Origin gFrontEnd )
				)
				( attribute "CDS_LIB" "mstr_discrete"
					( Origin gPackager )
				)
				( attribute "CDS_LOCATION" "R9B12"
					( Origin gPackager )
				)
				( attribute "CDS_SEC" "1"
					( Origin gPackager )
				)
				( attribute "LOCATION" "R9B12"
					( Origin gFrontEnd )
				)
				( attribute "MATERIAL" "CHIP"
					( Origin gFrontEnd )
				)
				( attribute "PACK_TYPE" "0402"
					( Origin gFrontEnd )
				)
				( attribute "PART_NUMBER" "G21796-026"
					( Origin gFrontEnd )
				)
				( attribute "PHYS_PAGE" "113"
					( Origin gFrontEnd )
				)
				( attribute "ROOM" "DEBUG"
					( Origin gFrontEnd )
				)
				( attribute "ROT" "0"
					( Origin gFrontEnd )
				)
				( attribute "SEC" "1"
					( Origin gFrontEnd )
				)
				( attribute "SEC_TYPE" "0402"
					( Origin gFrontEnd )
				)
				( attribute "TOLERANCE" "1%"
					( Origin gFrontEnd )
				)
				( attribute "VALUE" "1.00K"
					( Origin gFrontEnd )
				)
				( attribute "VER" "2"
					( Origin gFrontEnd )
				)
				( attribute "WATTAGE" "1/16W"
					( Origin gFrontEnd )
				)
				( attribute "XY" "(3425,1025)"
					( Origin gFrontEnd )
				)
				( attribute "CHIPS_PART_NAME" "RES"
					( Origin gPackager )
				)
				( attribute "CDS_PART_NAME" "RES_0402-1.00K,1%,1/16W,CHIP,GA"
					( Origin gPackager )
				)
				( objectStatus "R9B12" )
				( pin "a"
					( attribute "PN" "1"
						( Origin gPackager )
					)
					( objectStatus "R9B12.1" )
				)
				( pin "b"
					( attribute "PN" "2"
						( Origin gPackager )
					)
					( objectStatus "R9B12.2" )
				)
			)
			( gate "@baseboard_fab2_lib.baseboard_fab2(sch_1):page113_i204"
				( attribute "BOM_COST" "DEBUG"
					( Origin gFrontEnd )
				)
				( attribute "CDS_LIB" "mstr_discrete"
					( Origin gPackager )
				)
				( attribute "CDS_LOCATION" "R1M20"
					( Origin gPackager )
				)
				( attribute "CDS_SEC" "1"
					( Origin gPackager )
				)
				( attribute "LOCATION" "R1M20"
					( Origin gFrontEnd )
				)
				( attribute "MATERIAL" "CHIP"
					( Origin gFrontEnd )
				)
				( attribute "PACK_TYPE" "0402"
					( Origin gFrontEnd )
				)
				( attribute "PART_NUMBER" "G21796-026"
					( Origin gFrontEnd )
				)
				( attribute "PHYS_PAGE" "113"
					( Origin gFrontEnd )
				)
				( attribute "ROOM" "DEBUG"
					( Origin gFrontEnd )
				)
				( attribute "ROT" "0"
					( Origin gFrontEnd )
				)
				( attribute "SEC" "1"
					( Origin gFrontEnd )
				)
				( attribute "SEC_TYPE" "0402"
					( Origin gFrontEnd )
				)
				( attribute "TOLERANCE" "1%"
					( Origin gFrontEnd )
				)
				( attribute "VALUE" "1.00K"
					( Origin gFrontEnd )
				)
				( attribute "VER" "2"
					( Origin gFrontEnd )
				)
				( attribute "WATTAGE" "1/16W"
					( Origin gFrontEnd )
				)
				( attribute "XY" "(2925,1025)"
					( Origin gFrontEnd )
				)
				( attribute "CHIPS_PART_NAME" "RES"
					( Origin gPackager )
				)
				( attribute "CDS_PART_NAME" "RES_0402-1.00K,1%,1/16W,CHIP,GA"
					( Origin gPackager )
				)
				( objectStatus "R1M20" )
				( pin "a"
					( attribute "PN" "1"
						( Origin gPackager )
					)
					( objectStatus "R1M20.1" )
				)
				( pin "b"
					( attribute "PN" "2"
						( Origin gPackager )
					)
					( objectStatus "R1M20.2" )
				)
			)
			( gate "@baseboard_fab2_lib.baseboard_fab2(sch_1):page113_i205"
				( attribute "BOM_COST" "DEBUG"
					( Origin gFrontEnd )
				)
				( attribute "CDS_LIB" "mstr_discrete"
					( Origin gPackager )
				)
				( attribute "CDS_LOCATION" "R1M21"
					( Origin gPackager )
				)
				( attribute "CDS_SEC" "1"
					( Origin gPackager )
				)
				( attribute "LOCATION" "R1M21"
					( Origin gFrontEnd )
				)
				( attribute "MATERIAL" "CHIP"
					( Origin gFrontEnd )
				)
				( attribute "PACK_TYPE" "0402"
					( Origin gFrontEnd )
				)
				( attribute "PART_NUMBER" "G21796-026"
					( Origin gFrontEnd )
				)
				( attribute "PHYS_PAGE" "113"
					( Origin gFrontEnd )
				)
				( attribute "ROOM" "DEBUG"
					( Origin gFrontEnd )
				)
				( attribute "ROT" "0"
					( Origin gFrontEnd )
				)
				( attribute "SEC" "1"
					( Origin gFrontEnd )
				)
				( attribute "SEC_TYPE" "0402"
					( Origin gFrontEnd )
				)
				( attribute "TOLERANCE" "1%"
					( Origin gFrontEnd )
				)
				( attribute "VALUE" "1.00K"
					( Origin gFrontEnd )
				)
				( attribute "VER" "2"
					( Origin gFrontEnd )
				)
				( attribute "WATTAGE" "1/16W"
					( Origin gFrontEnd )
				)
				( attribute "XY" "(3675,1025)"
					( Origin gFrontEnd )
				)
				( attribute "CHIPS_PART_NAME" "RES"
					( Origin gPackager )
				)
				( attribute "CDS_PART_NAME" "RES_0402-1.00K,1%,1/16W,CHIP,GA"
					( Origin gPackager )
				)
				( objectStatus "R1M21" )
				( pin "a"
					( attribute "PN" "1"
						( Origin gPackager )
					)
					( objectStatus "R1M21.1" )
				)
				( pin "b"
					( attribute "PN" "2"
						( Origin gPackager )
					)
					( objectStatus "R1M21.2" )
				)
			)
			( gate "@baseboard_fab2_lib.baseboard_fab2(sch_1):page113_i206"
				( attribute "BOM_COST" "DEBUG"
					( Origin gFrontEnd )
				)
				( attribute "CDS_LIB" "mstr_ttl"
					( Origin gPackager )
				)
				( attribute "CDS_LOCATION" "U4R1"
					( Origin gPackager )
				)
				( attribute "CDS_SEC" "1"
					( Origin gPackager )
				)
				( attribute "LOCATION" "U4R1"
					( Origin gFrontEnd )
				)
				( attribute "MATERIAL" "IC"
					( Origin gFrontEnd )
				)
				( attribute "PACK_TYPE" "SMLF"
					( Origin gFrontEnd )
				)
				( attribute "PART_NUMBER" "C88177-001"
					( Origin gFrontEnd )
				)
				( attribute "PHYS_PAGE" "113"
					( Origin gFrontEnd )
				)
				( attribute "ROOM" "DEBUG"
					( Origin gFrontEnd )
				)
				( attribute "ROT" "0"
					( Origin gFrontEnd )
				)
				( attribute "SEC" "1"
					( Origin gFrontEnd )
				)
				( attribute "SEC_TYPE" "SMLF"
					( Origin gFrontEnd )
				)
				( attribute "VER" "1"
					( Origin gFrontEnd )
				)
				( attribute "XY" "(1625,3375)"
					( Origin gFrontEnd )
				)
				( attribute "CHIPS_PART_NAME" "74CBTLV1G125"
					( Origin gPackager )
				)
				( attribute "CDS_PART_NAME" "74CBTLV1G125_SMLF-IC,C88177-00A"
					( Origin gPackager )
				)
				( objectStatus "U4R1" )
				( pin "a"
					( attribute "PN" "2"
						( Origin gPackager )
					)
					( objectStatus "U4R1.2" )
				)
				( pin "b"
					( attribute "PN" "4"
						( Origin gPackager )
					)
					( objectStatus "U4R1.4" )
				)
				( pin "oe_n"
					( attribute "PN" "1"
						( Origin gPackager )
					)
					( objectStatus "U4R1.1" )
				)
			)
			( gate "@baseboard_fab2_lib.baseboard_fab2(sch_1):page113_i239"
				( attribute "CDS_LIB" "mstr_discrete"
					( Origin gPackager )
				)
				( attribute "CDS_LOCATION" "R9B11"
					( Origin gPackager )
				)
				( attribute "CDS_SEC" "1"
					( Origin gPackager )
				)
				( attribute "LOCATION" "R9B11"
					( Origin gFrontEnd )
				)
				( attribute "MATERIAL" "CHIP"
					( Origin gFrontEnd )
				)
				( attribute "PACK_TYPE" "0402"
					( Origin gFrontEnd )
				)
				( attribute "PART_NUMBER" "G21497-005"
					( Origin gFrontEnd )
				)
				( attribute "PHYS_PAGE" "113"
					( Origin gFrontEnd )
				)
				( attribute "ROT" "0"
					( Origin gFrontEnd )
				)
				( attribute "SEC" "1"
					( Origin gFrontEnd )
				)
				( attribute "SEC_TYPE" "0402"
					( Origin gFrontEnd )
				)
				( attribute "TOLERANCE" "5%"
					( Origin gFrontEnd )
				)
				( attribute "VALUE" "0.0"
					( Origin gFrontEnd )
				)
				( attribute "VER" "1"
					( Origin gFrontEnd )
				)
				( attribute "WATTAGE" "1/16W"
					( Origin gFrontEnd )
				)
				( attribute "XY" "(-2600,4625)"
					( Origin gFrontEnd )
				)
				( attribute "CHIPS_PART_NAME" "RES"
					( Origin gPackager )
				)
				( attribute "CDS_PART_NAME" "RES_0402-0.0,5%,1/16W,CHIP,G21A"
					( Origin gPackager )
				)
				( objectStatus "R9B11" )
				( pin "a"
					( attribute "PN" "1"
						( Origin gPackager )
					)
					( objectStatus "R9B11.1" )
				)
				( pin "b"
					( attribute "PN" "2"
						( Origin gPackager )
					)
					( objectStatus "R9B11.2" )
				)
			)
			( gate "@baseboard_fab2_lib.baseboard_fab2(sch_1):page113_i240"
				( attribute "CDS_LIB" "mstr_discrete"
					( Origin gPackager )
				)
				( attribute "CDS_LOCATION" "R9B13"
					( Origin gPackager )
				)
				( attribute "CDS_SEC" "1"
					( Origin gPackager )
				)
				( attribute "LOCATION" "R9B13"
					( Origin gFrontEnd )
				)
				( attribute "MATERIAL" "CHIP"
					( Origin gFrontEnd )
				)
				( attribute "PACK_TYPE" "0402"
					( Origin gFrontEnd )
				)
				( attribute "PART_NUMBER" "G21497-005"
					( Origin gFrontEnd )
				)
				( attribute "PHYS_PAGE" "113"
					( Origin gFrontEnd )
				)
				( attribute "ROT" "0"
					( Origin gFrontEnd )
				)
				( attribute "SEC" "1"
					( Origin gFrontEnd )
				)
				( attribute "SEC_TYPE" "0402"
					( Origin gFrontEnd )
				)
				( attribute "TOLERANCE" "5%"
					( Origin gFrontEnd )
				)
				( attribute "VALUE" "0.0"
					( Origin gFrontEnd )
				)
				( attribute "VER" "1"
					( Origin gFrontEnd )
				)
				( attribute "WATTAGE" "1/16W"
					( Origin gFrontEnd )
				)
				( attribute "XY" "(-2600,4375)"
					( Origin gFrontEnd )
				)
				( attribute "CHIPS_PART_NAME" "RES"
					( Origin gPackager )
				)
				( attribute "CDS_PART_NAME" "RES_0402-0.0,5%,1/16W,CHIP,G21A"
					( Origin gPackager )
				)
				( objectStatus "R9B13" )
				( pin "a"
					( attribute "PN" "1"
						( Origin gPackager )
					)
					( objectStatus "R9B13.1" )
				)
				( pin "b"
					( attribute "PN" "2"
						( Origin gPackager )
					)
					( objectStatus "R9B13.2" )
				)
			)
			( gate "@baseboard_fab2_lib.baseboard_fab2(sch_1):page113_i246"
				( attribute "CDS_LIB" "dev_discrete"
					( Origin gPackager )
				)
				( attribute "CDS_LOCATION" "C4R2"
					( Origin gPackager )
				)
				( attribute "CDS_SEC" "1"
					( Origin gPackager )
				)
				( attribute "LOCATION" "C4R2"
					( Origin gFrontEnd )
				)
				( attribute "MATERIAL" "X7R"
					( Origin gFrontEnd )
				)
				( attribute "PACK_TYPE" "0402V"
					( Origin gFrontEnd )
				)
				( attribute "PART_NUMBER" "A36096-030"
					( Origin gFrontEnd )
				)
				( attribute "PHYS_PAGE" "113"
					( Origin gFrontEnd )
				)
				( attribute "ROOM" "DEBUG"
					( Origin gFrontEnd )
				)
				( attribute "ROT" "2"
					( Origin gFrontEnd )
				)
				( attribute "SEC" "1"
					( Origin gFrontEnd )
				)
				( attribute "SEC_TYPE" "0402V"
					( Origin gFrontEnd )
				)
				( attribute "TOLERANCE" "10%"
					( Origin gFrontEnd )
				)
				( attribute "VALUE" "0.1UF"
					( Origin gFrontEnd )
				)
				( attribute "VER" "1"
					( Origin gFrontEnd )
				)
				( attribute "VOLTAGE" "16V"
					( Units "uVoltage" "V" 1.000000)
					( Origin gFrontEnd )
				)
				( attribute "XY" "(2125,3200)"
					( Origin gFrontEnd )
				)
				( attribute "CHIPS_PART_NAME" "CAP_A"
					( Origin gPackager )
				)
				( attribute "CDS_PART_NAME" "CAP_A_0402V-0.1UF,16V,10%,X7R,A"
					( Origin gPackager )
				)
				( objectStatus "C4R2" )
				( pin "a"
					( attribute "PN" "1"
						( Origin gPackager )
					)
					( objectStatus "C4R2.1" )
				)
				( pin "b"
					( attribute "PN" "2"
						( Origin gPackager )
					)
					( objectStatus "C4R2.2" )
				)
			)
			( gate "@baseboard_fab2_lib.baseboard_fab2(sch_1):page113_i248"
				( attribute "BOM_COST" "DEBUG"
					( Origin gFrontEnd )
				)
				( attribute "CDS_LIB" "dev_discrete"
					( Origin gPackager )
				)
				( attribute "CDS_LOCATION" "C1M33"
					( Origin gPackager )
				)
				( attribute "CDS_SEC" "1"
					( Origin gPackager )
				)
				( attribute "LOCATION" "C1M33"
					( Origin gFrontEnd )
				)
				( attribute "MATERIAL" "X7R"
					( Origin gFrontEnd )
				)
				( attribute "PACK_TYPE" "0402V"
					( Origin gFrontEnd )
				)
				( attribute "PART_NUMBER" "A36096-030"
					( Origin gFrontEnd )
				)
				( attribute "PHYS_PAGE" "113"
					( Origin gFrontEnd )
				)
				( attribute "ROOM" "DEBUG"
					( Origin gFrontEnd )
				)
				( attribute "ROT" "2"
					( Origin gFrontEnd )
				)
				( attribute "SEC" "1"
					( Origin gFrontEnd )
				)
				( attribute "SEC_TYPE" "0402V"
					( Origin gFrontEnd )
				)
				( attribute "TOLERANCE" "10%"
					( Origin gFrontEnd )
				)
				( attribute "VALUE" "0.1UF"
					( Origin gFrontEnd )
				)
				( attribute "VER" "1"
					( Origin gFrontEnd )
				)
				( attribute "VOLTAGE" "16V"
					( Units "uVoltage" "V" 1.000000)
					( Origin gFrontEnd )
				)
				( attribute "XY" "(2125,2650)"
					( Origin gFrontEnd )
				)
				( attribute "CHIPS_PART_NAME" "CAP_A"
					( Origin gPackager )
				)
				( attribute "CDS_PART_NAME" "CAP_A_0402V-0.1UF,16V,10%,X7R,A"
					( Origin gPackager )
				)
				( objectStatus "C1M33" )
				( pin "a"
					( attribute "PN" "1"
						( Origin gPackager )
					)
					( objectStatus "C1M33.1" )
				)
				( pin "b"
					( attribute "PN" "2"
						( Origin gPackager )
					)
					( objectStatus "C1M33.2" )
				)
			)
			( gate "@baseboard_fab2_lib.baseboard_fab2(sch_1):page113_i250"
				( attribute "BOM_COST" "DEBUG"
					( Origin gFrontEnd )
				)
				( attribute "CDS_LIB" "dev_discrete"
					( Origin gPackager )
				)
				( attribute "CDS_LOCATION" "C6M6"
					( Origin gPackager )
				)
				( attribute "CDS_SEC" "1"
					( Origin gPackager )
				)
				( attribute "LOCATION" "C6M6"
					( Origin gFrontEnd )
				)
				( attribute "MATERIAL" "X7R"
					( Origin gFrontEnd )
				)
				( attribute "PACK_TYPE" "0402V"
					( Origin gFrontEnd )
				)
				( attribute "PART_NUMBER" "A36096-030"
					( Origin gFrontEnd )
				)
				( attribute "PHYS_PAGE" "113"
					( Origin gFrontEnd )
				)
				( attribute "ROOM" "DEBUG"
					( Origin gFrontEnd )
				)
				( attribute "ROT" "2"
					( Origin gFrontEnd )
				)
				( attribute "SEC" "1"
					( Origin gFrontEnd )
				)
				( attribute "SEC_TYPE" "0402V"
					( Origin gFrontEnd )
				)
				( attribute "TOLERANCE" "10%"
					( Origin gFrontEnd )
				)
				( attribute "VALUE" "0.1UF"
					( Origin gFrontEnd )
				)
				( attribute "VER" "1"
					( Origin gFrontEnd )
				)
				( attribute "VOLTAGE" "16V"
					( Units "uVoltage" "V" 1.000000)
					( Origin gFrontEnd )
				)
				( attribute "XY" "(2150,2075)"
					( Origin gFrontEnd )
				)
				( attribute "CHIPS_PART_NAME" "CAP_A"
					( Origin gPackager )
				)
				( attribute "CDS_PART_NAME" "CAP_A_0402V-0.1UF,16V,10%,X7R,A"
					( Origin gPackager )
				)
				( objectStatus "C6M6" )
				( pin "a"
					( attribute "PN" "1"
						( Origin gPackager )
					)
					( objectStatus "C6M6.1" )
				)
				( pin "b"
					( attribute "PN" "2"
						( Origin gPackager )
					)
					( objectStatus "C6M6.2" )
				)
			)
			( gate "@baseboard_fab2_lib.baseboard_fab2(sch_1):page113_i255"
				( attribute "BOM_COST" "DEBUG"
					( Origin gFrontEnd )
				)
				( attribute "CDS_LIB" "mstr_analog"
					( Origin gPackager )
				)
				( attribute "CDS_LOCATION" "U2M1"
					( Origin gPackager )
				)
				( attribute "CDS_SEC" "1"
					( Origin gPackager )
				)
				( attribute "LOCATION" "U2M1"
					( Origin gFrontEnd )
				)
				( attribute "MATERIAL" "IC"
					( Origin gFrontEnd )
				)
				( attribute "PACK_TYPE" "SMLF"
					( Origin gFrontEnd )
				)
				( attribute "PART_NUMBER" "C99406-001"
					( Origin gFrontEnd )
				)
				( attribute "PHYS_PAGE" "113"
					( Origin gFrontEnd )
				)
				( attribute "ROOM" "DEBUG"
					( Origin gFrontEnd )
				)
				( attribute "ROT" "2"
					( Origin gFrontEnd )
				)
				( attribute "SEC" "1"
					( Origin gFrontEnd )
				)
				( attribute "SEC_TYPE" "SMLF"
					( Origin gFrontEnd )
				)
				( attribute "VER" "1"
					( Origin gFrontEnd )
				)
				( attribute "XY" "(-2125,2325)"
					( Origin gFrontEnd )
				)
				( attribute "CHIPS_PART_NAME" "NC7SB3157"
					( Origin gPackager )
				)
				( attribute "CDS_PART_NAME" "NC7SB3157_SMLF-IC,C99406-001"
					( Origin gPackager )
				)
				( objectStatus "U2M1" )
				( pin "a"
					( attribute "PN" "4"
						( Origin gPackager )
					)
					( objectStatus "U2M1.4" )
				)
				( pin "b0"
					( attribute "PN" "3"
						( Origin gPackager )
					)
					( objectStatus "U2M1.3" )
				)
				( pin "b1"
					( attribute "PN" "1"
						( Origin gPackager )
					)
					( objectStatus "U2M1.1" )
				)
				( pin "gnd"
					( attribute "PN" "2"
						( Origin gPackager )
					)
					( objectStatus "U2M1.2" )
				)
				( pin "s"
					( attribute "PN" "6"
						( Origin gPackager )
					)
					( objectStatus "U2M1.6" )
				)
				( pin "vcc"
					( attribute "PN" "5"
						( Origin gPackager )
					)
					( objectStatus "U2M1.5" )
				)
			)
			( gate "@baseboard_fab2_lib.baseboard_fab2(sch_1):page113_i265"
				( attribute "BOM_COST" "DEBUG"
					( Origin gFrontEnd )
				)
				( attribute "CDS_LIB" "dev_discrete"
					( Origin gPackager )
				)
				( attribute "CDS_LOCATION" "C1M34"
					( Origin gPackager )
				)
				( attribute "CDS_SEC" "1"
					( Origin gPackager )
				)
				( attribute "LOCATION" "C1M34"
					( Origin gFrontEnd )
				)
				( attribute "MATERIAL" "X7R"
					( Origin gFrontEnd )
				)
				( attribute "PACK_TYPE" "0402V"
					( Origin gFrontEnd )
				)
				( attribute "PART_NUMBER" "A36096-045"
					( Origin gFrontEnd )
				)
				( attribute "PHYS_PAGE" "113"
					( Origin gFrontEnd )
				)
				( attribute "ROOM" "DEBUG"
					( Origin gFrontEnd )
				)
				( attribute "ROT" "2"
					( Origin gFrontEnd )
				)
				( attribute "SEC" "1"
					( Origin gFrontEnd )
				)
				( attribute "SEC_TYPE" "0402V"
					( Origin gFrontEnd )
				)
				( attribute "TOLERANCE" "10%"
					( Origin gFrontEnd )
				)
				( attribute "VALUE" "0.01UF"
					( Origin gFrontEnd )
				)
				( attribute "VER" "1"
					( Origin gFrontEnd )
				)
				( attribute "VOLTAGE" "25V"
					( Units "uVoltage" "V" 1.000000)
					( Origin gFrontEnd )
				)
				( attribute "XY" "(-1275,1825)"
					( Origin gFrontEnd )
				)
				( attribute "CHIPS_PART_NAME" "CAP_A"
					( Origin gPackager )
				)
				( attribute "CDS_PART_NAME" "CAP_A_0402V-0.01UF,25V,10%,X7RA"
					( Origin gPackager )
				)
				( objectStatus "C1M34" )
				( pin "a"
					( attribute "PN" "1"
						( Origin gPackager )
					)
					( objectStatus "C1M34.1" )
				)
				( pin "b"
					( attribute "PN" "2"
						( Origin gPackager )
					)
					( objectStatus "C1M34.2" )
				)
			)
			( gate "@baseboard_fab2_lib.baseboard_fab2(sch_1):page113_i266"
				( attribute "BOM_COST" "DEBUG"
					( Origin gFrontEnd )
				)
				( attribute "CDS_LIB" "dev_discrete"
					( Origin gPackager )
				)
				( attribute "CDS_LOCATION" "C1M35"
					( Origin gPackager )
				)
				( attribute "CDS_SEC" "1"
					( Origin gPackager )
				)
				( attribute "LOCATION" "C1M35"
					( Origin gFrontEnd )
				)
				( attribute "MATERIAL" "X7R"
					( Origin gFrontEnd )
				)
				( attribute "PACK_TYPE" "0402V"
					( Origin gFrontEnd )
				)
				( attribute "PART_NUMBER" "A36096-045"
					( Origin gFrontEnd )
				)
				( attribute "PHYS_PAGE" "113"
					( Origin gFrontEnd )
				)
				( attribute "ROOM" "DEBUG"
					( Origin gFrontEnd )
				)
				( attribute "ROT" "2"
					( Origin gFrontEnd )
				)
				( attribute "SEC" "1"
					( Origin gFrontEnd )
				)
				( attribute "SEC_TYPE" "0402V"
					( Origin gFrontEnd )
				)
				( attribute "TOLERANCE" "10%"
					( Origin gFrontEnd )
				)
				( attribute "VALUE" "0.01UF"
					( Origin gFrontEnd )
				)
				( attribute "VER" "1"
					( Origin gFrontEnd )
				)
				( attribute "VOLTAGE" "25V"
					( Units "uVoltage" "V" 1.000000)
					( Origin gFrontEnd )
				)
				( attribute "XY" "(-1600,1825)"
					( Origin gFrontEnd )
				)
				( attribute "CHIPS_PART_NAME" "CAP_A"
					( Origin gPackager )
				)
				( attribute "CDS_PART_NAME" "CAP_A_0402V-0.01UF,25V,10%,X7RA"
					( Origin gPackager )
				)
				( objectStatus "C1M35" )
				( pin "a"
					( attribute "PN" "1"
						( Origin gPackager )
					)
					( objectStatus "C1M35.1" )
				)
				( pin "b"
					( attribute "PN" "2"
						( Origin gPackager )
					)
					( objectStatus "C1M35.2" )
				)
			)
			( gate "@baseboard_fab2_lib.baseboard_fab2(sch_1):page113_i267"
				( attribute "BOM_COST" "DEBUG"
					( Origin gFrontEnd )
				)
				( attribute "CDS_LIB" "dev_discrete"
					( Origin gPackager )
				)
				( attribute "CDS_LOCATION" "C1L20"
					( Origin gPackager )
				)
				( attribute "CDS_SEC" "1"
					( Origin gPackager )
				)
				( attribute "LOCATION" "C1L20"
					( Origin gFrontEnd )
				)
				( attribute "MATERIAL" "X7R"
					( Origin gFrontEnd )
				)
				( attribute "PACK_TYPE" "0402V"
					( Origin gFrontEnd )
				)
				( attribute "PART_NUMBER" "A36096-045"
					( Origin gFrontEnd )
				)
				( attribute "PHYS_PAGE" "113"
					( Origin gFrontEnd )
				)
				( attribute "ROOM" "DEBUG"
					( Origin gFrontEnd )
				)
				( attribute "ROT" "2"
					( Origin gFrontEnd )
				)
				( attribute "SEC" "1"
					( Origin gFrontEnd )
				)
				( attribute "SEC_TYPE" "0402V"
					( Origin gFrontEnd )
				)
				( attribute "TOLERANCE" "10%"
					( Origin gFrontEnd )
				)
				( attribute "VALUE" "0.01UF"
					( Origin gFrontEnd )
				)
				( attribute "VER" "1"
					( Origin gFrontEnd )
				)
				( attribute "VOLTAGE" "25V"
					( Units "uVoltage" "V" 1.000000)
					( Origin gFrontEnd )
				)
				( attribute "XY" "(3025,3650)"
					( Origin gFrontEnd )
				)
				( attribute "CHIPS_PART_NAME" "CAP_A"
					( Origin gPackager )
				)
				( attribute "CDS_PART_NAME" "CAP_A_0402V-0.01UF,25V,10%,X7RA"
					( Origin gPackager )
				)
				( objectStatus "C1L20" )
				( pin "a"
					( attribute "PN" "1"
						( Origin gPackager )
					)
					( objectStatus "C1L20.1" )
				)
				( pin "b"
					( attribute "PN" "2"
						( Origin gPackager )
					)
					( objectStatus "C1L20.2" )
				)
			)
			( gate "@baseboard_fab2_lib.baseboard_fab2(sch_1):page114_i40"
				( attribute "BOM_COST" "SB"
					( Origin gFrontEnd )
				)
				( attribute "CDS_LIB" "mstr_u_proc"
					( Origin gPackager )
				)
				( attribute "CDS_LOCATION" "U7C1"
					( Origin gPackager )
				)
				( attribute "CDS_SEC" "1"
					( Origin gPackager )
				)
				( attribute "LOCATION" "U7C1"
					( Origin gFrontEnd )
				)
				( attribute "MATERIAL" "IC"
					( Origin gFrontEnd )
				)
				( attribute "PACK_TYPE" "BGA1"
					( Origin gFrontEnd )
				)
				( attribute "PART_NUMBER" "H91415-002"
					( Origin gFrontEnd )
				)
				( attribute "PHYS_PAGE" "114"
					( Origin gFrontEnd )
				)
				( attribute "ROOM" "SB"
					( Origin gFrontEnd )
				)
				( attribute "ROT" "0"
					( Origin gFrontEnd )
				)
				( attribute "SEC" "1"
					( Origin gFrontEnd )
				)
				( attribute "SEC_TYPE" "BGA1"
					( Origin gFrontEnd )
				)
				( attribute "VER" "1"
					( Origin gFrontEnd )
				)
				( attribute "XY" "(525,2150)"
					( Origin gFrontEnd )
				)
				( attribute "CHIPS_PART_NAME" "LBG_CORE_QAT_EXT_D"
					( Origin gPackager )
				)
				( attribute "CDS_PART_NAME" "LBG_CORE_QAT_EXT_D_BGA1-IC,H91A"
					( Origin gPackager )
				)
				( objectStatus "U7C1" )
				( pin "clkout_itpxdpn"
					( attribute "PN" "A39"
						( Origin gPackager )
					)
					( objectStatus "U7C1.A39" )
				)
				( pin "clkout_itpxdpp"
					( attribute "PN" "C39"
						( Origin gPackager )
					)
					( objectStatus "U7C1.C39" )
				)
				( pin "clkout_nssccap0n"
					( attribute "PN" "A32"
						( Origin gPackager )
					)
					( objectStatus "U7C1.A32" )
				)
				( pin "clkout_nssccap0p"
					( attribute "PN" "C32"
						( Origin gPackager )
					)
					( objectStatus "U7C1.C32" )
				)
				( pin "clkout_nssccap1n"
					( attribute "PN" "B38"
						( Origin gPackager )
					)
					( objectStatus "U7C1.B38" )
				)
				( pin "clkout_nssccap1p"
					( attribute "PN" "D38"
						( Origin gPackager )
					)
					( objectStatus "U7C1.D38" )
				)
				( pin "clkout_plat0n"
					( attribute "PN" "B29"
						( Origin gPackager )
					)
					( objectStatus "U7C1.B29" )
				)
				( pin "clkout_plat0p"
					( attribute "PN" "D29"
						( Origin gPackager )
					)
					( objectStatus "U7C1.D29" )
				)
				( pin "clkout_plat1n"
					( attribute "PN" "B40"
						( Origin gPackager )
					)
					( objectStatus "U7C1.B40" )
				)
				( pin "clkout_plat1p"
					( attribute "PN" "D40"
						( Origin gPackager )
					)
					( objectStatus "U7C1.D40" )
				)
				( pin "clkout_srcn(0)"
					( attribute "PN" "K38"
						( Origin gPackager )
					)
					( objectStatus "U7C1.K38" )
				)
				( pin "clkout_srcn(1)"
					( attribute "PN" "K35"
						( Origin gPackager )
					)
					( objectStatus "U7C1.K35" )
				)
				( pin "clkout_srcn(2)"
					( attribute "PN" "J33"
						( Origin gPackager )
					)
					( objectStatus "U7C1.J33" )
				)
				( pin "clkout_srcn(3)"
					( attribute "PN" "K42"
						( Origin gPackager )
					)
					( objectStatus "U7C1.K42" )
				)
				( pin "clkout_srcn(4)"
					( attribute "PN" "A28"
						( Origin gPackager )
					)
					( objectStatus "U7C1.A28" )
				)
				( pin "clkout_srcn(5)"
					( attribute "PN" "J40"
						( Origin gPackager )
					)
					( objectStatus "U7C1.J40" )
				)
				( pin "clkout_srcn(6)"
					( attribute "PN" "D33"
						( Origin gPackager )
					)
					( objectStatus "U7C1.D33" )
				)
				( pin "clkout_srcn(7)"
					( attribute "PN" "H31"
						( Origin gPackager )
					)
					( objectStatus "U7C1.H31" )
				)
				( pin "clkout_srcn(8)"
					( attribute "PN" "D31"
						( Origin gPackager )
					)
					( objectStatus "U7C1.D31" )
				)
				( pin "clkout_srcn(9)"
					( attribute "PN" "J26"
						( Origin gPackager )
					)
					( objectStatus "U7C1.J26" )
				)
				( pin "clkout_srcn(10)"
					( attribute "PN" "B23"
						( Origin gPackager )
					)
					( objectStatus "U7C1.B23" )
				)
				( pin "clkout_srcn(11)"
					( attribute "PN" "B21"
						( Origin gPackager )
					)
					( objectStatus "U7C1.B21" )
				)
				( pin "clkout_srcn(12)"
					( attribute "PN" "K24"
						( Origin gPackager )
					)
					( objectStatus "U7C1.K24" )
				)
				( pin "clkout_srcn(13)"
					( attribute "PN" "C24"
						( Origin gPackager )
					)
					( objectStatus "U7C1.C24" )
				)
				( pin "clkout_srcn(14)"
					( attribute "PN" "C20"
						( Origin gPackager )
					)
					( objectStatus "U7C1.C20" )
				)
				( pin "clkout_srcn(15)"
					( attribute "PN" "K27"
						( Origin gPackager )
					)
					( objectStatus "U7C1.K27" )
				)
				( pin "clkout_srcp(0)"
					( attribute "PN" "H38"
						( Origin gPackager )
					)
					( objectStatus "U7C1.H38" )
				)
				( pin "clkout_srcp(1)"
					( attribute "PN" "H35"
						( Origin gPackager )
					)
					( objectStatus "U7C1.H35" )
				)
				( pin "clkout_srcp(2)"
					( attribute "PN" "G33"
						( Origin gPackager )
					)
					( objectStatus "U7C1.G33" )
				)
				( pin "clkout_srcp(3)"
					( attribute "PN" "H42"
						( Origin gPackager )
					)
					( objectStatus "U7C1.H42" )
				)
				( pin "clkout_srcp(4)"
					( attribute "PN" "C28"
						( Origin gPackager )
					)
					( objectStatus "U7C1.C28" )
				)
				( pin "clkout_srcp(5)"
					( attribute "PN" "G40"
						( Origin gPackager )
					)
					( objectStatus "U7C1.G40" )
				)
				( pin "clkout_srcp(6)"
					( attribute "PN" "B33"
						( Origin gPackager )
					)
					( objectStatus "U7C1.B33" )
				)
				( pin "clkout_srcp(7)"
					( attribute "PN" "K31"
						( Origin gPackager )
					)
					( objectStatus "U7C1.K31" )
				)
				( pin "clkout_srcp(8)"
					( attribute "PN" "B31"
						( Origin gPackager )
					)
					( objectStatus "U7C1.B31" )
				)
				( pin "clkout_srcp(9)"
					( attribute "PN" "G26"
						( Origin gPackager )
					)
					( objectStatus "U7C1.G26" )
				)
				( pin "clkout_srcp(10)"
					( attribute "PN" "D23"
						( Origin gPackager )
					)
					( objectStatus "U7C1.D23" )
				)
				( pin "clkout_srcp(11)"
					( attribute "PN" "D21"
						( Origin gPackager )
					)
					( objectStatus "U7C1.D21" )
				)
				( pin "clkout_srcp(12)"
					( attribute "PN" "H24"
						( Origin gPackager )
					)
					( objectStatus "U7C1.H24" )
				)
				( pin "clkout_srcp(13)"
					( attribute "PN" "A24"
						( Origin gPackager )
					)
					( objectStatus "U7C1.A24" )
				)
				( pin "clkout_srcp(14)"
					( attribute "PN" "A20"
						( Origin gPackager )
					)
					( objectStatus "U7C1.A20" )
				)
				( pin "clkout_srcp(15)"
					( attribute "PN" "H27"
						( Origin gPackager )
					)
					( objectStatus "U7C1.H27" )
				)
				( pin "clockse_bmcclk"
					( attribute "PN" "BW50"
						( Origin gPackager )
					)
					( objectStatus "U7C1.BW50" )
				)
				( pin "clockse_pmsyncclk1"
					( attribute "PN" "BY51"
						( Origin gPackager )
					)
					( objectStatus "U7C1.BY51" )
				)
				( pin "clockse_pmsyncclk2"
					( attribute "PN" "BV51"
						( Origin gPackager )
					)
					( objectStatus "U7C1.BV51" )
				)
				( pin "rsvd(64)"
					( attribute "PN" "C26"
						( Origin gPackager )
					)
					( objectStatus "U7C1.C26" )
				)
				( pin "rsvd(65)"
					( attribute "PN" "A26"
						( Origin gPackager )
					)
					( objectStatus "U7C1.A26" )
				)
				( pin "rtcx1"
					( attribute "PN" "K17"
						( Origin gPackager )
					)
					( objectStatus "U7C1.K17" )
				)
				( pin "rtcx2"
					( attribute "PN" "H17"
						( Origin gPackager )
					)
					( objectStatus "U7C1.H17" )
				)
				( pin "xclk_biasref"
					( attribute "PN" "G44"
						( Origin gPackager )
					)
					( objectStatus "U7C1.G44" )
				)
				( pin "xtal_in"
					( attribute "PN" "B35"
						( Origin gPackager )
					)
					( objectStatus "U7C1.B35" )
				)
				( pin "xtal_out"
					( attribute "PN" "D35"
						( Origin gPackager )
					)
					( objectStatus "U7C1.D35" )
				)
			)
			( gate "@baseboard_fab2_lib.baseboard_fab2(sch_1):page114_i46"
				( attribute "CDS_LIB" "mstr_discrete"
					( Origin gPackager )
				)
				( attribute "CDS_LOCATION" "C7C15"
					( Origin gPackager )
				)
				( attribute "CDS_SEC" "1"
					( Origin gPackager )
				)
				( attribute "LOCATION" "C7C15"
					( Origin gFrontEnd )
				)
				( attribute "MATERIAL" "C0G"
					( Origin gFrontEnd )
				)
				( attribute "PACK_TYPE" "0402LF"
					( Origin gFrontEnd )
				)
				( attribute "PART_NUMBER" "A36095-042"
					( Origin gFrontEnd )
				)
				( attribute "PHYS_PAGE" "114"
					( Origin gFrontEnd )
				)
				( attribute "ROOM" "SB"
					( Origin gFrontEnd )
				)
				( attribute "ROT" "0"
					( Origin gFrontEnd )
				)
				( attribute "SEC" "1"
					( Origin gPackager )
				)
				( attribute "TOLERANCE" "5%"
					( Origin gFrontEnd )
				)
				( attribute "VALUE" "18PF"
					( Origin gFrontEnd )
				)
				( attribute "VER" "1"
					( Origin gFrontEnd )
				)
				( attribute "VOLTAGE" "50V"
					( Units "uVoltage" "V" 1.000000)
					( Origin gFrontEnd )
				)
				( attribute "XY" "(225,-225)"
					( Origin gFrontEnd )
				)
				( attribute "CHIPS_PART_NAME" "CAP"
					( Origin gPackager )
				)
				( attribute "CDS_PART_NAME" "CAP_0402LF-18PF,50V,5%,C0G,A36A"
					( Origin gPackager )
				)
				( objectStatus "C7C15" )
				( pin "a"
					( attribute "PN" "1"
						( Origin gPackager )
					)
					( objectStatus "C7C15.1" )
				)
				( pin "b"
					( attribute "PN" "2"
						( Origin gPackager )
					)
					( objectStatus "C7C15.2" )
				)
			)
			( gate "@baseboard_fab2_lib.baseboard_fab2(sch_1):page114_i47"
				( attribute "BOM_COST" "SYS_CLOCK"
					( Origin gFrontEnd )
				)
				( attribute "CDS_LIB" "mstr_discrete"
					( Origin gPackager )
				)
				( attribute "CDS_LOCATION" "C7C5"
					( Origin gPackager )
				)
				( attribute "CDS_SEC" "1"
					( Origin gPackager )
				)
				( attribute "LOCATION" "C7C5"
					( Origin gFrontEnd )
				)
				( attribute "MATERIAL" "COG"
					( Origin gFrontEnd )
				)
				( attribute "PACK_TYPE" "0402LF"
					( Origin gFrontEnd )
				)
				( attribute "PART_NUMBER" "A36095-047"
					( Origin gFrontEnd )
				)
				( attribute "PHYS_PAGE" "114"
					( Origin gFrontEnd )
				)
				( attribute "ROOM" "SB"
					( Origin gFrontEnd )
				)
				( attribute "ROT" "0"
					( Origin gFrontEnd )
				)
				( attribute "SEC" "1"
					( Origin gFrontEnd )
				)
				( attribute "SEC_TYPE" "0402LF"
					( Origin gFrontEnd )
				)
				( attribute "TOLERANCE" "5%"
					( Origin gFrontEnd )
				)
				( attribute "VALUE" "15.0PF"
					( Origin gFrontEnd )
				)
				( attribute "VER" "1"
					( Origin gFrontEnd )
				)
				( attribute "VOLTAGE" "50V"
					( Units "uVoltage" "V" 1.000000)
					( Origin gFrontEnd )
				)
				( attribute "XY" "(-1525,-225)"
					( Origin gFrontEnd )
				)
				( attribute "CHIPS_PART_NAME" "CAP"
					( Origin gPackager )
				)
				( attribute "CDS_PART_NAME" "CAP_0402LF-15.0PF,50V,5%,COG,AA"
					( Origin gPackager )
				)
				( objectStatus "C7C5" )
				( pin "a"
					( attribute "PN" "1"
						( Origin gPackager )
					)
					( objectStatus "C7C5.1" )
				)
				( pin "b"
					( attribute "PN" "2"
						( Origin gPackager )
					)
					( objectStatus "C7C5.2" )
				)
			)
			( gate "@baseboard_fab2_lib.baseboard_fab2(sch_1):page114_i48"
				( attribute "CDS_LIB" "mstr_discrete"
					( Origin gPackager )
				)
				( attribute "CDS_LOCATION" "R7C1"
					( Origin gPackager )
				)
				( attribute "CDS_SEC" "1"
					( Origin gPackager )
				)
				( attribute "LOCATION" "R7C1"
					( Origin gFrontEnd )
				)
				( attribute "MATERIAL" "CHIP"
					( Origin gFrontEnd )
				)
				( attribute "PACK_TYPE" "0603"
					( Origin gFrontEnd )
				)
				( attribute "PART_NUMBER" "G22369-010"
					( Origin gFrontEnd )
				)
				( attribute "PHYS_PAGE" "114"
					( Origin gFrontEnd )
				)
				( attribute "ROOM" "SB"
					( Origin gFrontEnd )
				)
				( attribute "ROT" "0"
					( Origin gFrontEnd )
				)
				( attribute "SEC" "1"
					( Origin gFrontEnd )
				)
				( attribute "SEC_TYPE" "0603"
					( Origin gFrontEnd )
				)
				( attribute "TOLERANCE" "0.1%"
					( Origin gFrontEnd )
				)
				( attribute "VALUE" "200K"
					( Origin gFrontEnd )
				)
				( attribute "VER" "1"
					( Origin gFrontEnd )
				)
				( attribute "WATTAGE" "1/10W"
					( Origin gFrontEnd )
				)
				( attribute "XY" "(-1775,475)"
					( Origin gFrontEnd )
				)
				( attribute "CHIPS_PART_NAME" "RES"
					( Origin gPackager )
				)
				( attribute "CDS_PART_NAME" "RES_0603-200K,0.1%,1/10W,CHIP,A"
					( Origin gPackager )
				)
				( objectStatus "R7C1" )
				( pin "a"
					( attribute "PN" "1"
						( Origin gPackager )
					)
					( objectStatus "R7C1.1" )
				)
				( pin "b"
					( attribute "PN" "2"
						( Origin gPackager )
					)
					( objectStatus "R7C1.2" )
				)
			)
			( gate "@baseboard_fab2_lib.baseboard_fab2(sch_1):page114_i49"
				( attribute "CDS_LIB" "mstr_discrete"
					( Origin gPackager )
				)
				( attribute "CDS_LOCATION" "Y7C1"
					( Origin gPackager )
				)
				( attribute "CDS_SEC" "1"
					( Origin gPackager )
				)
				( attribute "LOCATION" "Y7C1"
					( Origin gFrontEnd )
				)
				( attribute "MATERIAL" "IC"
					( Origin gFrontEnd )
				)
				( attribute "PACK_TYPE" "2013"
					( Origin gFrontEnd )
				)
				( attribute "PART_NUMBER" "D71700-058"
					( Origin gFrontEnd )
				)
				( attribute "PHYS_PAGE" "114"
					( Origin gFrontEnd )
				)
				( attribute "ROOM" "SB"
					( Origin gFrontEnd )
				)
				( attribute "ROT" "0"
					( Origin gFrontEnd )
				)
				( attribute "SEC" "1"
					( Origin gFrontEnd )
				)
				( attribute "SEC_TYPE" "2013"
					( Origin gFrontEnd )
				)
				( attribute "VALUE" "48.000MHZ"
					( Origin gFrontEnd )
				)
				( attribute "VER" "1"
					( Origin gFrontEnd )
				)
				( attribute "XY" "(-1775,125)"
					( Origin gFrontEnd )
				)
				( attribute "CHIPS_PART_NAME" "CRYSTAL"
					( Origin gPackager )
				)
				( attribute "CDS_PART_NAME" "CRYSTAL_2013-48.000MHZ,IC,D717A"
					( Origin gPackager )
				)
				( objectStatus "Y7C1" )
				( pin "a"
					( attribute "PN" "1"
						( Origin gPackager )
					)
					( objectStatus "Y7C1.1" )
				)
				( pin "b"
					( attribute "PN" "3"
						( Origin gPackager )
					)
					( objectStatus "Y7C1.3" )
				)
			)
			( gate "@baseboard_fab2_lib.baseboard_fab2(sch_1):page114_i50"
				( attribute "BOM_COST" "SYS_CLOCK"
					( Origin gFrontEnd )
				)
				( attribute "CDS_LIB" "mstr_discrete"
					( Origin gPackager )
				)
				( attribute "CDS_LOCATION" "C7C4"
					( Origin gPackager )
				)
				( attribute "CDS_SEC" "1"
					( Origin gPackager )
				)
				( attribute "LOCATION" "C7C4"
					( Origin gFrontEnd )
				)
				( attribute "MATERIAL" "COG"
					( Origin gFrontEnd )
				)
				( attribute "PACK_TYPE" "0402LF"
					( Origin gFrontEnd )
				)
				( attribute "PART_NUMBER" "A36095-047"
					( Origin gFrontEnd )
				)
				( attribute "PHYS_PAGE" "114"
					( Origin gFrontEnd )
				)
				( attribute "ROOM" "SB"
					( Origin gFrontEnd )
				)
				( attribute "ROT" "0"
					( Origin gFrontEnd )
				)
				( attribute "SEC" "1"
					( Origin gFrontEnd )
				)
				( attribute "SEC_TYPE" "0402LF"
					( Origin gFrontEnd )
				)
				( attribute "TOLERANCE" "5%"
					( Origin gFrontEnd )
				)
				( attribute "VALUE" "15.0PF"
					( Origin gFrontEnd )
				)
				( attribute "VER" "1"
					( Origin gFrontEnd )
				)
				( attribute "VOLTAGE" "50V"
					( Units "uVoltage" "V" 1.000000)
					( Origin gFrontEnd )
				)
				( attribute "XY" "(-2025,-225)"
					( Origin gFrontEnd )
				)
				( attribute "CHIPS_PART_NAME" "CAP"
					( Origin gPackager )
				)
				( attribute "CDS_PART_NAME" "CAP_0402LF-15.0PF,50V,5%,COG,AA"
					( Origin gPackager )
				)
				( objectStatus "C7C4" )
				( pin "a"
					( attribute "PN" "1"
						( Origin gPackager )
					)
					( objectStatus "C7C4.1" )
				)
				( pin "b"
					( attribute "PN" "2"
						( Origin gPackager )
					)
					( objectStatus "C7C4.2" )
				)
			)
			( gate "@baseboard_fab2_lib.baseboard_fab2(sch_1):page114_i54"
				( attribute "BOM_COST" "SYS_CLOCK"
					( Origin gFrontEnd )
				)
				( attribute "CDS_LIB" "mstr_discrete"
					( Origin gPackager )
				)
				( attribute "CDS_LOCATION" "R7C6"
					( Origin gPackager )
				)
				( attribute "CDS_SEC" "1"
					( Origin gPackager )
				)
				( attribute "LOCATION" "R7C6"
					( Origin gFrontEnd )
				)
				( attribute "MATERIAL" "CHIP"
					( Origin gFrontEnd )
				)
				( attribute "PACK_TYPE" "0603"
					( Origin gFrontEnd )
				)
				( attribute "PART_NUMBER" "G22026-112"
					( Origin gFrontEnd )
				)
				( attribute "PHYS_PAGE" "114"
					( Origin gFrontEnd )
				)
				( attribute "ROOM" "SB"
					( Origin gFrontEnd )
				)
				( attribute "ROT" "0"
					( Origin gFrontEnd )
				)
				( attribute "SEC" "1"
					( Origin gPackager )
				)
				( attribute "TOLERANCE" "1.0%"
					( Origin gFrontEnd )
				)
				( attribute "VALUE" "10M"
					( Origin gFrontEnd )
				)
				( attribute "VER" "1"
					( Origin gFrontEnd )
				)
				( attribute "WATTAGE" "1/10W"
					( Origin gFrontEnd )
				)
				( attribute "XY" "(-25,475)"
					( Origin gFrontEnd )
				)
				( attribute "CHIPS_PART_NAME" "RES"
					( Origin gPackager )
				)
				( attribute "CDS_PART_NAME" "RES_0603-10M,1.0%,1/10W,CHIP,GA"
					( Origin gPackager )
				)
				( objectStatus "R7C6" )
				( pin "a"
					( attribute "PN" "1"
						( Origin gPackager )
					)
					( objectStatus "R7C6.1" )
				)
				( pin "b"
					( attribute "PN" "2"
						( Origin gPackager )
					)
					( objectStatus "R7C6.2" )
				)
			)
			( gate "@baseboard_fab2_lib.baseboard_fab2(sch_1):page114_i55"
				( attribute "CDS_LIB" "mstr_discrete"
					( Origin gPackager )
				)
				( attribute "CDS_LOCATION" "Y7C2"
					( Origin gPackager )
				)
				( attribute "CDS_SEC" "1"
					( Origin gPackager )
				)
				( attribute "LOCATION" "Y7C2"
					( Origin gFrontEnd )
				)
				( attribute "MATERIAL" "IC"
					( Origin gFrontEnd )
				)
				( attribute "PACK_TYPE" "SM"
					( Origin gFrontEnd )
				)
				( attribute "PART_NUMBER" "C13544-023"
					( Origin gFrontEnd )
				)
				( attribute "PHYS_PAGE" "114"
					( Origin gFrontEnd )
				)
				( attribute "ROOM" "SB"
					( Origin gFrontEnd )
				)
				( attribute "ROT" "0"
					( Origin gFrontEnd )
				)
				( attribute "SEC" "1"
					( Origin gFrontEnd )
				)
				( attribute "SEC_TYPE" "SM"
					( Origin gFrontEnd )
				)
				( attribute "VALUE" "32.768KHZ"
					( Origin gFrontEnd )
				)
				( attribute "VER" "1"
					( Origin gFrontEnd )
				)
				( attribute "XY" "(-25,125)"
					( Origin gFrontEnd )
				)
				( attribute "CHIPS_PART_NAME" "CRYSTAL"
					( Origin gPackager )
				)
				( attribute "CDS_PART_NAME" "CRYSTAL_SM-32.768KHZ,IC,C13544A"
					( Origin gPackager )
				)
				( objectStatus "Y7C2" )
				( pin "a"
					( attribute "PN" "1"
						( Origin gPackager )
					)
					( objectStatus "Y7C2.1" )
				)
				( pin "b"
					( attribute "PN" "2"
						( Origin gPackager )
					)
					( objectStatus "Y7C2.2" )
				)
			)
			( gate "@baseboard_fab2_lib.baseboard_fab2(sch_1):page114_i56"
				( attribute "CDS_LIB" "mstr_discrete"
					( Origin gPackager )
				)
				( attribute "CDS_LOCATION" "C7C13"
					( Origin gPackager )
				)
				( attribute "CDS_SEC" "1"
					( Origin gPackager )
				)
				( attribute "LOCATION" "C7C13"
					( Origin gFrontEnd )
				)
				( attribute "MATERIAL" "C0G"
					( Origin gFrontEnd )
				)
				( attribute "PACK_TYPE" "0402LF"
					( Origin gFrontEnd )
				)
				( attribute "PART_NUMBER" "A36095-042"
					( Origin gFrontEnd )
				)
				( attribute "PHYS_PAGE" "114"
					( Origin gFrontEnd )
				)
				( attribute "ROOM" "SB"
					( Origin gFrontEnd )
				)
				( attribute "ROT" "0"
					( Origin gFrontEnd )
				)
				( attribute "SEC" "1"
					( Origin gPackager )
				)
				( attribute "TOLERANCE" "5%"
					( Origin gFrontEnd )
				)
				( attribute "VALUE" "18PF"
					( Origin gFrontEnd )
				)
				( attribute "VER" "1"
					( Origin gFrontEnd )
				)
				( attribute "VOLTAGE" "50V"
					( Units "uVoltage" "V" 1.000000)
					( Origin gFrontEnd )
				)
				( attribute "XY" "(-275,-225)"
					( Origin gFrontEnd )
				)
				( attribute "CHIPS_PART_NAME" "CAP"
					( Origin gPackager )
				)
				( attribute "CDS_PART_NAME" "CAP_0402LF-18PF,50V,5%,C0G,A36A"
					( Origin gPackager )
				)
				( objectStatus "C7C13" )
				( pin "a"
					( attribute "PN" "1"
						( Origin gPackager )
					)
					( objectStatus "C7C13.1" )
				)
				( pin "b"
					( attribute "PN" "2"
						( Origin gPackager )
					)
					( objectStatus "C7C13.2" )
				)
			)
			( gate "@baseboard_fab2_lib.baseboard_fab2(sch_1):page114_i110"
				( attribute "CDS_LIB" "mstr_discrete"
					( Origin gPackager )
				)
				( attribute "CDS_LOCATION" "R8B20"
					( Origin gPackager )
				)
				( attribute "CDS_SEC" "1"
					( Origin gPackager )
				)
				( attribute "LOCATION" "R8B20"
					( Origin gFrontEnd )
				)
				( attribute "MATERIAL" "CHIP"
					( Origin gFrontEnd )
				)
				( attribute "PACK_TYPE" "0402"
					( Origin gFrontEnd )
				)
				( attribute "PART_NUMBER" "G21796-066"
					( Origin gFrontEnd )
				)
				( attribute "PHYS_PAGE" "114"
					( Origin gFrontEnd )
				)
				( attribute "ROOM" "SB"
					( Origin gFrontEnd )
				)
				( attribute "ROT" "0"
					( Origin gFrontEnd )
				)
				( attribute "SEC" "1"
					( Origin gFrontEnd )
				)
				( attribute "SEC_TYPE" "0402"
					( Origin gFrontEnd )
				)
				( attribute "TOLERANCE" "1%"
					( Origin gFrontEnd )
				)
				( attribute "VALUE" "10.0"
					( Origin gFrontEnd )
				)
				( attribute "VER" "1"
					( Origin gFrontEnd )
				)
				( attribute "WATTAGE" "1/16W"
					( Origin gFrontEnd )
				)
				( attribute "XY" "(2300,1350)"
					( Origin gFrontEnd )
				)
				( attribute "CHIPS_PART_NAME" "RES"
					( Origin gPackager )
				)
				( attribute "CDS_PART_NAME" "RES_0402-10.0,1%,1/16W,CHIP,G2A"
					( Origin gPackager )
				)
				( objectStatus "R8B20" )
				( pin "a"
					( attribute "PN" "1"
						( Origin gPackager )
					)
					( objectStatus "R8B20.1" )
				)
				( pin "b"
					( attribute "PN" "2"
						( Origin gPackager )
					)
					( objectStatus "R8B20.2" )
				)
			)
			( gate "@baseboard_fab2_lib.baseboard_fab2(sch_1):page114_i124"
				( attribute "CDS_LIB" "mstr_discrete"
					( Origin gPackager )
				)
				( attribute "CDS_LOCATION" "R8B21"
					( Origin gPackager )
				)
				( attribute "CDS_SEC" "1"
					( Origin gPackager )
				)
				( attribute "LOCATION" "R8B21"
					( Origin gFrontEnd )
				)
				( attribute "MATERIAL" "EMPTY"
					( Origin gFrontEnd )
				)
				( attribute "PACK_TYPE" "0402"
					( Origin gFrontEnd )
				)
				( attribute "PART_NUMBER" "G21796-047"
					( Origin gFrontEnd )
				)
				( attribute "PHYS_PAGE" "114"
					( Origin gFrontEnd )
				)
				( attribute "ROOM" "SB"
					( Origin gFrontEnd )
				)
				( attribute "ROT" "0"
					( Origin gFrontEnd )
				)
				( attribute "SEC" "1"
					( Origin gFrontEnd )
				)
				( attribute "SEC_TYPE" "0402"
					( Origin gFrontEnd )
				)
				( attribute "TOLERANCE" "1%"
					( Origin gFrontEnd )
				)
				( attribute "VALUE" "49.9"
					( Origin gFrontEnd )
				)
				( attribute "VER" "2"
					( Origin gFrontEnd )
				)
				( attribute "WATTAGE" "1/16W"
					( Origin gFrontEnd )
				)
				( attribute "XY" "(2900,1100)"
					( Origin gFrontEnd )
				)
				( attribute "CHIPS_PART_NAME" "RES"
					( Origin gPackager )
				)
				( attribute "CDS_PART_NAME" "RES_0402-49.9,1%,1/16W,EMPTY,GA"
					( Origin gPackager )
				)
				( objectStatus "R8B21" )
				( pin "a"
					( attribute "PN" "1"
						( Origin gPackager )
					)
					( objectStatus "R8B21.1" )
				)
				( pin "b"
					( attribute "PN" "2"
						( Origin gPackager )
					)
					( objectStatus "R8B21.2" )
				)
			)
			( gate "@baseboard_fab2_lib.baseboard_fab2(sch_1):page114_i141"
				( attribute "BOM_COST" "SB"
					( Origin gFrontEnd )
				)
				( attribute "CDS_LIB" "mstr_discrete"
					( Origin gPackager )
				)
				( attribute "CDS_LOCATION" "R7C2"
					( Origin gPackager )
				)
				( attribute "CDS_SEC" "1"
					( Origin gPackager )
				)
				( attribute "LOCATION" "R7C2"
					( Origin gFrontEnd )
				)
				( attribute "MATERIAL" "EMPTY"
					( Origin gFrontEnd )
				)
				( attribute "PACK_TYPE" "0402"
					( Origin gFrontEnd )
				)
				( attribute "PART_NUMBER" "G21497-005"
					( Origin gFrontEnd )
				)
				( attribute "PHYS_PAGE" "114"
					( Origin gFrontEnd )
				)
				( attribute "ROOM" "SB"
					( Origin gFrontEnd )
				)
				( attribute "ROT" "0"
					( Origin gFrontEnd )
				)
				( attribute "SEC" "1"
					( Origin gFrontEnd )
				)
				( attribute "SEC_TYPE" "0402"
					( Origin gFrontEnd )
				)
				( attribute "TOLERANCE" "5%"
					( Origin gFrontEnd )
				)
				( attribute "VALUE" "0.0"
					( Origin gFrontEnd )
				)
				( attribute "VER" "1"
					( Origin gFrontEnd )
				)
				( attribute "WATTAGE" "1/16W"
					( Origin gFrontEnd )
				)
				( attribute "XY" "(-1175,2800)"
					( Origin gFrontEnd )
				)
				( attribute "CHIPS_PART_NAME" "RES"
					( Origin gPackager )
				)
				( attribute "CDS_PART_NAME" "RES_0402-0.0,5%,1/16W,EMPTY,G2A"
					( Origin gPackager )
				)
				( objectStatus "R7C2" )
				( pin "a"
					( attribute "PN" "1"
						( Origin gPackager )
					)
					( objectStatus "R7C2.1" )
				)
				( pin "b"
					( attribute "PN" "2"
						( Origin gPackager )
					)
					( objectStatus "R7C2.2" )
				)
			)
			( gate "@baseboard_fab2_lib.baseboard_fab2(sch_1):page114_i142"
				( attribute "BOM_COST" "SB"
					( Origin gFrontEnd )
				)
				( attribute "CDS_LIB" "mstr_discrete"
					( Origin gPackager )
				)
				( attribute "CDS_LOCATION" "R7C4"
					( Origin gPackager )
				)
				( attribute "CDS_SEC" "1"
					( Origin gPackager )
				)
				( attribute "LOCATION" "R7C4"
					( Origin gFrontEnd )
				)
				( attribute "MATERIAL" "EMPTY"
					( Origin gFrontEnd )
				)
				( attribute "PACK_TYPE" "0402"
					( Origin gFrontEnd )
				)
				( attribute "PART_NUMBER" "G21497-005"
					( Origin gFrontEnd )
				)
				( attribute "PHYS_PAGE" "114"
					( Origin gFrontEnd )
				)
				( attribute "ROOM" "SB"
					( Origin gFrontEnd )
				)
				( attribute "ROT" "0"
					( Origin gFrontEnd )
				)
				( attribute "SEC" "1"
					( Origin gFrontEnd )
				)
				( attribute "SEC_TYPE" "0402"
					( Origin gFrontEnd )
				)
				( attribute "TOLERANCE" "5%"
					( Origin gFrontEnd )
				)
				( attribute "VALUE" "0.0"
					( Origin gFrontEnd )
				)
				( attribute "VER" "1"
					( Origin gFrontEnd )
				)
				( attribute "WATTAGE" "1/16W"
					( Origin gFrontEnd )
				)
				( attribute "XY" "(-1625,2850)"
					( Origin gFrontEnd )
				)
				( attribute "CHIPS_PART_NAME" "RES"
					( Origin gPackager )
				)
				( attribute "CDS_PART_NAME" "RES_0402-0.0,5%,1/16W,EMPTY,G2A"
					( Origin gPackager )
				)
				( objectStatus "R7C4" )
				( pin "a"
					( attribute "PN" "1"
						( Origin gPackager )
					)
					( objectStatus "R7C4.1" )
				)
				( pin "b"
					( attribute "PN" "2"
						( Origin gPackager )
					)
					( objectStatus "R7C4.2" )
				)
			)
			( gate "@baseboard_fab2_lib.baseboard_fab2(sch_1):page114_i149"
				( attribute "CDS_LIB" "mstr_discrete"
					( Origin gPackager )
				)
				( attribute "CDS_LOCATION" "R3N1"
					( Origin gPackager )
				)
				( attribute "CDS_SEC" "1"
					( Origin gPackager )
				)
				( attribute "LOCATION" "R3N1"
					( Origin gFrontEnd )
				)
				( attribute "MATERIAL" "CHIP"
					( Origin gFrontEnd )
				)
				( attribute "PACK_TYPE" "0402"
					( Origin gFrontEnd )
				)
				( attribute "PART_NUMBER" "G21796-276"
					( Origin gFrontEnd )
				)
				( attribute "PHYS_PAGE" "114"
					( Origin gFrontEnd )
				)
				( attribute "ROOM" "SB"
					( Origin gFrontEnd )
				)
				( attribute "ROT" "0"
					( Origin gFrontEnd )
				)
				( attribute "SEC" "1"
					( Origin gPackager )
				)
				( attribute "TOLERANCE" "1.0%"
					( Origin gFrontEnd )
				)
				( attribute "VALUE" "169"
					( Origin gFrontEnd )
				)
				( attribute "VER" "2"
					( Origin gFrontEnd )
				)
				( attribute "WATTAGE" "1/16W"
					( Origin gFrontEnd )
				)
				( attribute "XY" "(-2950,2750)"
					( Origin gFrontEnd )
				)
				( attribute "CHIPS_PART_NAME" "RES"
					( Origin gPackager )
				)
				( attribute "CDS_PART_NAME" "RES_0402-169,1.0%,1/16W,CHIP,GA"
					( Origin gPackager )
				)
				( objectStatus "R3N1" )
				( pin "a"
					( attribute "PN" "1"
						( Origin gPackager )
					)
					( objectStatus "R3N1.1" )
				)
				( pin "b"
					( attribute "PN" "2"
						( Origin gPackager )
					)
					( objectStatus "R3N1.2" )
				)
			)
			( gate "@baseboard_fab2_lib.baseboard_fab2(sch_1):page115_i74"
				( attribute "BOM_COST" "SB"
					( Origin gFrontEnd )
				)
				( attribute "CDS_LIB" "mstr_u_proc"
					( Origin gPackager )
				)
				( attribute "CDS_LOCATION" "U7C1"
					( Origin gPackager )
				)
				( attribute "CDS_SEC" "2"
					( Origin gPackager )
				)
				( attribute "LOCATION" "U7C1"
					( Origin gFrontEnd )
				)
				( attribute "MATERIAL" "IC"
					( Origin gFrontEnd )
				)
				( attribute "PACK_TYPE" "BGA1"
					( Origin gFrontEnd )
				)
				( attribute "PART_NUMBER" "H91415-002"
					( Origin gFrontEnd )
				)
				( attribute "PHYS_PAGE" "115"
					( Origin gFrontEnd )
				)
				( attribute "ROOM" "SB"
					( Origin gFrontEnd )
				)
				( attribute "ROT" "0"
					( Origin gFrontEnd )
				)
				( attribute "SEC" "2"
					( Origin gFrontEnd )
				)
				( attribute "SEC_TYPE" "BGA1"
					( Origin gFrontEnd )
				)
				( attribute "VER" "2"
					( Origin gFrontEnd )
				)
				( attribute "XY" "(-4000,2500)"
					( Origin gFrontEnd )
				)
				( attribute "CHIPS_PART_NAME" "LBG_CORE_QAT_EXT_D"
					( Origin gPackager )
				)
				( attribute "CDS_PART_NAME" "LBG_CORE_QAT_EXT_D_BGA1-IC,H91A"
					( Origin gPackager )
				)
				( objectStatus "U7C1" )
				( pin "rsvd(55)"
					( attribute "PN" "BN68"
						( Origin gPackager )
					)
					( objectStatus "U7C1.BN68" )
				)
				( pin "usb2_comp"
					( attribute "PN" "BN70"
						( Origin gPackager )
					)
					( objectStatus "U7C1.BN70" )
				)
				( pin "usb2_vbus"
					( attribute "PN" "BR67"
						( Origin gPackager )
					)
					( objectStatus "U7C1.BR67" )
				)
				( pin "usb2n_1"
					( attribute "PN" "BY60"
						( Origin gPackager )
					)
					( objectStatus "U7C1.BY60" )
				)
				( pin "usb2n_2"
					( attribute "PN" "CA61"
						( Origin gPackager )
					)
					( objectStatus "U7C1.CA61" )
				)
				( pin "usb2n_3"
					( attribute "PN" "CA59"
						( Origin gPackager )
					)
					( objectStatus "U7C1.CA59" )
				)
				( pin "usb2n_4"
					( attribute "PN" "BY62"
						( Origin gPackager )
					)
					( objectStatus "U7C1.BY62" )
				)
				( pin "usb2n_5"
					( attribute "PN" "BY58"
						( Origin gPackager )
					)
					( objectStatus "U7C1.BY58" )
				)
				( pin "usb2n_6"
					( attribute "PN" "CA63"
						( Origin gPackager )
					)
					( objectStatus "U7C1.CA63" )
				)
				( pin "usb2n_7"
					( attribute "PN" "CA57"
						( Origin gPackager )
					)
					( objectStatus "U7C1.CA57" )
				)
				( pin "usb2n_8"
					( attribute "PN" "BY64"
						( Origin gPackager )
					)
					( objectStatus "U7C1.BY64" )
				)
				( pin "usb2n_9"
					( attribute "PN" "BY55"
						( Origin gPackager )
					)
					( objectStatus "U7C1.BY55" )
				)
				( pin "usb2n_10"
					( attribute "PN" "BW65"
						( Origin gPackager )
					)
					( objectStatus "U7C1.BW65" )
				)
				( pin "usb2n_11"
					( attribute "PN" "CA54"
						( Origin gPackager )
					)
					( objectStatus "U7C1.CA54" )
				)
				( pin "usb2n_12"
					( attribute "PN" "BW67"
						( Origin gPackager )
					)
					( objectStatus "U7C1.BW67" )
				)
				( pin "usb2n_13"
					( attribute "PN" "BY53"
						( Origin gPackager )
					)
					( objectStatus "U7C1.BY53" )
				)
				( pin "usb2n_14"
					( attribute "PN" "BW68"
						( Origin gPackager )
					)
					( objectStatus "U7C1.BW68" )
				)
				( pin "usb2p_1"
					( attribute "PN" "BV60"
						( Origin gPackager )
					)
					( objectStatus "U7C1.BV60" )
				)
				( pin "usb2p_2"
					( attribute "PN" "BW61"
						( Origin gPackager )
					)
					( objectStatus "U7C1.BW61" )
				)
				( pin "usb2p_3"
					( attribute "PN" "BW59"
						( Origin gPackager )
					)
					( objectStatus "U7C1.BW59" )
				)
				( pin "usb2p_4"
					( attribute "PN" "BV62"
						( Origin gPackager )
					)
					( objectStatus "U7C1.BV62" )
				)
				( pin "usb2p_5"
					( attribute "PN" "BV58"
						( Origin gPackager )
					)
					( objectStatus "U7C1.BV58" )
				)
				( pin "usb2p_6"
					( attribute "PN" "BW63"
						( Origin gPackager )
					)
					( objectStatus "U7C1.BW63" )
				)
				( pin "usb2p_7"
					( attribute "PN" "BW57"
						( Origin gPackager )
					)
					( objectStatus "U7C1.BW57" )
				)
				( pin "usb2p_8"
					( attribute "PN" "BV64"
						( Origin gPackager )
					)
					( objectStatus "U7C1.BV64" )
				)
				( pin "usb2p_9"
					( attribute "PN" "BV55"
						( Origin gPackager )
					)
					( objectStatus "U7C1.BV55" )
				)
				( pin "usb2p_10"
					( attribute "PN" "BU65"
						( Origin gPackager )
					)
					( objectStatus "U7C1.BU65" )
				)
				( pin "usb2p_11"
					( attribute "PN" "BW54"
						( Origin gPackager )
					)
					( objectStatus "U7C1.BW54" )
				)
				( pin "usb2p_12"
					( attribute "PN" "BV66"
						( Origin gPackager )
					)
					( objectStatus "U7C1.BV66" )
				)
				( pin "usb2p_13"
					( attribute "PN" "BV53"
						( Origin gPackager )
					)
					( objectStatus "U7C1.BV53" )
				)
				( pin "usb2p_14"
					( attribute "PN" "BU67"
						( Origin gPackager )
					)
					( objectStatus "U7C1.BU67" )
				)
				( pin "usb3_1_rxn"
					( attribute "PN" "BK71"
						( Origin gPackager )
					)
					( objectStatus "U7C1.BK71" )
				)
				( pin "usb3_1_rxp"
					( attribute "PN" "BK69"
						( Origin gPackager )
					)
					( objectStatus "U7C1.BK69" )
				)
				( pin "usb3_1_txn"
					( attribute "PN" "BL52"
						( Origin gPackager )
					)
					( objectStatus "U7C1.BL52" )
				)
				( pin "usb3_1_txp"
					( attribute "PN" "BK54"
						( Origin gPackager )
					)
					( objectStatus "U7C1.BK54" )
				)
				( pin "usb3_2_rxn"
					( attribute "PN" "BJ72"
						( Origin gPackager )
					)
					( objectStatus "U7C1.BJ72" )
				)
				( pin "usb3_2_rxp"
					( attribute "PN" "BJ70"
						( Origin gPackager )
					)
					( objectStatus "U7C1.BJ70" )
				)
				( pin "usb3_2_txn"
					( attribute "PN" "BL56"
						( Origin gPackager )
					)
					( objectStatus "U7C1.BL56" )
				)
				( pin "usb3_2_txp"
					( attribute "PN" "BJ56"
						( Origin gPackager )
					)
					( objectStatus "U7C1.BJ56" )
				)
				( pin "usb3_3_rxn"
					( attribute "PN" "BH71"
						( Origin gPackager )
					)
					( objectStatus "U7C1.BH71" )
				)
				( pin "usb3_3_rxp"
					( attribute "PN" "BH69"
						( Origin gPackager )
					)
					( objectStatus "U7C1.BH69" )
				)
				( pin "usb3_3_txn"
					( attribute "PN" "BM54"
						( Origin gPackager )
					)
					( objectStatus "U7C1.BM54" )
				)
				( pin "usb3_3_txp"
					( attribute "PN" "BN56"
						( Origin gPackager )
					)
					( objectStatus "U7C1.BN56" )
				)
				( pin "usb3_4_rxn"
					( attribute "PN" "BF72"
						( Origin gPackager )
					)
					( objectStatus "U7C1.BF72" )
				)
				( pin "usb3_4_rxp"
					( attribute "PN" "BF70"
						( Origin gPackager )
					)
					( objectStatus "U7C1.BF70" )
				)
				( pin "usb3_4_txn"
					( attribute "PN" "BH58"
						( Origin gPackager )
					)
					( objectStatus "U7C1.BH58" )
				)
				( pin "usb3_4_txp"
					( attribute "PN" "BG56"
						( Origin gPackager )
					)
					( objectStatus "U7C1.BG56" )
				)
				( pin "usb3_5_rxn"
					( attribute "PN" "BE71"
						( Origin gPackager )
					)
					( objectStatus "U7C1.BE71" )
				)
				( pin "usb3_5_rxp"
					( attribute "PN" "BE69"
						( Origin gPackager )
					)
					( objectStatus "U7C1.BE69" )
				)
				( pin "usb3_5_txn"
					( attribute "PN" "BK58"
						( Origin gPackager )
					)
					( objectStatus "U7C1.BK58" )
				)
				( pin "usb3_5_txp"
					( attribute "PN" "BJ59"
						( Origin gPackager )
					)
					( objectStatus "U7C1.BJ59" )
				)
				( pin "usb3_6_rxn"
					( attribute "PN" "BD72"
						( Origin gPackager )
					)
					( objectStatus "U7C1.BD72" )
				)
				( pin "usb3_6_rxp"
					( attribute "PN" "BD70"
						( Origin gPackager )
					)
					( objectStatus "U7C1.BD70" )
				)
				( pin "usb3_6_txn"
					( attribute "PN" "BL59"
						( Origin gPackager )
					)
					( objectStatus "U7C1.BL59" )
				)
				( pin "usb3_6_txp"
					( attribute "PN" "BM61"
						( Origin gPackager )
					)
					( objectStatus "U7C1.BM61" )
				)
			)
			( gate "@baseboard_fab2_lib.baseboard_fab2(sch_1):page115_i90"
				( attribute "CDS_LIB" "mstr_discrete"
					( Origin gPackager )
				)
				( attribute "CDS_LOCATION" "R8B9"
					( Origin gPackager )
				)
				( attribute "CDS_SEC" "1"
					( Origin gPackager )
				)
				( attribute "LOCATION" "R8B9"
					( Origin gFrontEnd )
				)
				( attribute "MATERIAL" "CHIP"
					( Origin gFrontEnd )
				)
				( attribute "PACK_TYPE" "0402"
					( Origin gFrontEnd )
				)
				( attribute "PART_NUMBER" "G21796-341"
					( Origin gFrontEnd )
				)
				( attribute "PHYS_PAGE" "115"
					( Origin gFrontEnd )
				)
				( attribute "ROOM" "SB"
					( Origin gFrontEnd )
				)
				( attribute "ROT" "0"
					( Origin gFrontEnd )
				)
				( attribute "SEC" "1"
					( Origin gFrontEnd )
				)
				( attribute "SEC_TYPE" "0402"
					( Origin gFrontEnd )
				)
				( attribute "TOLERANCE" "1%"
					( Origin gFrontEnd )
				)
				( attribute "VALUE" "113"
					( Origin gFrontEnd )
				)
				( attribute "VER" "2"
					( Origin gFrontEnd )
				)
				( attribute "WATTAGE" "1/16W"
					( Origin gFrontEnd )
				)
				( attribute "XY" "(-5750,1775)"
					( Origin gFrontEnd )
				)
				( attribute "CHIPS_PART_NAME" "RES"
					( Origin gPackager )
				)
				( attribute "CDS_PART_NAME" "RES_0402-113,1%,1/16W,CHIP,G21A"
					( Origin gPackager )
				)
				( objectStatus "R8B9" )
				( pin "a"
					( attribute "PN" "1"
						( Origin gPackager )
					)
					( objectStatus "R8B9.1" )
				)
				( pin "b"
					( attribute "PN" "2"
						( Origin gPackager )
					)
					( objectStatus "R8B9.2" )
				)
			)
			( gate "@baseboard_fab2_lib.baseboard_fab2(sch_1):page115_i114"
				( attribute "CDS_LIB" "mstr_discrete"
					( Origin gPackager )
				)
				( attribute "CDS_LOCATION" "R8B32"
					( Origin gPackager )
				)
				( attribute "CDS_SEC" "1"
					( Origin gPackager )
				)
				( attribute "LOCATION" "R8B32"
					( Origin gFrontEnd )
				)
				( attribute "MATERIAL" "CHIP"
					( Origin gFrontEnd )
				)
				( attribute "PACK_TYPE" "0402"
					( Origin gFrontEnd )
				)
				( attribute "PART_NUMBER" "G21796-016"
					( Origin gFrontEnd )
				)
				( attribute "PHYS_PAGE" "115"
					( Origin gFrontEnd )
				)
				( attribute "ROT" "0"
					( Origin gFrontEnd )
				)
				( attribute "SEC" "1"
					( Origin gFrontEnd )
				)
				( attribute "SEC_TYPE" "0402"
					( Origin gFrontEnd )
				)
				( attribute "TOLERANCE" "1%"
					( Origin gFrontEnd )
				)
				( attribute "VALUE" "10.0K"
					( Origin gFrontEnd )
				)
				( attribute "VER" "2"
					( Origin gFrontEnd )
				)
				( attribute "WATTAGE" "1/16W"
					( Origin gFrontEnd )
				)
				( attribute "XY" "(-5425,1775)"
					( Origin gFrontEnd )
				)
				( attribute "CHIPS_PART_NAME" "RES"
					( Origin gPackager )
				)
				( attribute "CDS_PART_NAME" "RES_0402-10.0K,1%,1/16W,CHIP,GA"
					( Origin gPackager )
				)
				( objectStatus "R8B32" )
				( pin "a"
					( attribute "PN" "1"
						( Origin gPackager )
					)
					( objectStatus "R8B32.1" )
				)
				( pin "b"
					( attribute "PN" "2"
						( Origin gPackager )
					)
					( objectStatus "R8B32.2" )
				)
			)
			( gate "@baseboard_fab2_lib.baseboard_fab2(sch_1):page116_i108"
				( attribute "CDS_LIB" "mstr_discrete"
					( Origin gPackager )
				)
				( attribute "CDS_LOCATION" "R3M11"
					( Origin gPackager )
				)
				( attribute "CDS_SEC" "1"
					( Origin gPackager )
				)
				( attribute "LOCATION" "R3M11"
					( Origin gFrontEnd )
				)
				( attribute "MATERIAL" "CHIP"
					( Origin gFrontEnd )
				)
				( attribute "NO_XNET_CONNECTION" "1"
					( Origin gFrontEnd )
				)
				( attribute "PACK_TYPE" "0402"
					( Origin gFrontEnd )
				)
				( attribute "PART_NUMBER" "G21796-017"
					( Origin gFrontEnd )
				)
				( attribute "PHYS_PAGE" "116"
					( Origin gFrontEnd )
				)
				( attribute "ROOM" "SB"
					( Origin gFrontEnd )
				)
				( attribute "ROT" "2"
					( Origin gFrontEnd )
				)
				( attribute "SEC" "1"
					( Origin gFrontEnd )
				)
				( attribute "SEC_TYPE" "0402"
					( Origin gFrontEnd )
				)
				( attribute "TOLERANCE" "1%"
					( Origin gFrontEnd )
				)
				( attribute "VALUE" "100.0"
					( Origin gFrontEnd )
				)
				( attribute "VER" "2"
					( Origin gFrontEnd )
				)
				( attribute "WATTAGE" "1/16W"
					( Origin gFrontEnd )
				)
				( attribute "XY" "(-7550,2150)"
					( Origin gFrontEnd )
				)
				( attribute "CHIPS_PART_NAME" "RES"
					( Origin gPackager )
				)
				( attribute "CDS_PART_NAME" "RES_0402-100.0,1%,1/16W,CHIP,GA"
					( Origin gPackager )
				)
				( objectStatus "R3M11" )
				( pin "a"
					( attribute "PN" "1"
						( Origin gPackager )
					)
					( objectStatus "R3M11.1" )
				)
				( pin "b"
					( attribute "PN" "2"
						( Origin gPackager )
					)
					( objectStatus "R3M11.2" )
				)
			)
			( gate "@baseboard_fab2_lib.baseboard_fab2(sch_1):page116_i181"
				( attribute "CDS_LIB" "mstr_discrete"
					( Origin gPackager )
				)
				( attribute "CDS_LOCATION" "R3M12"
					( Origin gPackager )
				)
				( attribute "CDS_SEC" "1"
					( Origin gPackager )
				)
				( attribute "LOCATION" "R3M12"
					( Origin gFrontEnd )
				)
				( attribute "MATERIAL" "CHIP"
					( Origin gFrontEnd )
				)
				( attribute "NO_XNET_CONNECTION" "1"
					( Origin gFrontEnd )
				)
				( attribute "PACK_TYPE" "0402"
					( Origin gFrontEnd )
				)
				( attribute "PART_NUMBER" "G21796-017"
					( Origin gFrontEnd )
				)
				( attribute "PHYS_PAGE" "116"
					( Origin gFrontEnd )
				)
				( attribute "ROOM" "SB"
					( Origin gFrontEnd )
				)
				( attribute "ROT" "2"
					( Origin gFrontEnd )
				)
				( attribute "SEC" "1"
					( Origin gFrontEnd )
				)
				( attribute "SEC_TYPE" "0402"
					( Origin gFrontEnd )
				)
				( attribute "TOLERANCE" "1%"
					( Origin gFrontEnd )
				)
				( attribute "VALUE" "100.0"
					( Origin gFrontEnd )
				)
				( attribute "VER" "2"
					( Origin gFrontEnd )
				)
				( attribute "WATTAGE" "1/16W"
					( Origin gFrontEnd )
				)
				( attribute "XY" "(-7125,2150)"
					( Origin gFrontEnd )
				)
				( attribute "CHIPS_PART_NAME" "RES"
					( Origin gPackager )
				)
				( attribute "CDS_PART_NAME" "RES_0402-100.0,1%,1/16W,CHIP,GA"
					( Origin gPackager )
				)
				( objectStatus "R3M12" )
				( pin "a"
					( attribute "PN" "1"
						( Origin gPackager )
					)
					( objectStatus "R3M12.1" )
				)
				( pin "b"
					( attribute "PN" "2"
						( Origin gPackager )
					)
					( objectStatus "R3M12.2" )
				)
			)
			( gate "@baseboard_fab2_lib.baseboard_fab2(sch_1):page116_i182"
				( attribute "CDS_LIB" "dev_discrete"
					( Origin gPackager )
				)
				( attribute "CDS_LOCATION" "C2M4"
					( Origin gPackager )
				)
				( attribute "CDS_SEC" "1"
					( Origin gPackager )
				)
				( attribute "LOCATION" "C2M4"
					( Origin gFrontEnd )
				)
				( attribute "MATERIAL" "EMPTY"
					( Origin gFrontEnd )
				)
				( attribute "PACK_TYPE" "0402V"
					( Origin gFrontEnd )
				)
				( attribute "PART_NUMBER" "A36096-030"
					( Origin gFrontEnd )
				)
				( attribute "PHYS_PAGE" "116"
					( Origin gFrontEnd )
				)
				( attribute "ROOM" "SB"
					( Origin gFrontEnd )
				)
				( attribute "ROT" "0"
					( Origin gFrontEnd )
				)
				( attribute "SEC" "1"
					( Origin gFrontEnd )
				)
				( attribute "SEC_TYPE" "0402V"
					( Origin gFrontEnd )
				)
				( attribute "TOLERANCE" "10%"
					( Origin gFrontEnd )
				)
				( attribute "VALUE" "0.1UF"
					( Origin gFrontEnd )
				)
				( attribute "VER" "2"
					( Origin gFrontEnd )
				)
				( attribute "VOLTAGE" "16V"
					( Units "uVoltage" "V" 1.000000)
					( Origin gFrontEnd )
				)
				( attribute "XY" "(-1725,2650)"
					( Origin gFrontEnd )
				)
				( attribute "CHIPS_PART_NAME" "CAP_A"
					( Origin gPackager )
				)
				( attribute "CDS_PART_NAME" "CAP_A_0402V-0.1UF,16V,10%,EMPTA"
					( Origin gPackager )
				)
				( objectStatus "C2M4" )
				( pin "a"
					( attribute "PN" "1"
						( Origin gPackager )
					)
					( objectStatus "C2M4.1" )
				)
				( pin "b"
					( attribute "PN" "2"
						( Origin gPackager )
					)
					( objectStatus "C2M4.2" )
				)
			)
			( gate "@baseboard_fab2_lib.baseboard_fab2(sch_1):page116_i183"
				( attribute "CDS_LIB" "dev_discrete"
					( Origin gPackager )
				)
				( attribute "CDS_LOCATION" "C2M3"
					( Origin gPackager )
				)
				( attribute "CDS_SEC" "1"
					( Origin gPackager )
				)
				( attribute "LOCATION" "C2M3"
					( Origin gFrontEnd )
				)
				( attribute "MATERIAL" "EMPTY"
					( Origin gFrontEnd )
				)
				( attribute "PACK_TYPE" "0402V"
					( Origin gFrontEnd )
				)
				( attribute "PART_NUMBER" "A36096-030"
					( Origin gFrontEnd )
				)
				( attribute "PHYS_PAGE" "116"
					( Origin gFrontEnd )
				)
				( attribute "ROOM" "SB"
					( Origin gFrontEnd )
				)
				( attribute "ROT" "0"
					( Origin gFrontEnd )
				)
				( attribute "SEC" "1"
					( Origin gFrontEnd )
				)
				( attribute "SEC_TYPE" "0402V"
					( Origin gFrontEnd )
				)
				( attribute "TOLERANCE" "10%"
					( Origin gFrontEnd )
				)
				( attribute "VALUE" "0.1UF"
					( Origin gFrontEnd )
				)
				( attribute "VER" "2"
					( Origin gFrontEnd )
				)
				( attribute "VOLTAGE" "16V"
					( Units "uVoltage" "V" 1.000000)
					( Origin gFrontEnd )
				)
				( attribute "XY" "(-1325,2600)"
					( Origin gFrontEnd )
				)
				( attribute "CHIPS_PART_NAME" "CAP_A"
					( Origin gPackager )
				)
				( attribute "CDS_PART_NAME" "CAP_A_0402V-0.1UF,16V,10%,EMPTA"
					( Origin gPackager )
				)
				( objectStatus "C2M3" )
				( pin "a"
					( attribute "PN" "1"
						( Origin gPackager )
					)
					( objectStatus "C2M3.1" )
				)
				( pin "b"
					( attribute "PN" "2"
						( Origin gPackager )
					)
					( objectStatus "C2M3.2" )
				)
			)
			( gate "@baseboard_fab2_lib.baseboard_fab2(sch_1):page116_i220"
				( attribute "BOM_COST" "SB"
					( Origin gFrontEnd )
				)
				( attribute "CDS_LIB" "mstr_u_proc"
					( Origin gPackager )
				)
				( attribute "CDS_LOCATION" "U7C1"
					( Origin gPackager )
				)
				( attribute "CDS_SEC" "3"
					( Origin gPackager )
				)
				( attribute "LOCATION" "U7C1"
					( Origin gFrontEnd )
				)
				( attribute "MATERIAL" "IC"
					( Origin gFrontEnd )
				)
				( attribute "PACK_TYPE" "BGA1"
					( Origin gFrontEnd )
				)
				( attribute "PART_NUMBER" "H91415-002"
					( Origin gFrontEnd )
				)
				( attribute "PHYS_PAGE" "116"
					( Origin gFrontEnd )
				)
				( attribute "ROOM" "SB"
					( Origin gFrontEnd )
				)
				( attribute "ROT" "0"
					( Origin gFrontEnd )
				)
				( attribute "SEC" "3"
					( Origin gFrontEnd )
				)
				( attribute "SEC_TYPE" "BGA1"
					( Origin gFrontEnd )
				)
				( attribute "VER" "3"
					( Origin gFrontEnd )
				)
				( attribute "XY" "(-4025,2850)"
					( Origin gFrontEnd )
				)
				( attribute "CHIPS_PART_NAME" "LBG_CORE_QAT_EXT_D"
					( Origin gPackager )
				)
				( attribute "CDS_PART_NAME" "LBG_CORE_QAT_EXT_D_BGA1-IC,H91A"
					( Origin gPackager )
				)
				( objectStatus "U7C1" )
				( pin "extclkn"
					( attribute "PN" "D66"
						( Origin gPackager )
					)
					( objectStatus "U7C1.D66" )
				)
				( pin "extclkp"
					( attribute "PN" "E67"
						( Origin gPackager )
					)
					( objectStatus "U7C1.E67" )
				)
				( pin "pcie4_gbe_rxn"
					( attribute "PN" "AN70"
						( Origin gPackager )
					)
					( objectStatus "U7C1.AN70" )
				)
				( pin "pcie4_gbe_rxp"
					( attribute "PN" "AN72"
						( Origin gPackager )
					)
					( objectStatus "U7C1.AN72" )
				)
				( pin "pcie4_gbe_txn"
					( attribute "PN" "BG66"
						( Origin gPackager )
					)
					( objectStatus "U7C1.BG66" )
				)
				( pin "pcie4_gbe_txp"
					( attribute "PN" "BJ66"
						( Origin gPackager )
					)
					( objectStatus "U7C1.BJ66" )
				)
				( pin "pcie5_gbe_rxn"
					( attribute "PN" "AM69"
						( Origin gPackager )
					)
					( objectStatus "U7C1.AM69" )
				)
				( pin "pcie5_gbe_rxp"
					( attribute "PN" "AM71"
						( Origin gPackager )
					)
					( objectStatus "U7C1.AM71" )
				)
				( pin "pcie5_gbe_txn"
					( attribute "PN" "BH65"
						( Origin gPackager )
					)
					( objectStatus "U7C1.BH65" )
				)
				( pin "pcie5_gbe_txp"
					( attribute "PN" "BJ63"
						( Origin gPackager )
					)
					( objectStatus "U7C1.BJ63" )
				)
				( pin "pcie6_ssata0_rxn"
					( attribute "PN" "BB63"
						( Origin gPackager )
					)
					( objectStatus "U7C1.BB63" )
				)
				( pin "pcie6_ssata0_rxp"
					( attribute "PN" "BD61"
						( Origin gPackager )
					)
					( objectStatus "U7C1.BD61" )
				)
				( pin "pcie6_ssata0_txn"
					( attribute "PN" "AJ70"
						( Origin gPackager )
					)
					( objectStatus "U7C1.AJ70" )
				)
				( pin "pcie6_ssata0_txp"
					( attribute "PN" "AJ72"
						( Origin gPackager )
					)
					( objectStatus "U7C1.AJ72" )
				)
				( pin "pcie7_ssata1_rxn"
					( attribute "PN" "AY59"
						( Origin gPackager )
					)
					( objectStatus "U7C1.AY59" )
				)
				( pin "pcie7_ssata1_rxp"
					( attribute "PN" "BA61"
						( Origin gPackager )
					)
					( objectStatus "U7C1.BA61" )
				)
				( pin "pcie7_ssata1_txn"
					( attribute "PN" "AH69"
						( Origin gPackager )
					)
					( objectStatus "U7C1.AH69" )
				)
				( pin "pcie7_ssata1_txp"
					( attribute "PN" "AH71"
						( Origin gPackager )
					)
					( objectStatus "U7C1.AH71" )
				)
				( pin "pcie8_ssata2_gbe_rxn"
					( attribute "PN" "BA65"
						( Origin gPackager )
					)
					( objectStatus "U7C1.BA65" )
				)
				( pin "pcie8_ssata2_gbe_rxp"
					( attribute "PN" "BD65"
						( Origin gPackager )
					)
					( objectStatus "U7C1.BD65" )
				)
				( pin "pcie8_ssata2_gbe_txn"
					( attribute "PN" "AF70"
						( Origin gPackager )
					)
					( objectStatus "U7C1.AF70" )
				)
				( pin "pcie8_ssata2_gbe_txp"
					( attribute "PN" "AF72"
						( Origin gPackager )
					)
					( objectStatus "U7C1.AF72" )
				)
				( pin "pcie9_ssata3_rxn"
					( attribute "PN" "AW65"
						( Origin gPackager )
					)
					( objectStatus "U7C1.AW65" )
				)
				( pin "pcie9_ssata3_rxp"
					( attribute "PN" "AY66"
						( Origin gPackager )
					)
					( objectStatus "U7C1.AY66" )
				)
				( pin "pcie9_ssata3_txn"
					( attribute "PN" "AE69"
						( Origin gPackager )
					)
					( objectStatus "U7C1.AE69" )
				)
				( pin "pcie9_ssata3_txp"
					( attribute "PN" "AE71"
						( Origin gPackager )
					)
					( objectStatus "U7C1.AE71" )
				)
				( pin "pcie10_ssata4_rxn"
					( attribute "PN" "AV63"
						( Origin gPackager )
					)
					( objectStatus "U7C1.AV63" )
				)
				( pin "pcie10_ssata4_rxp"
					( attribute "PN" "AU65"
						( Origin gPackager )
					)
					( objectStatus "U7C1.AU65" )
				)
				( pin "pcie10_ssata4_txn"
					( attribute "PN" "AD70"
						( Origin gPackager )
					)
					( objectStatus "U7C1.AD70" )
				)
				( pin "pcie10_ssata4_txp"
					( attribute "PN" "AD72"
						( Origin gPackager )
					)
					( objectStatus "U7C1.AD72" )
				)
				( pin "pcie11_ssata5_gbe_rxn"
					( attribute "PN" "AT66"
						( Origin gPackager )
					)
					( objectStatus "U7C1.AT66" )
				)
				( pin "pcie11_ssata5_gbe_rxp"
					( attribute "PN" "AV66"
						( Origin gPackager )
					)
					( objectStatus "U7C1.AV66" )
				)
				( pin "pcie11_ssata5_gbe_txn"
					( attribute "PN" "AC69"
						( Origin gPackager )
					)
					( objectStatus "U7C1.AC69" )
				)
				( pin "pcie11_ssata5_gbe_txp"
					( attribute "PN" "AC71"
						( Origin gPackager )
					)
					( objectStatus "U7C1.AC71" )
				)
				( pin "pcie12_up0_sata0_rxn"
					( attribute "PN" "AR61"
						( Origin gPackager )
					)
					( objectStatus "U7C1.AR61" )
				)
				( pin "pcie12_up0_sata0_rxp"
					( attribute "PN" "AT63"
						( Origin gPackager )
					)
					( objectStatus "U7C1.AT63" )
				)
				( pin "pcie12_up0_sata0_txn"
					( attribute "PN" "W69"
						( Origin gPackager )
					)
					( objectStatus "U7C1.W69" )
				)
				( pin "pcie12_up0_sata0_txp"
					( attribute "PN" "W71"
						( Origin gPackager )
					)
					( objectStatus "U7C1.W71" )
				)
				( pin "pcie13_up1_sata1_rxn"
					( attribute "PN" "AL66"
						( Origin gPackager )
					)
					( objectStatus "U7C1.AL66" )
				)
				( pin "pcie13_up1_sata1_rxp"
					( attribute "PN" "AN65"
						( Origin gPackager )
					)
					( objectStatus "U7C1.AN65" )
				)
				( pin "pcie13_up1_sata1_txn"
					( attribute "PN" "V70"
						( Origin gPackager )
					)
					( objectStatus "U7C1.V70" )
				)
				( pin "pcie13_up1_sata1_txp"
					( attribute "PN" "V72"
						( Origin gPackager )
					)
					( objectStatus "U7C1.V72" )
				)
				( pin "pcie14_up2_sata2_rxn"
					( attribute "PN" "AK65"
						( Origin gPackager )
					)
					( objectStatus "U7C1.AK65" )
				)
				( pin "pcie14_up2_sata2_rxp"
					( attribute "PN" "AJ63"
						( Origin gPackager )
					)
					( objectStatus "U7C1.AJ63" )
				)
				( pin "pcie14_up2_sata2_txn"
					( attribute "PN" "T69"
						( Origin gPackager )
					)
					( objectStatus "U7C1.T69" )
				)
				( pin "pcie14_up2_sata2_txp"
					( attribute "PN" "T71"
						( Origin gPackager )
					)
					( objectStatus "U7C1.T71" )
				)
				( pin "pcie15_up3_sata3_rxn"
					( attribute "PN" "AP63"
						( Origin gPackager )
					)
					( objectStatus "U7C1.AP63" )
				)
				( pin "pcie15_up3_sata3_rxp"
					( attribute "PN" "AL63"
						( Origin gPackager )
					)
					( objectStatus "U7C1.AL63" )
				)
				( pin "pcie15_up3_sata3_txn"
					( attribute "PN" "R70"
						( Origin gPackager )
					)
					( objectStatus "U7C1.R70" )
				)
				( pin "pcie15_up3_sata3_txp"
					( attribute "PN" "R72"
						( Origin gPackager )
					)
					( objectStatus "U7C1.R72" )
				)
				( pin "pcie16_up4_sata4_rxn"
					( attribute "PN" "AF65"
						( Origin gPackager )
					)
					( objectStatus "U7C1.AF65" )
				)
				( pin "pcie16_up4_sata4_rxp"
					( attribute "PN" "AH65"
						( Origin gPackager )
					)
					( objectStatus "U7C1.AH65" )
				)
				( pin "pcie16_up4_sata4_txn"
					( attribute "PN" "P69"
						( Origin gPackager )
					)
					( objectStatus "U7C1.P69" )
				)
				( pin "pcie16_up4_sata4_txp"
					( attribute "PN" "P71"
						( Origin gPackager )
					)
					( objectStatus "U7C1.P71" )
				)
				( pin "pcie17_up5_sata5_rxn"
					( attribute "PN" "AH61"
						( Origin gPackager )
					)
					( objectStatus "U7C1.AH61" )
				)
				( pin "pcie17_up5_sata5_rxp"
					( attribute "PN" "AG63"
						( Origin gPackager )
					)
					( objectStatus "U7C1.AG63" )
				)
				( pin "pcie17_up5_sata5_txn"
					( attribute "PN" "N70"
						( Origin gPackager )
					)
					( objectStatus "U7C1.N70" )
				)
				( pin "pcie17_up5_sata5_txp"
					( attribute "PN" "N72"
						( Origin gPackager )
					)
					( objectStatus "U7C1.N72" )
				)
				( pin "pcie18_up6_sata6_rxn"
					( attribute "PN" "AP59"
						( Origin gPackager )
					)
					( objectStatus "U7C1.AP59" )
				)
				( pin "pcie18_up6_sata6_rxp"
					( attribute "PN" "AN61"
						( Origin gPackager )
					)
					( objectStatus "U7C1.AN61" )
				)
				( pin "pcie18_up6_sata6_txn"
					( attribute "PN" "M69"
						( Origin gPackager )
					)
					( objectStatus "U7C1.M69" )
				)
				( pin "pcie18_up6_sata6_txp"
					( attribute "PN" "M71"
						( Origin gPackager )
					)
					( objectStatus "U7C1.M71" )
				)
				( pin "pcie19_up7_sata7_rxn"
					( attribute "PN" "AA61"
						( Origin gPackager )
					)
					( objectStatus "U7C1.AA61" )
				)
				( pin "pcie19_up7_sata7_rxp"
					( attribute "PN" "AD61"
						( Origin gPackager )
					)
					( objectStatus "U7C1.AD61" )
				)
				( pin "pcie19_up7_sata7_txn"
					( attribute "PN" "L70"
						( Origin gPackager )
					)
					( objectStatus "U7C1.L70" )
				)
				( pin "pcie19_up7_sata7_txp"
					( attribute "PN" "L72"
						( Origin gPackager )
					)
					( objectStatus "U7C1.L72" )
				)
				( pin "pcie_rcompn"
					( attribute "PN" "BD58"
						( Origin gPackager )
					)
					( objectStatus "U7C1.BD58" )
				)
				( pin "pcie_rcompp"
					( attribute "PN" "BB56"
						( Origin gPackager )
					)
					( objectStatus "U7C1.BB56" )
				)
				( pin "pcieup_rcompn"
					( attribute "PN" "AF58"
						( Origin gPackager )
					)
					( objectStatus "U7C1.AF58" )
				)
				( pin "pcieup_rcompp"
					( attribute "PN" "AH58"
						( Origin gPackager )
					)
					( objectStatus "U7C1.AH58" )
				)
				( pin "rsvd(47)"
					( attribute "PN" "AP69"
						( Origin gPackager )
					)
					( objectStatus "U7C1.AP69" )
				)
				( pin "rsvd(48)"
					( attribute "PN" "AP71"
						( Origin gPackager )
					)
					( objectStatus "U7C1.AP71" )
				)
				( pin "rsvd(49)"
					( attribute "PN" "G67"
						( Origin gPackager )
					)
					( objectStatus "U7C1.G67" )
				)
				( pin "rsvd(50)"
					( attribute "PN" "H69"
						( Origin gPackager )
					)
					( objectStatus "U7C1.H69" )
				)
				( pin "rsvd(51)"
					( attribute "PN" "AA69"
						( Origin gPackager )
					)
					( objectStatus "U7C1.AA69" )
				)
				( pin "rsvd(52)"
					( attribute "PN" "AA71"
						( Origin gPackager )
					)
					( objectStatus "U7C1.AA71" )
				)
				( pin "usb3_7_pcie0_rxn"
					( attribute "PN" "BA71"
						( Origin gPackager )
					)
					( objectStatus "U7C1.BA71" )
				)
				( pin "usb3_7_pcie0_rxp"
					( attribute "PN" "BA69"
						( Origin gPackager )
					)
					( objectStatus "U7C1.BA69" )
				)
				( pin "usb3_7_pcie0_txn"
					( attribute "PN" "BR61"
						( Origin gPackager )
					)
					( objectStatus "U7C1.BR61" )
				)
				( pin "usb3_7_pcie0_txp"
					( attribute "PN" "BN63"
						( Origin gPackager )
					)
					( objectStatus "U7C1.BN63" )
				)
				( pin "usb3_8_pcie1_rxn"
					( attribute "PN" "AY72"
						( Origin gPackager )
					)
					( objectStatus "U7C1.AY72" )
				)
				( pin "usb3_8_pcie1_rxp"
					( attribute "PN" "AY70"
						( Origin gPackager )
					)
					( objectStatus "U7C1.AY70" )
				)
				( pin "usb3_8_pcie1_txn"
					( attribute "PN" "BM65"
						( Origin gPackager )
					)
					( objectStatus "U7C1.BM65" )
				)
				( pin "usb3_8_pcie1_txp"
					( attribute "PN" "BR65"
						( Origin gPackager )
					)
					( objectStatus "U7C1.BR65" )
				)
				( pin "usb3_9_pcie2_rxn"
					( attribute "PN" "AW71"
						( Origin gPackager )
					)
					( objectStatus "U7C1.AW71" )
				)
				( pin "usb3_9_pcie2_rxp"
					( attribute "PN" "AW69"
						( Origin gPackager )
					)
					( objectStatus "U7C1.AW69" )
				)
				( pin "usb3_9_pcie2_txn"
					( attribute "PN" "BK65"
						( Origin gPackager )
					)
					( objectStatus "U7C1.BK65" )
				)
				( pin "usb3_9_pcie2_txp"
					( attribute "PN" "BL66"
						( Origin gPackager )
					)
					( objectStatus "U7C1.BL66" )
				)
				( pin "usb3_10_pcie3_gbe_rxn"
					( attribute "PN" "AV72"
						( Origin gPackager )
					)
					( objectStatus "U7C1.AV72" )
				)
				( pin "usb3_10_pcie3_gbe_rxp"
					( attribute "PN" "AV70"
						( Origin gPackager )
					)
					( objectStatus "U7C1.AV70" )
				)
				( pin "usb3_10_pcie3_gbe_txn"
					( attribute "PN" "BH61"
						( Origin gPackager )
					)
					( objectStatus "U7C1.BH61" )
				)
				( pin "usb3_10_pcie3_gbe_txp"
					( attribute "PN" "BK61"
						( Origin gPackager )
					)
					( objectStatus "U7C1.BK61" )
				)
			)
			( gate "@baseboard_fab2_lib.baseboard_fab2(sch_1):page116_i229"
				( attribute "CDS_LIB" "mstr_discrete"
					( Origin gPackager )
				)
				( attribute "CDS_LOCATION" "R7B8"
					( Origin gPackager )
				)
				( attribute "CDS_SEC" "1"
					( Origin gPackager )
				)
				( attribute "LOCATION" "R7B8"
					( Origin gFrontEnd )
				)
				( attribute "MATERIAL" "EMPTY"
					( Origin gFrontEnd )
				)
				( attribute "PACK_TYPE" "0402"
					( Origin gFrontEnd )
				)
				( attribute "PART_NUMBER" "G21796-016"
					( Origin gFrontEnd )
				)
				( attribute "PHYS_PAGE" "116"
					( Origin gFrontEnd )
				)
				( attribute "ROOM" "SB"
					( Origin gFrontEnd )
				)
				( attribute "ROT" "0"
					( Origin gFrontEnd )
				)
				( attribute "SEC" "1"
					( Origin gFrontEnd )
				)
				( attribute "SEC_TYPE" "0402"
					( Origin gFrontEnd )
				)
				( attribute "TOLERANCE" "1%"
					( Origin gFrontEnd )
				)
				( attribute "VALUE" "10.0K"
					( Origin gFrontEnd )
				)
				( attribute "VER" "2"
					( Origin gFrontEnd )
				)
				( attribute "WATTAGE" "1/16W"
					( Origin gFrontEnd )
				)
				( attribute "XY" "(-2125,1400)"
					( Origin gFrontEnd )
				)
				( attribute "CHIPS_PART_NAME" "RES"
					( Origin gPackager )
				)
				( attribute "CDS_PART_NAME" "RES_0402-10.0K,1%,1/16W,EMPTY,A"
					( Origin gPackager )
				)
				( objectStatus "R7B8" )
				( pin "a"
					( attribute "PN" "1"
						( Origin gPackager )
					)
					( objectStatus "R7B8.1" )
				)
				( pin "b"
					( attribute "PN" "2"
						( Origin gPackager )
					)
					( objectStatus "R7B8.2" )
				)
			)
			( gate "@baseboard_fab2_lib.baseboard_fab2(sch_1):page116_i230"
				( attribute "CDS_LIB" "mstr_discrete"
					( Origin gPackager )
				)
				( attribute "CDS_LOCATION" "R7B7"
					( Origin gPackager )
				)
				( attribute "CDS_SEC" "1"
					( Origin gPackager )
				)
				( attribute "LOCATION" "R7B7"
					( Origin gFrontEnd )
				)
				( attribute "MATERIAL" "EMPTY"
					( Origin gFrontEnd )
				)
				( attribute "PACK_TYPE" "0402"
					( Origin gFrontEnd )
				)
				( attribute "PART_NUMBER" "G21796-016"
					( Origin gFrontEnd )
				)
				( attribute "PHYS_PAGE" "116"
					( Origin gFrontEnd )
				)
				( attribute "ROOM" "SB"
					( Origin gFrontEnd )
				)
				( attribute "ROT" "0"
					( Origin gFrontEnd )
				)
				( attribute "SEC" "1"
					( Origin gFrontEnd )
				)
				( attribute "SEC_TYPE" "0402"
					( Origin gFrontEnd )
				)
				( attribute "TOLERANCE" "1%"
					( Origin gFrontEnd )
				)
				( attribute "VALUE" "10.0K"
					( Origin gFrontEnd )
				)
				( attribute "VER" "2"
					( Origin gFrontEnd )
				)
				( attribute "WATTAGE" "1/16W"
					( Origin gFrontEnd )
				)
				( attribute "XY" "(-1825,1400)"
					( Origin gFrontEnd )
				)
				( attribute "CHIPS_PART_NAME" "RES"
					( Origin gPackager )
				)
				( attribute "CDS_PART_NAME" "RES_0402-10.0K,1%,1/16W,EMPTY,A"
					( Origin gPackager )
				)
				( objectStatus "R7B7" )
				( pin "a"
					( attribute "PN" "1"
						( Origin gPackager )
					)
					( objectStatus "R7B7.1" )
				)
				( pin "b"
					( attribute "PN" "2"
						( Origin gPackager )
					)
					( objectStatus "R7B7.2" )
				)
			)
			( gate "@baseboard_fab2_lib.baseboard_fab2(sch_1):page116_i234"
				( attribute "CDS_LIB" "mstr_discrete"
					( Origin gPackager )
				)
				( attribute "CDS_LOCATION" "R3M9"
					( Origin gPackager )
				)
				( attribute "CDS_SEC" "1"
					( Origin gPackager )
				)
				( attribute "LOCATION" "R3M9"
					( Origin gFrontEnd )
				)
				( attribute "MATERIAL" "CHIP"
					( Origin gFrontEnd )
				)
				( attribute "PACK_TYPE" "0402"
					( Origin gFrontEnd )
				)
				( attribute "PART_NUMBER" "G21796-010"
					( Origin gFrontEnd )
				)
				( attribute "PHYS_PAGE" "116"
					( Origin gFrontEnd )
				)
				( attribute "ROOM" "SB"
					( Origin gFrontEnd )
				)
				( attribute "ROT" "0"
					( Origin gFrontEnd )
				)
				( attribute "SEC" "1"
					( Origin gPackager )
				)
				( attribute "TOLERANCE" "1%"
					( Origin gFrontEnd )
				)
				( attribute "VALUE" "100.0K"
					( Origin gFrontEnd )
				)
				( attribute "VER" "2"
					( Origin gFrontEnd )
				)
				( attribute "WATTAGE" "1/16W"
					( Origin gFrontEnd )
				)
				( attribute "XY" "(-6225,725)"
					( Origin gFrontEnd )
				)
				( attribute "CHIPS_PART_NAME" "RES"
					( Origin gPackager )
				)
				( attribute "CDS_PART_NAME" "RES_0402-100.0K,1%,1/16W,CHIP,A"
					( Origin gPackager )
				)
				( objectStatus "R3M9" )
				( pin "a"
					( attribute "PN" "1"
						( Origin gPackager )
					)
					( objectStatus "R3M9.1" )
				)
				( pin "b"
					( attribute "PN" "2"
						( Origin gPackager )
					)
					( objectStatus "R3M9.2" )
				)
			)
			( gate "@baseboard_fab2_lib.baseboard_fab2(sch_1):page116_i235"
				( attribute "CDS_LIB" "mstr_discrete"
					( Origin gPackager )
				)
				( attribute "CDS_LOCATION" "R3M8"
					( Origin gPackager )
				)
				( attribute "CDS_SEC" "1"
					( Origin gPackager )
				)
				( attribute "LOCATION" "R3M8"
					( Origin gFrontEnd )
				)
				( attribute "MATERIAL" "CHIP"
					( Origin gFrontEnd )
				)
				( attribute "PACK_TYPE" "0402"
					( Origin gFrontEnd )
				)
				( attribute "PART_NUMBER" "G21796-010"
					( Origin gFrontEnd )
				)
				( attribute "PHYS_PAGE" "116"
					( Origin gFrontEnd )
				)
				( attribute "ROOM" "SB"
					( Origin gFrontEnd )
				)
				( attribute "ROT" "0"
					( Origin gFrontEnd )
				)
				( attribute "SEC" "1"
					( Origin gPackager )
				)
				( attribute "TOLERANCE" "1%"
					( Origin gFrontEnd )
				)
				( attribute "VALUE" "100.0K"
					( Origin gFrontEnd )
				)
				( attribute "VER" "2"
					( Origin gFrontEnd )
				)
				( attribute "WATTAGE" "1/16W"
					( Origin gFrontEnd )
				)
				( attribute "XY" "(-5900,725)"
					( Origin gFrontEnd )
				)
				( attribute "CHIPS_PART_NAME" "RES"
					( Origin gPackager )
				)
				( attribute "CDS_PART_NAME" "RES_0402-100.0K,1%,1/16W,CHIP,A"
					( Origin gPackager )
				)
				( objectStatus "R3M8" )
				( pin "a"
					( attribute "PN" "1"
						( Origin gPackager )
					)
					( objectStatus "R3M8.1" )
				)
				( pin "b"
					( attribute "PN" "2"
						( Origin gPackager )
					)
					( objectStatus "R3M8.2" )
				)
			)
			( gate "@baseboard_fab2_lib.baseboard_fab2(sch_1):page117_i9"
				( attribute "BOM_COST" "SB"
					( Origin gFrontEnd )
				)
				( attribute "CDS_LIB" "mstr_u_proc"
					( Origin gPackager )
				)
				( attribute "CDS_LOCATION" "U7C1"
					( Origin gPackager )
				)
				( attribute "CDS_SEC" "4"
					( Origin gPackager )
				)
				( attribute "LOCATION" "U7C1"
					( Origin gFrontEnd )
				)
				( attribute "MATERIAL" "IC"
					( Origin gFrontEnd )
				)
				( attribute "PACK_TYPE" "BGA1"
					( Origin gFrontEnd )
				)
				( attribute "PART_NUMBER" "H91415-002"
					( Origin gFrontEnd )
				)
				( attribute "PHYS_PAGE" "117"
					( Origin gFrontEnd )
				)
				( attribute "ROOM" "SB"
					( Origin gFrontEnd )
				)
				( attribute "ROT" "0"
					( Origin gFrontEnd )
				)
				( attribute "SEC" "4"
					( Origin gFrontEnd )
				)
				( attribute "SEC_TYPE" "BGA1"
					( Origin gFrontEnd )
				)
				( attribute "VER" "4"
					( Origin gFrontEnd )
				)
				( attribute "XY" "(-3925,2150)"
					( Origin gFrontEnd )
				)
				( attribute "CHIPS_PART_NAME" "LBG_CORE_QAT_EXT_D"
					( Origin gPackager )
				)
				( attribute "CDS_PART_NAME" "LBG_CORE_QAT_EXT_D_BGA1-IC,H91A"
					( Origin gPackager )
				)
				( objectStatus "U7C1" )
				( pin "dmi_rxn(0)"
					( attribute "PN" "D42"
						( Origin gPackager )
					)
					( objectStatus "U7C1.D42" )
				)
				( pin "dmi_rxn(1)"
					( attribute "PN" "C43"
						( Origin gPackager )
					)
					( objectStatus "U7C1.C43" )
				)
				( pin "dmi_rxn(2)"
					( attribute "PN" "D44"
						( Origin gPackager )
					)
					( objectStatus "U7C1.D44" )
				)
				( pin "dmi_rxn(3)"
					( attribute "PN" "C45"
						( Origin gPackager )
					)
					( objectStatus "U7C1.C45" )
				)
				( pin "dmi_rxp(0)"
					( attribute "PN" "B42"
						( Origin gPackager )
					)
					( objectStatus "U7C1.B42" )
				)
				( pin "dmi_rxp(1)"
					( attribute "PN" "A43"
						( Origin gPackager )
					)
					( objectStatus "U7C1.A43" )
				)
				( pin "dmi_rxp(2)"
					( attribute "PN" "B44"
						( Origin gPackager )
					)
					( objectStatus "U7C1.B44" )
				)
				( pin "dmi_rxp(3)"
					( attribute "PN" "A45"
						( Origin gPackager )
					)
					( objectStatus "U7C1.A45" )
				)
				( pin "dmi_txn(0)"
					( attribute "PN" "H46"
						( Origin gPackager )
					)
					( objectStatus "U7C1.H46" )
				)
				( pin "dmi_txn(1)"
					( attribute "PN" "J48"
						( Origin gPackager )
					)
					( objectStatus "U7C1.J48" )
				)
				( pin "dmi_txn(2)"
					( attribute "PN" "K50"
						( Origin gPackager )
					)
					( objectStatus "U7C1.K50" )
				)
				( pin "dmi_txn(3)"
					( attribute "PN" "P52"
						( Origin gPackager )
					)
					( objectStatus "U7C1.P52" )
				)
				( pin "dmi_txp(0)"
					( attribute "PN" "K46"
						( Origin gPackager )
					)
					( objectStatus "U7C1.K46" )
				)
				( pin "dmi_txp(1)"
					( attribute "PN" "H50"
						( Origin gPackager )
					)
					( objectStatus "U7C1.H50" )
				)
				( pin "dmi_txp(2)"
					( attribute "PN" "M52"
						( Origin gPackager )
					)
					( objectStatus "U7C1.M52" )
				)
				( pin "dmi_txp(3)"
					( attribute "PN" "N54"
						( Origin gPackager )
					)
					( objectStatus "U7C1.N54" )
				)
				( pin "pcieup_0_rxn"
					( attribute "PN" "C48"
						( Origin gPackager )
					)
					( objectStatus "U7C1.C48" )
				)
				( pin "pcieup_0_rxp"
					( attribute "PN" "A48"
						( Origin gPackager )
					)
					( objectStatus "U7C1.A48" )
				)
				( pin "pcieup_0_txn"
					( attribute "PN" "J52"
						( Origin gPackager )
					)
					( objectStatus "U7C1.J52" )
				)
				( pin "pcieup_0_txp"
					( attribute "PN" "G52"
						( Origin gPackager )
					)
					( objectStatus "U7C1.G52" )
				)
				( pin "pcieup_1_rxn"
					( attribute "PN" "D49"
						( Origin gPackager )
					)
					( objectStatus "U7C1.D49" )
				)
				( pin "pcieup_1_rxp"
					( attribute "PN" "B49"
						( Origin gPackager )
					)
					( objectStatus "U7C1.B49" )
				)
				( pin "pcieup_1_txn"
					( attribute "PN" "P56"
						( Origin gPackager )
					)
					( objectStatus "U7C1.P56" )
				)
				( pin "pcieup_1_txp"
					( attribute "PN" "M56"
						( Origin gPackager )
					)
					( objectStatus "U7C1.M56" )
				)
				( pin "pcieup_2_rxn"
					( attribute "PN" "C50"
						( Origin gPackager )
					)
					( objectStatus "U7C1.C50" )
				)
				( pin "pcieup_2_rxp"
					( attribute "PN" "A50"
						( Origin gPackager )
					)
					( objectStatus "U7C1.A50" )
				)
				( pin "pcieup_2_txn"
					( attribute "PN" "H54"
						( Origin gPackager )
					)
					( objectStatus "U7C1.H54" )
				)
				( pin "pcieup_2_txp"
					( attribute "PN" "G56"
						( Origin gPackager )
					)
					( objectStatus "U7C1.G56" )
				)
				( pin "pcieup_3_rxn"
					( attribute "PN" "D51"
						( Origin gPackager )
					)
					( objectStatus "U7C1.D51" )
				)
				( pin "pcieup_3_rxp"
					( attribute "PN" "B51"
						( Origin gPackager )
					)
					( objectStatus "U7C1.B51" )
				)
				( pin "pcieup_3_txn"
					( attribute "PN" "J56"
						( Origin gPackager )
					)
					( objectStatus "U7C1.J56" )
				)
				( pin "pcieup_3_txp"
					( attribute "PN" "K58"
						( Origin gPackager )
					)
					( objectStatus "U7C1.K58" )
				)
				( pin "pcieup_4_rxn"
					( attribute "PN" "C52"
						( Origin gPackager )
					)
					( objectStatus "U7C1.C52" )
				)
				( pin "pcieup_4_rxp"
					( attribute "PN" "A52"
						( Origin gPackager )
					)
					( objectStatus "U7C1.A52" )
				)
				( pin "pcieup_4_txn"
					( attribute "PN" "N58"
						( Origin gPackager )
					)
					( objectStatus "U7C1.N58" )
				)
				( pin "pcieup_4_txp"
					( attribute "PN" "M59"
						( Origin gPackager )
					)
					( objectStatus "U7C1.M59" )
				)
				( pin "pcieup_5_rxn"
					( attribute "PN" "D53"
						( Origin gPackager )
					)
					( objectStatus "U7C1.D53" )
				)
				( pin "pcieup_5_rxp"
					( attribute "PN" "B53"
						( Origin gPackager )
					)
					( objectStatus "U7C1.B53" )
				)
				( pin "pcieup_5_txn"
					( attribute "PN" "N61"
						( Origin gPackager )
					)
					( objectStatus "U7C1.N61" )
				)
				( pin "pcieup_5_txp"
					( attribute "PN" "K61"
						( Origin gPackager )
					)
					( objectStatus "U7C1.K61" )
				)
				( pin "pcieup_6_rxn"
					( attribute "PN" "C54"
						( Origin gPackager )
					)
					( objectStatus "U7C1.C54" )
				)
				( pin "pcieup_6_rxp"
					( attribute "PN" "A54"
						( Origin gPackager )
					)
					( objectStatus "U7C1.A54" )
				)
				( pin "pcieup_6_txn"
					( attribute "PN" "H61"
						( Origin gPackager )
					)
					( objectStatus "U7C1.H61" )
				)
				( pin "pcieup_6_txp"
					( attribute "PN" "J63"
						( Origin gPackager )
					)
					( objectStatus "U7C1.J63" )
				)
				( pin "pcieup_7_rxn"
					( attribute "PN" "D55"
						( Origin gPackager )
					)
					( objectStatus "U7C1.D55" )
				)
				( pin "pcieup_7_rxp"
					( attribute "PN" "B55"
						( Origin gPackager )
					)
					( objectStatus "U7C1.B55" )
				)
				( pin "pcieup_7_txn"
					( attribute "PN" "P59"
						( Origin gPackager )
					)
					( objectStatus "U7C1.P59" )
				)
				( pin "pcieup_7_txp"
					( attribute "PN" "R61"
						( Origin gPackager )
					)
					( objectStatus "U7C1.R61" )
				)
				( pin "pcieup_8_rxn"
					( attribute "PN" "C57"
						( Origin gPackager )
					)
					( objectStatus "U7C1.C57" )
				)
				( pin "pcieup_8_rxp"
					( attribute "PN" "A57"
						( Origin gPackager )
					)
					( objectStatus "U7C1.A57" )
				)
				( pin "pcieup_8_txn"
					( attribute "PN" "K65"
						( Origin gPackager )
					)
					( objectStatus "U7C1.K65" )
				)
				( pin "pcieup_8_txp"
					( attribute "PN" "M63"
						( Origin gPackager )
					)
					( objectStatus "U7C1.M63" )
				)
				( pin "pcieup_9_rxn"
					( attribute "PN" "D58"
						( Origin gPackager )
					)
					( objectStatus "U7C1.D58" )
				)
				( pin "pcieup_9_rxp"
					( attribute "PN" "B58"
						( Origin gPackager )
					)
					( objectStatus "U7C1.B58" )
				)
				( pin "pcieup_9_txn"
					( attribute "PN" "J66"
						( Origin gPackager )
					)
					( objectStatus "U7C1.J66" )
				)
				( pin "pcieup_9_txp"
					( attribute "PN" "M66"
						( Origin gPackager )
					)
					( objectStatus "U7C1.M66" )
				)
				( pin "pcieup_10_rxn"
					( attribute "PN" "C59"
						( Origin gPackager )
					)
					( objectStatus "U7C1.C59" )
				)
				( pin "pcieup_10_rxp"
					( attribute "PN" "A59"
						( Origin gPackager )
					)
					( objectStatus "U7C1.A59" )
				)
				( pin "pcieup_10_txn"
					( attribute "PN" "N65"
						( Origin gPackager )
					)
					( objectStatus "U7C1.N65" )
				)
				( pin "pcieup_10_txp"
					( attribute "PN" "P66"
						( Origin gPackager )
					)
					( objectStatus "U7C1.P66" )
				)
				( pin "pcieup_11_rxn"
					( attribute "PN" "D60"
						( Origin gPackager )
					)
					( objectStatus "U7C1.D60" )
				)
				( pin "pcieup_11_rxp"
					( attribute "PN" "B60"
						( Origin gPackager )
					)
					( objectStatus "U7C1.B60" )
				)
				( pin "pcieup_11_txn"
					( attribute "PN" "T59"
						( Origin gPackager )
					)
					( objectStatus "U7C1.T59" )
				)
				( pin "pcieup_11_txp"
					( attribute "PN" "V59"
						( Origin gPackager )
					)
					( objectStatus "U7C1.V59" )
				)
				( pin "pcieup_12_rxn"
					( attribute "PN" "C61"
						( Origin gPackager )
					)
					( objectStatus "U7C1.C61" )
				)
				( pin "pcieup_12_rxp"
					( attribute "PN" "A61"
						( Origin gPackager )
					)
					( objectStatus "U7C1.A61" )
				)
				( pin "pcieup_12_txn"
					( attribute "PN" "R65"
						( Origin gPackager )
					)
					( objectStatus "U7C1.R65" )
				)
				( pin "pcieup_12_txp"
					( attribute "PN" "U65"
						( Origin gPackager )
					)
					( objectStatus "U7C1.U65" )
				)
				( pin "pcieup_13_rxn"
					( attribute "PN" "D62"
						( Origin gPackager )
					)
					( objectStatus "U7C1.D62" )
				)
				( pin "pcieup_13_rxp"
					( attribute "PN" "B62"
						( Origin gPackager )
					)
					( objectStatus "U7C1.B62" )
				)
				( pin "pcieup_13_txn"
					( attribute "PN" "T63"
						( Origin gPackager )
					)
					( objectStatus "U7C1.T63" )
				)
				( pin "pcieup_13_txp"
					( attribute "PN" "U61"
						( Origin gPackager )
					)
					( objectStatus "U7C1.U61" )
				)
				( pin "pcieup_14_rxn"
					( attribute "PN" "C63"
						( Origin gPackager )
					)
					( objectStatus "U7C1.C63" )
				)
				( pin "pcieup_14_rxp"
					( attribute "PN" "A63"
						( Origin gPackager )
					)
					( objectStatus "U7C1.A63" )
				)
				( pin "pcieup_14_txn"
					( attribute "PN" "W65"
						( Origin gPackager )
					)
					( objectStatus "U7C1.W65" )
				)
				( pin "pcieup_14_txp"
					( attribute "PN" "V63"
						( Origin gPackager )
					)
					( objectStatus "U7C1.V63" )
				)
				( pin "pcieup_15_rxn"
					( attribute "PN" "D64"
						( Origin gPackager )
					)
					( objectStatus "U7C1.D64" )
				)
				( pin "pcieup_15_rxp"
					( attribute "PN" "B64"
						( Origin gPackager )
					)
					( objectStatus "U7C1.B64" )
				)
				( pin "pcieup_15_txn"
					( attribute "PN" "Y66"
						( Origin gPackager )
					)
					( objectStatus "U7C1.Y66" )
				)
				( pin "pcieup_15_txp"
					( attribute "PN" "AA65"
						( Origin gPackager )
					)
					( objectStatus "U7C1.AA65" )
				)
			)
			( gate "@baseboard_fab2_lib.baseboard_fab2(sch_1):page118_i66"
				( attribute "BOM_COST" "SB"
					( Origin gFrontEnd )
				)
				( attribute "CDS_LIB" "mstr_discrete"
					( Origin gPackager )
				)
				( attribute "CDS_LOCATION" "R3N9"
					( Origin gPackager )
				)
				( attribute "CDS_SEC" "1"
					( Origin gPackager )
				)
				( attribute "LOCATION" "R3N9"
					( Origin gFrontEnd )
				)
				( attribute "MATERIAL" "CHIP"
					( Origin gFrontEnd )
				)
				( attribute "PACK_TYPE" "0402"
					( Origin gFrontEnd )
				)
				( attribute "PART_NUMBER" "G21796-066"
					( Origin gFrontEnd )
				)
				( attribute "PHYS_PAGE" "118"
					( Origin gFrontEnd )
				)
				( attribute "ROOM" "SB"
					( Origin gFrontEnd )
				)
				( attribute "ROT" "0"
					( Origin gFrontEnd )
				)
				( attribute "SEC" "1"
					( Origin gFrontEnd )
				)
				( attribute "SEC_TYPE" "0402"
					( Origin gFrontEnd )
				)
				( attribute "TOLERANCE" "1%"
					( Origin gFrontEnd )
				)
				( attribute "VALUE" "10.0"
					( Origin gFrontEnd )
				)
				( attribute "VER" "1"
					( Origin gFrontEnd )
				)
				( attribute "WATTAGE" "1/16W"
					( Origin gFrontEnd )
				)
				( attribute "XY" "(-1575,2675)"
					( Origin gFrontEnd )
				)
				( attribute "CHIPS_PART_NAME" "RES"
					( Origin gPackager )
				)
				( attribute "CDS_PART_NAME" "RES_0402-10.0,1%,1/16W,CHIP,G2A"
					( Origin gPackager )
				)
				( objectStatus "R3N9" )
				( pin "a"
					( attribute "PN" "1"
						( Origin gPackager )
					)
					( objectStatus "R3N9.1" )
				)
				( pin "b"
					( attribute "PN" "2"
						( Origin gPackager )
					)
					( objectStatus "R3N9.2" )
				)
			)
			( gate "@baseboard_fab2_lib.baseboard_fab2(sch_1):page118_i67"
				( attribute "BOM_COST" "SB"
					( Origin gFrontEnd )
				)
				( attribute "CDS_LIB" "mstr_discrete"
					( Origin gPackager )
				)
				( attribute "CDS_LOCATION" "R3N14"
					( Origin gPackager )
				)
				( attribute "CDS_SEC" "1"
					( Origin gPackager )
				)
				( attribute "LOCATION" "R3N14"
					( Origin gFrontEnd )
				)
				( attribute "MATERIAL" "EMPTY"
					( Origin gFrontEnd )
				)
				( attribute "PACK_TYPE" "0402"
					( Origin gFrontEnd )
				)
				( attribute "PART_NUMBER" "G21796-047"
					( Origin gFrontEnd )
				)
				( attribute "PHYS_PAGE" "118"
					( Origin gFrontEnd )
				)
				( attribute "ROOM" "SB"
					( Origin gFrontEnd )
				)
				( attribute "ROT" "0"
					( Origin gFrontEnd )
				)
				( attribute "SEC" "1"
					( Origin gFrontEnd )
				)
				( attribute "SEC_TYPE" "0402"
					( Origin gFrontEnd )
				)
				( attribute "TOLERANCE" "1%"
					( Origin gFrontEnd )
				)
				( attribute "VALUE" "49.9"
					( Origin gFrontEnd )
				)
				( attribute "VER" "2"
					( Origin gFrontEnd )
				)
				( attribute "WATTAGE" "1/16W"
					( Origin gFrontEnd )
				)
				( attribute "XY" "(-1075,2475)"
					( Origin gFrontEnd )
				)
				( attribute "CHIPS_PART_NAME" "RES"
					( Origin gPackager )
				)
				( attribute "CDS_PART_NAME" "RES_0402-49.9,1%,1/16W,EMPTY,GA"
					( Origin gPackager )
				)
				( objectStatus "R3N14" )
				( pin "a"
					( attribute "PN" "1"
						( Origin gPackager )
					)
					( objectStatus "R3N14.1" )
				)
				( pin "b"
					( attribute "PN" "2"
						( Origin gPackager )
					)
					( objectStatus "R3N14.2" )
				)
			)
			( gate "@baseboard_fab2_lib.baseboard_fab2(sch_1):page118_i71"
				( attribute "BOM_COST" "SB"
					( Origin gFrontEnd )
				)
				( attribute "CDS_LIB" "mstr_discrete"
					( Origin gPackager )
				)
				( attribute "CDS_LOCATION" "R3N13"
					( Origin gPackager )
				)
				( attribute "CDS_SEC" "1"
					( Origin gPackager )
				)
				( attribute "LOCATION" "R3N13"
					( Origin gFrontEnd )
				)
				( attribute "MATERIAL" "CHIP"
					( Origin gFrontEnd )
				)
				( attribute "PACK_TYPE" "0402"
					( Origin gFrontEnd )
				)
				( attribute "PART_NUMBER" "G21796-072"
					( Origin gFrontEnd )
				)
				( attribute "PHYS_PAGE" "118"
					( Origin gFrontEnd )
				)
				( attribute "ROOM" "SB"
					( Origin gFrontEnd )
				)
				( attribute "ROT" "0"
					( Origin gFrontEnd )
				)
				( attribute "SEC" "1"
					( Origin gFrontEnd )
				)
				( attribute "SEC_TYPE" "0402"
					( Origin gFrontEnd )
				)
				( attribute "TOLERANCE" "1%"
					( Origin gFrontEnd )
				)
				( attribute "VALUE" "4.75K"
					( Origin gFrontEnd )
				)
				( attribute "VER" "2"
					( Origin gFrontEnd )
				)
				( attribute "WATTAGE" "1/16W"
					( Origin gFrontEnd )
				)
				( attribute "XY" "(-2300,4650)"
					( Origin gFrontEnd )
				)
				( attribute "CHIPS_PART_NAME" "RES"
					( Origin gPackager )
				)
				( attribute "CDS_PART_NAME" "RES_0402-4.75K,1%,1/16W,CHIP,GA"
					( Origin gPackager )
				)
				( objectStatus "R3N13" )
				( pin "a"
					( attribute "PN" "1"
						( Origin gPackager )
					)
					( objectStatus "R3N13.1" )
				)
				( pin "b"
					( attribute "PN" "2"
						( Origin gPackager )
					)
					( objectStatus "R3N13.2" )
				)
			)
			( gate "@baseboard_fab2_lib.baseboard_fab2(sch_1):page118_i73"
				( attribute "BOM_COST" "SB"
					( Origin gFrontEnd )
				)
				( attribute "CDS_LIB" "mstr_u_proc"
					( Origin gPackager )
				)
				( attribute "CDS_LOCATION" "U7C1"
					( Origin gPackager )
				)
				( attribute "CDS_SEC" "5"
					( Origin gPackager )
				)
				( attribute "LOCATION" "U7C1"
					( Origin gFrontEnd )
				)
				( attribute "MATERIAL" "IC"
					( Origin gFrontEnd )
				)
				( attribute "PACK_TYPE" "BGA1"
					( Origin gFrontEnd )
				)
				( attribute "PART_NUMBER" "H91415-002"
					( Origin gFrontEnd )
				)
				( attribute "PHYS_PAGE" "118"
					( Origin gFrontEnd )
				)
				( attribute "ROOM" "SB"
					( Origin gFrontEnd )
				)
				( attribute "ROT" "0"
					( Origin gFrontEnd )
				)
				( attribute "SEC" "5"
					( Origin gFrontEnd )
				)
				( attribute "SEC_TYPE" "BGA1"
					( Origin gFrontEnd )
				)
				( attribute "VER" "5"
					( Origin gFrontEnd )
				)
				( attribute "XY" "(-4025,3025)"
					( Origin gFrontEnd )
				)
				( attribute "CHIPS_PART_NAME" "LBG_CORE_QAT_EXT_D"
					( Origin gPackager )
				)
				( attribute "CDS_PART_NAME" "LBG_CORE_QAT_EXT_D_BGA1-IC,H91A"
					( Origin gPackager )
				)
				( objectStatus "U7C1" )
				( pin "cpu_trst_n"
					( attribute "PN" "AT56"
						( Origin gPackager )
					)
					( objectStatus "U7C1.AT56" )
				)
				( pin "dsw_pwrok"
					( attribute "PN" "K13"
						( Origin gPackager )
					)
					( objectStatus "U7C1.K13" )
				)
				( pin "gpd0"
					( attribute "PN" "G15"
						( Origin gPackager )
					)
					( objectStatus "U7C1.G15" )
				)
				( pin "gpd1_acpresent"
					( attribute "PN" "H13"
						( Origin gPackager )
					)
					( objectStatus "U7C1.H13" )
				)
				( pin "gpd2_gbe_wake_n"
					( attribute "PN" "M11"
						( Origin gPackager )
					)
					( objectStatus "U7C1.M11" )
				)
				( pin "gpd3_pwrbtn_n"
					( attribute "PN" "C15"
						( Origin gPackager )
					)
					( objectStatus "U7C1.C15" )
				)
				( pin "gpd4_slp_s3_n"
					( attribute "PN" "D14"
						( Origin gPackager )
					)
					( objectStatus "U7C1.D14" )
				)
				( pin "gpd5_slp_s4_n"
					( attribute "PN" "B16"
						( Origin gPackager )
					)
					( objectStatus "U7C1.B16" )
				)
				( pin "gpd6_slp_a_n"
					( attribute "PN" "G11"
						( Origin gPackager )
					)
					( objectStatus "U7C1.G11" )
				)
				( pin "gpd7"
					( attribute "PN" "H9"
						( Origin gPackager )
					)
					( objectStatus "U7C1.H9" )
				)
				( pin "gpd8_susclk"
					( attribute "PN" "C13"
						( Origin gPackager )
					)
					( objectStatus "U7C1.C13" )
				)
				( pin "gpd9"
					( attribute "PN" "A15"
						( Origin gPackager )
					)
					( objectStatus "U7C1.A15" )
				)
				( pin "gpd10_slp_s5_n"
					( attribute "PN" "B14"
						( Origin gPackager )
					)
					( objectStatus "U7C1.B14" )
				)
				( pin "gpd11_gbephy"
					( attribute "PN" "A13"
						( Origin gPackager )
					)
					( objectStatus "U7C1.A13" )
				)
				( pin "itp_pmode"
					( attribute "PN" "AR54"
						( Origin gPackager )
					)
					( objectStatus "U7C1.AR54" )
				)
				( pin "jtag_tck"
					( attribute "PN" "AL56"
						( Origin gPackager )
					)
					( objectStatus "U7C1.AL56" )
				)
				( pin "jtag_tdi"
					( attribute "PN" "AN54"
						( Origin gPackager )
					)
					( objectStatus "U7C1.AN54" )
				)
				( pin "jtag_tdo"
					( attribute "PN" "AP56"
						( Origin gPackager )
					)
					( objectStatus "U7C1.AP56" )
				)
				( pin "jtag_tms"
					( attribute "PN" "AH54"
						( Origin gPackager )
					)
					( objectStatus "U7C1.AH54" )
				)
				( pin "jtagx"
					( attribute "PN" "AF54"
						( Origin gPackager )
					)
					( objectStatus "U7C1.AF54" )
				)
				( pin "lan_rbias_0"
					( attribute "PN" "BB29"
						( Origin gPackager )
					)
					( objectStatus "U7C1.BB29" )
				)
				( pin "lan_rbias_1"
					( attribute "PN" "BD42"
						( Origin gPackager )
					)
					( objectStatus "U7C1.BD42" )
				)
				( pin "lan_rx_p0n"
					( attribute "PN" "BH31"
						( Origin gPackager )
					)
					( objectStatus "U7C1.BH31" )
				)
				( pin "lan_rx_p0p"
					( attribute "PN" "BF31"
						( Origin gPackager )
					)
					( objectStatus "U7C1.BF31" )
				)
				( pin "lan_rx_p1n"
					( attribute "PN" "BG29"
						( Origin gPackager )
					)
					( objectStatus "U7C1.BG29" )
				)
				( pin "lan_rx_p1p"
					( attribute "PN" "BJ29"
						( Origin gPackager )
					)
					( objectStatus "U7C1.BJ29" )
				)
				( pin "lan_rx_p2n"
					( attribute "PN" "BJ37"
						( Origin gPackager )
					)
					( objectStatus "U7C1.BJ37" )
				)
				( pin "lan_rx_p2p"
					( attribute "PN" "BG37"
						( Origin gPackager )
					)
					( objectStatus "U7C1.BG37" )
				)
				( pin "lan_rx_p3n"
					( attribute "PN" "BF35"
						( Origin gPackager )
					)
					( objectStatus "U7C1.BF35" )
				)
				( pin "lan_rx_p3p"
					( attribute "PN" "BH35"
						( Origin gPackager )
					)
					( objectStatus "U7C1.BH35" )
				)
				( pin "lan_tx_p0n"
					( attribute "PN" "BM27"
						( Origin gPackager )
					)
					( objectStatus "U7C1.BM27" )
				)
				( pin "lan_tx_p0p"
					( attribute "PN" "BR27"
						( Origin gPackager )
					)
					( objectStatus "U7C1.BR27" )
				)
				( pin "lan_tx_p1n"
					( attribute "PN" "BM24"
						( Origin gPackager )
					)
					( objectStatus "U7C1.BM24" )
				)
				( pin "lan_tx_p1p"
					( attribute "PN" "BR24"
						( Origin gPackager )
					)
					( objectStatus "U7C1.BR24" )
				)
				( pin "lan_tx_p2n"
					( attribute "PN" "BM35"
						( Origin gPackager )
					)
					( objectStatus "U7C1.BM35" )
				)
				( pin "lan_tx_p2p"
					( attribute "PN" "BR35"
						( Origin gPackager )
					)
					( objectStatus "U7C1.BR35" )
				)
				( pin "lan_tx_p3n"
					( attribute "PN" "BR31"
						( Origin gPackager )
					)
					( objectStatus "U7C1.BR31" )
				)
				( pin "lan_tx_p3p"
					( attribute "PN" "BM31"
						( Origin gPackager )
					)
					( objectStatus "U7C1.BM31" )
				)
				( pin "lan_xtal_in"
					( attribute "PN" "BV16"
						( Origin gPackager )
					)
					( objectStatus "U7C1.BV16" )
				)
				( pin "lan_xtal_out"
					( attribute "PN" "BY16"
						( Origin gPackager )
					)
					( objectStatus "U7C1.BY16" )
				)
				( pin "pch_pwrok"
					( attribute "PN" "R17"
						( Origin gPackager )
					)
					( objectStatus "U7C1.R17" )
				)
				( pin "peci"
					( attribute "PN" "U9"
						( Origin gPackager )
					)
					( objectStatus "U7C1.U9" )
				)
				( pin "pltrst_cpu_n"
					( attribute "PN" "U17"
						( Origin gPackager )
					)
					( objectStatus "U7C1.U17" )
				)
				( pin "pm_sync"
					( attribute "PN" "U13"
						( Origin gPackager )
					)
					( objectStatus "U7C1.U13" )
				)
				( pin "pm_sync2"
					( attribute "PN" "V7"
						( Origin gPackager )
					)
					( objectStatus "U7C1.V7" )
				)
				( pin "prdy_n"
					( attribute "PN" "AD54"
						( Origin gPackager )
					)
					( objectStatus "U7C1.AD54" )
				)
				( pin "preq_n"
					( attribute "PN" "U54"
						( Origin gPackager )
					)
					( objectStatus "U7C1.U54" )
				)
				( pin "proc_pwrgd"
					( attribute "PN" "R9"
						( Origin gPackager )
					)
					( objectStatus "U7C1.R9" )
				)
				( pin "rsmrst_n"
					( attribute "PN" "P15"
						( Origin gPackager )
					)
					( objectStatus "U7C1.P15" )
				)
				( pin "rsvd(32)"
					( attribute "PN" "AA54"
						( Origin gPackager )
					)
					( objectStatus "U7C1.AA54" )
				)
				( pin "rsvd(33)"
					( attribute "PN" "V56"
						( Origin gPackager )
					)
					( objectStatus "U7C1.V56" )
				)
				( pin "rsvd(34)"
					( attribute "PN" "Y56"
						( Origin gPackager )
					)
					( objectStatus "U7C1.Y56" )
				)
				( pin "rsvd(35)"
					( attribute "PN" "W54"
						( Origin gPackager )
					)
					( objectStatus "U7C1.W54" )
				)
				( pin "rsvd(36)"
					( attribute "PN" "AK54"
						( Origin gPackager )
					)
					( objectStatus "U7C1.AK54" )
				)
				( pin "rsvd(37)"
					( attribute "PN" "BN29"
						( Origin gPackager )
					)
					( objectStatus "U7C1.BN29" )
				)
				( pin "rsvd(38)"
					( attribute "PN" "BL29"
						( Origin gPackager )
					)
					( objectStatus "U7C1.BL29" )
				)
				( pin "rsvd(39)"
					( attribute "PN" "BL26"
						( Origin gPackager )
					)
					( objectStatus "U7C1.BL26" )
				)
				( pin "rsvd(40)"
					( attribute "PN" "BN26"
						( Origin gPackager )
					)
					( objectStatus "U7C1.BN26" )
				)
				( pin "rsvd(41)"
					( attribute "PN" "BJ40"
						( Origin gPackager )
					)
					( objectStatus "U7C1.BJ40" )
				)
				( pin "rsvd(42)"
					( attribute "PN" "BG40"
						( Origin gPackager )
					)
					( objectStatus "U7C1.BG40" )
				)
				( pin "rsvd(43)"
					( attribute "PN" "BL33"
						( Origin gPackager )
					)
					( objectStatus "U7C1.BL33" )
				)
				( pin "rsvd(44)"
					( attribute "PN" "BN33"
						( Origin gPackager )
					)
					( objectStatus "U7C1.BN33" )
				)
				( pin "rsvd(45)"
					( attribute "PN" "P22"
						( Origin gPackager )
					)
					( objectStatus "U7C1.P22" )
				)
				( pin "rsvd(46)"
					( attribute "CDS_NOT_ON_SYM" "TRUE"
						( Origin gFrontEnd )
					)
				)
				( pin "rsvd(47)"
					( attribute "CDS_NOT_ON_SYM" "TRUE"
						( Origin gFrontEnd )
					)
				)
				( pin "rsvd(48)"
					( attribute "CDS_NOT_ON_SYM" "TRUE"
						( Origin gFrontEnd )
					)
				)
				( pin "rsvd(49)"
					( attribute "CDS_NOT_ON_SYM" "TRUE"
						( Origin gFrontEnd )
					)
				)
				( pin "rsvd(50)"
					( attribute "CDS_NOT_ON_SYM" "TRUE"
						( Origin gFrontEnd )
					)
				)
				( pin "rsvd(51)"
					( attribute "CDS_NOT_ON_SYM" "TRUE"
						( Origin gFrontEnd )
					)
				)
				( pin "rsvd(52)"
					( attribute "CDS_NOT_ON_SYM" "TRUE"
						( Origin gFrontEnd )
					)
				)
				( pin "rsvd(53)"
					( attribute "PN" "P26"
						( Origin gPackager )
					)
					( objectStatus "U7C1.P26" )
				)
				( pin "rsvd(54)"
					( attribute "PN" "R24"
						( Origin gPackager )
					)
					( objectStatus "U7C1.R24" )
				)
				( pin "slp_gbe_n"
					( attribute "PN" "M15"
						( Origin gPackager )
					)
					( objectStatus "U7C1.M15" )
				)
				( pin "slp_sus_n"
					( attribute "PN" "P7"
						( Origin gPackager )
					)
					( objectStatus "U7C1.P7" )
				)
				( pin "sys_pwrok"
					( attribute "PN" "BY19"
						( Origin gPackager )
					)
					( objectStatus "U7C1.BY19" )
				)
				( pin "sys_reset_n"
					( attribute "PN" "BV19"
						( Origin gPackager )
					)
					( objectStatus "U7C1.BV19" )
				)
				( pin "thrmtrip_n"
					( attribute "PN" "V15"
						( Origin gPackager )
					)
					( objectStatus "U7C1.V15" )
				)
				( pin "trigger_in"
					( attribute "PN" "M7"
						( Origin gPackager )
					)
					( objectStatus "U7C1.M7" )
				)
				( pin "trigger_out"
					( attribute "PN" "R13"
						( Origin gPackager )
					)
					( objectStatus "U7C1.R13" )
				)
				( pin "wake_n"
					( attribute "PN" "K9"
						( Origin gPackager )
					)
					( objectStatus "U7C1.K9" )
				)
			)
			( gate "@baseboard_fab2_lib.baseboard_fab2(sch_1):page118_i76"
				( attribute "BOM_COST" "SB"
					( Origin gFrontEnd )
				)
				( attribute "CDS_LIB" "mstr_discrete"
					( Origin gPackager )
				)
				( attribute "CDS_LOCATION" "Y8C1"
					( Origin gPackager )
				)
				( attribute "CDS_SEC" "1"
					( Origin gPackager )
				)
				( attribute "LOCATION" "Y8C1"
					( Origin gFrontEnd )
				)
				( attribute "MATERIAL" "IC"
					( Origin gFrontEnd )
				)
				( attribute "PACK_TYPE" "2013"
					( Origin gFrontEnd )
				)
				( attribute "PART_NUMBER" "H19611-001"
					( Origin gFrontEnd )
				)
				( attribute "PHYS_PAGE" "118"
					( Origin gFrontEnd )
				)
				( attribute "ROOM" "SB"
					( Origin gFrontEnd )
				)
				( attribute "ROT" "0"
					( Origin gFrontEnd )
				)
				( attribute "SEC" "1"
					( Origin gFrontEnd )
				)
				( attribute "SEC_TYPE" "2013"
					( Origin gFrontEnd )
				)
				( attribute "VALUE" "25.000MHZ"
					( Origin gFrontEnd )
				)
				( attribute "VER" "1"
					( Origin gFrontEnd )
				)
				( attribute "XY" "(-7400,850)"
					( Origin gFrontEnd )
				)
				( attribute "CHIPS_PART_NAME" "CRYSTAL"
					( Origin gPackager )
				)
				( attribute "CDS_PART_NAME" "CRYSTAL_2013-25.000MHZ,IC,H196A"
					( Origin gPackager )
				)
				( objectStatus "Y8C1" )
				( pin "a"
					( attribute "PN" "1"
						( Origin gPackager )
					)
					( objectStatus "Y8C1.1" )
				)
				( pin "b"
					( attribute "PN" "3"
						( Origin gPackager )
					)
					( objectStatus "Y8C1.3" )
				)
			)
			( gate "@baseboard_fab2_lib.baseboard_fab2(sch_1):page118_i77"
				( attribute "BOM_COST" "SB"
					( Origin gFrontEnd )
				)
				( attribute "CDS_LIB" "mstr_discrete"
					( Origin gPackager )
				)
				( attribute "CDS_LOCATION" "C8C2"
					( Origin gPackager )
				)
				( attribute "CDS_SEC" "1"
					( Origin gPackager )
				)
				( attribute "LOCATION" "C8C2"
					( Origin gFrontEnd )
				)
				( attribute "MATERIAL" "COG"
					( Origin gFrontEnd )
				)
				( attribute "PACK_TYPE" "0402LF"
					( Origin gFrontEnd )
				)
				( attribute "PART_NUMBER" "A36095-031"
					( Origin gFrontEnd )
				)
				( attribute "PHYS_PAGE" "118"
					( Origin gFrontEnd )
				)
				( attribute "ROOM" "SB"
					( Origin gFrontEnd )
				)
				( attribute "ROT" "0"
					( Origin gFrontEnd )
				)
				( attribute "SEC" "1"
					( Origin gFrontEnd )
				)
				( attribute "SEC_TYPE" "0402LF"
					( Origin gFrontEnd )
				)
				( attribute "TOLERANCE" "5%"
					( Origin gFrontEnd )
				)
				( attribute "VALUE" "33.0PF"
					( Origin gFrontEnd )
				)
				( attribute "VER" "1"
					( Origin gFrontEnd )
				)
				( attribute "VOLTAGE" "50V"
					( Units "uVoltage" "V" 1.000000)
					( Origin gFrontEnd )
				)
				( attribute "XY" "(-7250,600)"
					( Origin gFrontEnd )
				)
				( attribute "CHIPS_PART_NAME" "CAP"
					( Origin gPackager )
				)
				( attribute "CDS_PART_NAME" "CAP_0402LF-33.0PF,50V,5%,COG,AA"
					( Origin gPackager )
				)
				( objectStatus "C8C2" )
				( pin "a"
					( attribute "PN" "1"
						( Origin gPackager )
					)
					( objectStatus "C8C2.1" )
				)
				( pin "b"
					( attribute "PN" "2"
						( Origin gPackager )
					)
					( objectStatus "C8C2.2" )
				)
			)
			( gate "@baseboard_fab2_lib.baseboard_fab2(sch_1):page118_i79"
				( attribute "BOM_COST" "SB"
					( Origin gFrontEnd )
				)
				( attribute "CDS_LIB" "mstr_discrete"
					( Origin gPackager )
				)
				( attribute "CDS_LOCATION" "C8C1"
					( Origin gPackager )
				)
				( attribute "CDS_SEC" "1"
					( Origin gPackager )
				)
				( attribute "LOCATION" "C8C1"
					( Origin gFrontEnd )
				)
				( attribute "MATERIAL" "COG"
					( Origin gFrontEnd )
				)
				( attribute "PACK_TYPE" "0402LF"
					( Origin gFrontEnd )
				)
				( attribute "PART_NUMBER" "A36095-031"
					( Origin gFrontEnd )
				)
				( attribute "PHYS_PAGE" "118"
					( Origin gFrontEnd )
				)
				( attribute "ROOM" "SB"
					( Origin gFrontEnd )
				)
				( attribute "ROT" "0"
					( Origin gFrontEnd )
				)
				( attribute "SEC" "1"
					( Origin gFrontEnd )
				)
				( attribute "SEC_TYPE" "0402LF"
					( Origin gFrontEnd )
				)
				( attribute "TOLERANCE" "5%"
					( Origin gFrontEnd )
				)
				( attribute "VALUE" "33.0PF"
					( Origin gFrontEnd )
				)
				( attribute "VER" "1"
					( Origin gFrontEnd )
				)
				( attribute "VOLTAGE" "50V"
					( Units "uVoltage" "V" 1.000000)
					( Origin gFrontEnd )
				)
				( attribute "XY" "(-7700,625)"
					( Origin gFrontEnd )
				)
				( attribute "CHIPS_PART_NAME" "CAP"
					( Origin gPackager )
				)
				( attribute "CDS_PART_NAME" "CAP_0402LF-33.0PF,50V,5%,COG,AA"
					( Origin gPackager )
				)
				( objectStatus "C8C1" )
				( pin "a"
					( attribute "PN" "1"
						( Origin gPackager )
					)
					( objectStatus "C8C1.1" )
				)
				( pin "b"
					( attribute "PN" "2"
						( Origin gPackager )
					)
					( objectStatus "C8C1.2" )
				)
			)
			( gate "@baseboard_fab2_lib.baseboard_fab2(sch_1):page118_i96"
				( attribute "CDS_LIB" "mstr_discrete"
					( Origin gPackager )
				)
				( attribute "CDS_LOCATION" "R2N4"
					( Origin gPackager )
				)
				( attribute "CDS_SEC" "1"
					( Origin gPackager )
				)
				( attribute "LOCATION" "R2N4"
					( Origin gFrontEnd )
				)
				( attribute "MATERIAL" "CHIP"
					( Origin gFrontEnd )
				)
				( attribute "PACK_TYPE" "0402"
					( Origin gFrontEnd )
				)
				( attribute "PART_NUMBER" "G85996-004"
					( Origin gFrontEnd )
				)
				( attribute "PHYS_PAGE" "118"
					( Origin gFrontEnd )
				)
				( attribute "ROOM" "SB"
					( Origin gFrontEnd )
				)
				( attribute "ROT" "0"
					( Origin gFrontEnd )
				)
				( attribute "SEC" "1"
					( Origin gFrontEnd )
				)
				( attribute "SEC_TYPE" "0402"
					( Origin gFrontEnd )
				)
				( attribute "TOLERANCE" "0.1%"
					( Origin gFrontEnd )
				)
				( attribute "VALUE" "1.0K"
					( Origin gFrontEnd )
				)
				( attribute "VER" "2"
					( Origin gFrontEnd )
				)
				( attribute "WATTAGE" "1/16W"
					( Origin gFrontEnd )
				)
				( attribute "XY" "(-7225,2175)"
					( Origin gFrontEnd )
				)
				( attribute "CHIPS_PART_NAME" "RES"
					( Origin gPackager )
				)
				( attribute "CDS_PART_NAME" "RES_0402-1.0K,0.1%,1/16W,CHIP,A"
					( Origin gPackager )
				)
				( objectStatus "R2N4" )
				( pin "a"
					( attribute "PN" "1"
						( Origin gPackager )
					)
					( objectStatus "R2N4.1" )
				)
				( pin "b"
					( attribute "PN" "2"
						( Origin gPackager )
					)
					( objectStatus "R2N4.2" )
				)
			)
			( gate "@baseboard_fab2_lib.baseboard_fab2(sch_1):page118_i99"
				( attribute "CDS_LIB" "mstr_discrete"
					( Origin gPackager )
				)
				( attribute "CDS_LOCATION" "R2M6"
					( Origin gPackager )
				)
				( attribute "CDS_SEC" "1"
					( Origin gPackager )
				)
				( attribute "LOCATION" "R2M6"
					( Origin gFrontEnd )
				)
				( attribute "MATERIAL" "CHIP"
					( Origin gFrontEnd )
				)
				( attribute "PACK_TYPE" "0402"
					( Origin gFrontEnd )
				)
				( attribute "PART_NUMBER" "G85996-004"
					( Origin gFrontEnd )
				)
				( attribute "PHYS_PAGE" "118"
					( Origin gFrontEnd )
				)
				( attribute "ROOM" "SB"
					( Origin gFrontEnd )
				)
				( attribute "ROT" "0"
					( Origin gFrontEnd )
				)
				( attribute "SEC" "1"
					( Origin gFrontEnd )
				)
				( attribute "SEC_TYPE" "0402"
					( Origin gFrontEnd )
				)
				( attribute "TOLERANCE" "0.1%"
					( Origin gFrontEnd )
				)
				( attribute "VALUE" "1.0K"
					( Origin gFrontEnd )
				)
				( attribute "VER" "1"
					( Origin gFrontEnd )
				)
				( attribute "WATTAGE" "1/16W"
					( Origin gFrontEnd )
				)
				( attribute "XY" "(-1700,1875)"
					( Origin gFrontEnd )
				)
				( attribute "CHIPS_PART_NAME" "RES"
					( Origin gPackager )
				)
				( attribute "CDS_PART_NAME" "RES_0402-1.0K,0.1%,1/16W,CHIP,A"
					( Origin gPackager )
				)
				( objectStatus "R2M6" )
				( pin "a"
					( attribute "PN" "1"
						( Origin gPackager )
					)
					( objectStatus "R2M6.1" )
				)
				( pin "b"
					( attribute "PN" "2"
						( Origin gPackager )
					)
					( objectStatus "R2M6.2" )
				)
			)
			( gate "@baseboard_fab2_lib.baseboard_fab2(sch_1):page118_i120"
				( attribute "BOM_COST" "SB"
					( Origin gFrontEnd )
				)
				( attribute "CDS_LIB" "mstr_discrete"
					( Origin gPackager )
				)
				( attribute "CDS_LOCATION" "R8C24"
					( Origin gPackager )
				)
				( attribute "CDS_SEC" "1"
					( Origin gPackager )
				)
				( attribute "LOCATION" "R8C24"
					( Origin gFrontEnd )
				)
				( attribute "MATERIAL" "CHIP"
					( Origin gFrontEnd )
				)
				( attribute "PACK_TYPE" "0402"
					( Origin gFrontEnd )
				)
				( attribute "PART_NUMBER" "G21497-005"
					( Origin gFrontEnd )
				)
				( attribute "PHYS_PAGE" "118"
					( Origin gFrontEnd )
				)
				( attribute "ROOM" "SB"
					( Origin gFrontEnd )
				)
				( attribute "ROT" "0"
					( Origin gFrontEnd )
				)
				( attribute "SEC" "1"
					( Origin gFrontEnd )
				)
				( attribute "SEC_TYPE" "0402"
					( Origin gFrontEnd )
				)
				( attribute "TOLERANCE" "5%"
					( Origin gFrontEnd )
				)
				( attribute "VALUE" "0.0"
					( Origin gFrontEnd )
				)
				( attribute "VER" "1"
					( Origin gFrontEnd )
				)
				( attribute "WATTAGE" "1/16W"
					( Origin gFrontEnd )
				)
				( attribute "XY" "(-1675,900)"
					( Origin gFrontEnd )
				)
				( attribute "CHIPS_PART_NAME" "RES"
					( Origin gPackager )
				)
				( attribute "CDS_PART_NAME" "RES_0402-0.0,5%,1/16W,CHIP,G21A"
					( Origin gPackager )
				)
				( objectStatus "R8C24" )
				( pin "a"
					( attribute "PN" "1"
						( Origin gPackager )
					)
					( objectStatus "R8C24.1" )
				)
				( pin "b"
					( attribute "PN" "2"
						( Origin gPackager )
					)
					( objectStatus "R8C24.2" )
				)
			)
			( gate "@baseboard_fab2_lib.baseboard_fab2(sch_1):page118_i125"
				( attribute "BOM_COST" "SB"
					( Origin gFrontEnd )
				)
				( attribute "CDS_LIB" "mstr_discrete"
					( Origin gPackager )
				)
				( attribute "CDS_LOCATION" "R8C23"
					( Origin gPackager )
				)
				( attribute "CDS_SEC" "1"
					( Origin gPackager )
				)
				( attribute "LOCATION" "R8C23"
					( Origin gFrontEnd )
				)
				( attribute "MATERIAL" "EMPTY"
					( Origin gFrontEnd )
				)
				( attribute "PACK_TYPE" "0402"
					( Origin gFrontEnd )
				)
				( attribute "PART_NUMBER" "G21497-005"
					( Origin gFrontEnd )
				)
				( attribute "PHYS_PAGE" "118"
					( Origin gFrontEnd )
				)
				( attribute "ROOM" "SB"
					( Origin gFrontEnd )
				)
				( attribute "ROT" "0"
					( Origin gFrontEnd )
				)
				( attribute "SEC" "1"
					( Origin gFrontEnd )
				)
				( attribute "SEC_TYPE" "0402"
					( Origin gFrontEnd )
				)
				( attribute "TOLERANCE" "5%"
					( Origin gFrontEnd )
				)
				( attribute "VALUE" "0.0"
					( Origin gFrontEnd )
				)
				( attribute "VER" "1"
					( Origin gFrontEnd )
				)
				( attribute "WATTAGE" "1/16W"
					( Origin gFrontEnd )
				)
				( attribute "XY" "(-1675,675)"
					( Origin gFrontEnd )
				)
				( attribute "CHIPS_PART_NAME" "RES"
					( Origin gPackager )
				)
				( attribute "CDS_PART_NAME" "RES_0402-0.0,5%,1/16W,EMPTY,G2A"
					( Origin gPackager )
				)
				( objectStatus "R8C23" )
				( pin "a"
					( attribute "PN" "1"
						( Origin gPackager )
					)
					( objectStatus "R8C23.1" )
				)
				( pin "b"
					( attribute "PN" "2"
						( Origin gPackager )
					)
					( objectStatus "R8C23.2" )
				)
			)
			( gate "@baseboard_fab2_lib.baseboard_fab2(sch_1):page118_i128"
				( attribute "BOM_COST" "SB"
					( Origin gFrontEnd )
				)
				( attribute "CDS_LIB" "mstr_discrete"
					( Origin gPackager )
				)
				( attribute "CDS_LOCATION" "R2N6"
					( Origin gPackager )
				)
				( attribute "CDS_SEC" "1"
					( Origin gPackager )
				)
				( attribute "LOCATION" "R2N6"
					( Origin gFrontEnd )
				)
				( attribute "MATERIAL" "CHIP"
					( Origin gFrontEnd )
				)
				( attribute "PACK_TYPE" "0402"
					( Origin gFrontEnd )
				)
				( attribute "PART_NUMBER" "G21796-016"
					( Origin gFrontEnd )
				)
				( attribute "PHYS_PAGE" "118"
					( Origin gFrontEnd )
				)
				( attribute "ROOM" "SB"
					( Origin gFrontEnd )
				)
				( attribute "ROT" "0"
					( Origin gFrontEnd )
				)
				( attribute "SEC" "1"
					( Origin gFrontEnd )
				)
				( attribute "SEC_TYPE" "0402"
					( Origin gFrontEnd )
				)
				( attribute "TOLERANCE" "1%"
					( Origin gFrontEnd )
				)
				( attribute "VALUE" "10.0K"
					( Origin gFrontEnd )
				)
				( attribute "VER" "2"
					( Origin gFrontEnd )
				)
				( attribute "WATTAGE" "1/16W"
					( Origin gFrontEnd )
				)
				( attribute "XY" "(-2200,1100)"
					( Origin gFrontEnd )
				)
				( attribute "CHIPS_PART_NAME" "RES"
					( Origin gPackager )
				)
				( attribute "CDS_PART_NAME" "RES_0402-10.0K,1%,1/16W,CHIP,GA"
					( Origin gPackager )
				)
				( objectStatus "R2N6" )
				( pin "a"
					( attribute "PN" "1"
						( Origin gPackager )
					)
					( objectStatus "R2N6.1" )
				)
				( pin "b"
					( attribute "PN" "2"
						( Origin gPackager )
					)
					( objectStatus "R2N6.2" )
				)
			)
			( gate "@baseboard_fab2_lib.baseboard_fab2(sch_1):page118_i131"
				( attribute "BOM_COST" "SB"
					( Origin gFrontEnd )
				)
				( attribute "CDS_LIB" "mstr_discrete"
					( Origin gPackager )
				)
				( attribute "CDS_LOCATION" "R7D23"
					( Origin gPackager )
				)
				( attribute "CDS_SEC" "1"
					( Origin gPackager )
				)
				( attribute "LOCATION" "R7D23"
					( Origin gFrontEnd )
				)
				( attribute "MATERIAL" "CHIP"
					( Origin gFrontEnd )
				)
				( attribute "PACK_TYPE" "0402"
					( Origin gFrontEnd )
				)
				( attribute "PART_NUMBER" "G21497-005"
					( Origin gFrontEnd )
				)
				( attribute "PHYS_PAGE" "118"
					( Origin gFrontEnd )
				)
				( attribute "ROOM" "SB"
					( Origin gFrontEnd )
				)
				( attribute "ROT" "0"
					( Origin gFrontEnd )
				)
				( attribute "SEC" "1"
					( Origin gFrontEnd )
				)
				( attribute "SEC_TYPE" "0402"
					( Origin gFrontEnd )
				)
				( attribute "TOLERANCE" "5%"
					( Origin gFrontEnd )
				)
				( attribute "VALUE" "0.0"
					( Origin gFrontEnd )
				)
				( attribute "VER" "1"
					( Origin gFrontEnd )
				)
				( attribute "WATTAGE" "1/16W"
					( Origin gFrontEnd )
				)
				( attribute "XY" "(-6750,3975)"
					( Origin gFrontEnd )
				)
				( attribute "CHIPS_PART_NAME" "RES"
					( Origin gPackager )
				)
				( attribute "CDS_PART_NAME" "RES_0402-0.0,5%,1/16W,CHIP,G21A"
					( Origin gPackager )
				)
				( objectStatus "R7D23" )
				( pin "a"
					( attribute "PN" "1"
						( Origin gPackager )
					)
					( objectStatus "R7D23.1" )
				)
				( pin "b"
					( attribute "PN" "2"
						( Origin gPackager )
					)
					( objectStatus "R7D23.2" )
				)
			)
			( gate "@baseboard_fab2_lib.baseboard_fab2(sch_1):page118_i136"
				( attribute "BOM_COST" "SB"
					( Origin gFrontEnd )
				)
				( attribute "CDS_LIB" "dev_discrete"
					( Origin gPackager )
				)
				( attribute "CDS_LOCATION" "C7D1"
					( Origin gPackager )
				)
				( attribute "CDS_SEC" "1"
					( Origin gPackager )
				)
				( attribute "LOCATION" "C7D1"
					( Origin gFrontEnd )
				)
				( attribute "MATERIAL" "X7R"
					( Origin gFrontEnd )
				)
				( attribute "PACK_TYPE" "0402V"
					( Origin gFrontEnd )
				)
				( attribute "PART_NUMBER" "A36096-030"
					( Origin gFrontEnd )
				)
				( attribute "PHYS_PAGE" "118"
					( Origin gFrontEnd )
				)
				( attribute "ROOM" "SB"
					( Origin gFrontEnd )
				)
				( attribute "ROT" "0"
					( Origin gFrontEnd )
				)
				( attribute "SEC" "1"
					( Origin gFrontEnd )
				)
				( attribute "SEC_TYPE" "0402V"
					( Origin gFrontEnd )
				)
				( attribute "TOLERANCE" "10%"
					( Origin gFrontEnd )
				)
				( attribute "VALUE" "0.1UF"
					( Origin gFrontEnd )
				)
				( attribute "VER" "1"
					( Origin gFrontEnd )
				)
				( attribute "VOLTAGE" "16V"
					( Units "uVoltage" "V" 1.000000)
					( Origin gFrontEnd )
				)
				( attribute "XY" "(-5200,375)"
					( Origin gFrontEnd )
				)
				( attribute "CHIPS_PART_NAME" "CAP_A"
					( Origin gPackager )
				)
				( attribute "CDS_PART_NAME" "CAP_A_0402V-0.1UF,16V,10%,X7R,A"
					( Origin gPackager )
				)
				( objectStatus "C7D1" )
				( pin "a"
					( attribute "PN" "1"
						( Origin gPackager )
					)
					( objectStatus "C7D1.1" )
				)
				( pin "b"
					( attribute "PN" "2"
						( Origin gPackager )
					)
					( objectStatus "C7D1.2" )
				)
			)
			( gate "@baseboard_fab2_lib.baseboard_fab2(sch_1):page118_i142"
				( attribute "BOM_COST" "DEBUG"
					( Origin gFrontEnd )
				)
				( attribute "CDS_LIB" "mstr_ttl"
					( Origin gPackager )
				)
				( attribute "CDS_LOCATION" "U7D1"
					( Origin gPackager )
				)
				( attribute "CDS_SEC" "1"
					( Origin gPackager )
				)
				( attribute "LOCATION" "U7D1"
					( Origin gFrontEnd )
				)
				( attribute "MATERIAL" "IC"
					( Origin gFrontEnd )
				)
				( attribute "PACK_TYPE" "SMLF"
					( Origin gFrontEnd )
				)
				( attribute "PART_NUMBER" "C88177-001"
					( Origin gFrontEnd )
				)
				( attribute "PHYS_PAGE" "118"
					( Origin gFrontEnd )
				)
				( attribute "ROOM" "DEBUG"
					( Origin gFrontEnd )
				)
				( attribute "ROT" "0"
					( Origin gFrontEnd )
				)
				( attribute "SEC" "1"
					( Origin gPackager )
				)
				( attribute "VER" "1"
					( Origin gFrontEnd )
				)
				( attribute "XY" "(-4575,1075)"
					( Origin gFrontEnd )
				)
				( attribute "CHIPS_PART_NAME" "74CBTLV1G125"
					( Origin gPackager )
				)
				( attribute "CDS_PART_NAME" "74CBTLV1G125_SMLF-IC,C88177-00A"
					( Origin gPackager )
				)
				( objectStatus "U7D1" )
				( pin "a"
					( attribute "PN" "2"
						( Origin gPackager )
					)
					( objectStatus "U7D1.2" )
				)
				( pin "b"
					( attribute "PN" "4"
						( Origin gPackager )
					)
					( objectStatus "U7D1.4" )
				)
				( pin "oe_n"
					( attribute "PN" "1"
						( Origin gPackager )
					)
					( objectStatus "U7D1.1" )
				)
			)
			( gate "@baseboard_fab2_lib.baseboard_fab2(sch_1):page118_i144"
				( attribute "BOM_COST" "SB"
					( Origin gFrontEnd )
				)
				( attribute "CDS_LIB" "mstr_discrete"
					( Origin gPackager )
				)
				( attribute "CDS_LOCATION" "R7C23"
					( Origin gPackager )
				)
				( attribute "CDS_SEC" "1"
					( Origin gPackager )
				)
				( attribute "LOCATION" "R7C23"
					( Origin gFrontEnd )
				)
				( attribute "MATERIAL" "CHIP"
					( Origin gFrontEnd )
				)
				( attribute "PACK_TYPE" "0402"
					( Origin gFrontEnd )
				)
				( attribute "PART_NUMBER" "G21796-016"
					( Origin gFrontEnd )
				)
				( attribute "PHYS_PAGE" "118"
					( Origin gFrontEnd )
				)
				( attribute "ROOM" "SB"
					( Origin gFrontEnd )
				)
				( attribute "ROT" "0"
					( Origin gFrontEnd )
				)
				( attribute "SEC" "1"
					( Origin gFrontEnd )
				)
				( attribute "SEC_TYPE" "0402"
					( Origin gFrontEnd )
				)
				( attribute "TOLERANCE" "1%"
					( Origin gFrontEnd )
				)
				( attribute "VALUE" "10.0K"
					( Origin gFrontEnd )
				)
				( attribute "VER" "2"
					( Origin gFrontEnd )
				)
				( attribute "WATTAGE" "1/16W"
					( Origin gFrontEnd )
				)
				( attribute "XY" "(-5175,1275)"
					( Origin gFrontEnd )
				)
				( attribute "CHIPS_PART_NAME" "RES"
					( Origin gPackager )
				)
				( attribute "CDS_PART_NAME" "RES_0402-10.0K,1%,1/16W,CHIP,GA"
					( Origin gPackager )
				)
				( objectStatus "R7C23" )
				( pin "a"
					( attribute "PN" "1"
						( Origin gPackager )
					)
					( objectStatus "R7C23.1" )
				)
				( pin "b"
					( attribute "PN" "2"
						( Origin gPackager )
					)
					( objectStatus "R7C23.2" )
				)
			)
			( gate "@baseboard_fab2_lib.baseboard_fab2(sch_1):page119_i115"
				( attribute "BOM_COST" "SB"
					( Origin gFrontEnd )
				)
				( attribute "CDS_LIB" "mstr_u_proc"
					( Origin gPackager )
				)
				( attribute "CDS_LOCATION" "U7C1"
					( Origin gPackager )
				)
				( attribute "CDS_SEC" "6"
					( Origin gPackager )
				)
				( attribute "LOCATION" "U7C1"
					( Origin gFrontEnd )
				)
				( attribute "MATERIAL" "IC"
					( Origin gFrontEnd )
				)
				( attribute "PACK_TYPE" "BGA1"
					( Origin gFrontEnd )
				)
				( attribute "PART_NUMBER" "H91415-002"
					( Origin gFrontEnd )
				)
				( attribute "PHYS_PAGE" "119"
					( Origin gFrontEnd )
				)
				( attribute "ROOM" "SB"
					( Origin gFrontEnd )
				)
				( attribute "ROT" "0"
					( Origin gFrontEnd )
				)
				( attribute "SEC" "6"
					( Origin gFrontEnd )
				)
				( attribute "SEC_TYPE" "BGA1"
					( Origin gFrontEnd )
				)
				( attribute "VER" "6"
					( Origin gFrontEnd )
				)
				( attribute "XY" "(-4200,3200)"
					( Origin gFrontEnd )
				)
				( attribute "CHIPS_PART_NAME" "LBG_CORE_QAT_EXT_D"
					( Origin gPackager )
				)
				( attribute "CDS_PART_NAME" "LBG_CORE_QAT_EXT_D_BGA1-IC,H91A"
					( Origin gPackager )
				)
				( objectStatus "U7C1" )
				( pin "gpp_a0_rcin_n_espi_alert1_n"
					( attribute "PN" "N3"
						( Origin gPackager )
					)
					( objectStatus "U7C1.N3" )
				)
				( pin "gpp_a1_lad0_espi_io0"
					( attribute "PN" "Y3"
						( Origin gPackager )
					)
					( objectStatus "U7C1.Y3" )
				)
				( pin "gpp_a2_lad1_espi_io1"
					( attribute "PN" "N1"
						( Origin gPackager )
					)
					( objectStatus "U7C1.N1" )
				)
				( pin "gpp_a3_lad2_espi_io2"
					( attribute "PN" "W2"
						( Origin gPackager )
					)
					( objectStatus "U7C1.W2" )
				)
				( pin "gpp_a4_lad3_espi_io3"
					( attribute "PN" "Y1"
						( Origin gPackager )
					)
					( objectStatus "U7C1.Y1" )
				)
				( pin "gpp_a5_lframe_n_espi_cs0_n"
					( attribute "PN" "P4"
						( Origin gPackager )
					)
					( objectStatus "U7C1.P4" )
				)
				( pin "gpp_a6_serirq_espi_cs1_n"
					( attribute "PN" "P2"
						( Origin gPackager )
					)
					( objectStatus "U7C1.P2" )
				)
				( pin "gpp_a7_pirqa_n_espi_alert0_n"
					( attribute "PN" "AA2"
						( Origin gPackager )
					)
					( objectStatus "U7C1.AA2" )
				)
				( pin "gpp_a8_clkrun_n"
					( attribute "PN" "AB1"
						( Origin gPackager )
					)
					( objectStatus "U7C1.AB1" )
				)
				( pin "gpp_a9_clkout_lpc0_espi_clk"
					( attribute "PN" "R3"
						( Origin gPackager )
					)
					( objectStatus "U7C1.R3" )
				)
				( pin "gpp_a10_clkout_lpc1"
					( attribute "PN" "AA4"
						( Origin gPackager )
					)
					( objectStatus "U7C1.AA4" )
				)
				( pin "gpp_a11_pme_n"
					( attribute "PN" "AC2"
						( Origin gPackager )
					)
					( objectStatus "U7C1.AC2" )
				)
				( pin "gpp_a12_bmbusy_n_sxexithldoff_n"
					( attribute "PN" "R1"
						( Origin gPackager )
					)
					( objectStatus "U7C1.R1" )
				)
				( pin "gpp_a13_suswarn_n_suspwrdnack"
					( attribute "PN" "T4"
						( Origin gPackager )
					)
					( objectStatus "U7C1.T4" )
				)
				( pin "gpp_a14_espi_reset_n"
					( attribute "PN" "AB3"
						( Origin gPackager )
					)
					( objectStatus "U7C1.AB3" )
				)
				( pin "gpp_a15_susack_n"
					( attribute "PN" "AC4"
						( Origin gPackager )
					)
					( objectStatus "U7C1.AC4" )
				)
				( pin "gpp_a16_clkout_lpc2"
					( attribute "PN" "T2"
						( Origin gPackager )
					)
					( objectStatus "U7C1.T2" )
				)
				( pin "gpp_a17"
					( attribute "PN" "AD1"
						( Origin gPackager )
					)
					( objectStatus "U7C1.AD1" )
				)
				( pin "gpp_a18"
					( attribute "PN" "AD3"
						( Origin gPackager )
					)
					( objectStatus "U7C1.AD3" )
				)
				( pin "gpp_a19"
					( attribute "PN" "V3"
						( Origin gPackager )
					)
					( objectStatus "U7C1.V3" )
				)
				( pin "gpp_a20"
					( attribute "PN" "W4"
						( Origin gPackager )
					)
					( objectStatus "U7C1.W4" )
				)
				( pin "gpp_a21"
					( attribute "PN" "AE2"
						( Origin gPackager )
					)
					( objectStatus "U7C1.AE2" )
				)
				( pin "gpp_a22"
					( attribute "PN" "AE4"
						( Origin gPackager )
					)
					( objectStatus "U7C1.AE4" )
				)
				( pin "gpp_a23"
					( attribute "PN" "V1"
						( Origin gPackager )
					)
					( objectStatus "U7C1.V1" )
				)
				( pin "gpp_b0_core_vid0"
					( attribute "PN" "BL7"
						( Origin gPackager )
					)
					( objectStatus "U7C1.BL7" )
				)
				( pin "gpp_b1_core_vid1"
					( attribute "PN" "BH9"
						( Origin gPackager )
					)
					( objectStatus "U7C1.BH9" )
				)
				( pin "gpp_b2"
					( attribute "PN" "BN15"
						( Origin gPackager )
					)
					( objectStatus "U7C1.BN15" )
				)
				( pin "gpp_b3_cpu_gp2"
					( attribute "PN" "BR9"
						( Origin gPackager )
					)
					( objectStatus "U7C1.BR9" )
				)
				( pin "gpp_b4_cpu_gp3"
					( attribute "PN" "BN7"
						( Origin gPackager )
					)
					( objectStatus "U7C1.BN7" )
				)
				( pin "gpp_b5_srcclkreq0_n"
					( attribute "PN" "BK17"
						( Origin gPackager )
					)
					( objectStatus "U7C1.BK17" )
				)
				( pin "gpp_b6_srcclkreq1_n"
					( attribute "PN" "BG18"
						( Origin gPackager )
					)
					( objectStatus "U7C1.BG18" )
				)
				( pin "gpp_b7_srcclkreq2_n"
					( attribute "PN" "BR13"
						( Origin gPackager )
					)
					( objectStatus "U7C1.BR13" )
				)
				( pin "gpp_b8_srcclkreq3_n"
					( attribute "PN" "BN11"
						( Origin gPackager )
					)
					( objectStatus "U7C1.BN11" )
				)
				( pin "gpp_b9_srcclkreq4_n"
					( attribute "PN" "BH20"
						( Origin gPackager )
					)
					( objectStatus "U7C1.BH20" )
				)
				( pin "gpp_b10_srcclkreq5_n"
					( attribute "PN" "BL11"
						( Origin gPackager )
					)
					( objectStatus "U7C1.BL11" )
				)
				( pin "gpp_b11"
					( attribute "PN" "BK9"
						( Origin gPackager )
					)
					( objectStatus "U7C1.BK9" )
				)
				( pin "gpp_b12_glb_rst_warn_n"
					( attribute "PN" "BL18"
						( Origin gPackager )
					)
					( objectStatus "U7C1.BL18" )
				)
				( pin "gpp_b13_pltrst_n"
					( attribute "PN" "BN18"
						( Origin gPackager )
					)
					( objectStatus "U7C1.BN18" )
				)
				( pin "gpp_b14_spkr"
					( attribute "PN" "BH13"
						( Origin gPackager )
					)
					( objectStatus "U7C1.BH13" )
				)
				( pin "gpp_b15"
					( attribute "PN" "BK13"
						( Origin gPackager )
					)
					( objectStatus "U7C1.BK13" )
				)
				( pin "gpp_b16"
					( attribute "PN" "BG22"
						( Origin gPackager )
					)
					( objectStatus "U7C1.BG22" )
				)
				( pin "gpp_b17"
					( attribute "PN" "BG15"
						( Origin gPackager )
					)
					( objectStatus "U7C1.BG15" )
				)
				( pin "gpp_b18"
					( attribute "PN" "BL15"
						( Origin gPackager )
					)
					( objectStatus "U7C1.BL15" )
				)
				( pin "gpp_b19"
					( attribute "PN" "BK20"
						( Origin gPackager )
					)
					( objectStatus "U7C1.BK20" )
				)
				( pin "gpp_b20"
					( attribute "PN" "BJ22"
						( Origin gPackager )
					)
					( objectStatus "U7C1.BJ22" )
				)
				( pin "gpp_b21"
					( attribute "PN" "BH17"
						( Origin gPackager )
					)
					( objectStatus "U7C1.BH17" )
				)
				( pin "gpp_b22"
					( attribute "PN" "BR17"
						( Origin gPackager )
					)
					( objectStatus "U7C1.BR17" )
				)
				( pin "gpp_b23_meie_sml1alrt_n_phot_n"
					( attribute "PN" "BM20"
						( Origin gPackager )
					)
					( objectStatus "U7C1.BM20" )
				)
				( pin "gpp_c0_smbclk"
					( attribute "PN" "BW28"
						( Origin gPackager )
					)
					( objectStatus "U7C1.BW28" )
				)
				( pin "gpp_c1_smbdata"
					( attribute "PN" "BV27"
						( Origin gPackager )
					)
					( objectStatus "U7C1.BV27" )
				)
				( pin "gpp_c2_smbalert_n"
					( attribute "PN" "BY27"
						( Origin gPackager )
					)
					( objectStatus "U7C1.BY27" )
				)
				( pin "gpp_c3_sml0clk_ie"
					( attribute "PN" "BV29"
						( Origin gPackager )
					)
					( objectStatus "U7C1.BV29" )
				)
				( pin "gpp_c4_sml0data_ie"
					( attribute "PN" "BW30"
						( Origin gPackager )
					)
					( objectStatus "U7C1.BW30" )
				)
				( pin "gpp_c5_sml0alert_ie_n"
					( attribute "PN" "BW34"
						( Origin gPackager )
					)
					( objectStatus "U7C1.BW34" )
				)
				( pin "gpp_c6_sml1clk_ie"
					( attribute "PN" "CA28"
						( Origin gPackager )
					)
					( objectStatus "U7C1.CA28" )
				)
				( pin "gpp_c7_sml1data_ie"
					( attribute "PN" "BV35"
						( Origin gPackager )
					)
					( objectStatus "U7C1.BV35" )
				)
				( pin "gpp_c8"
					( attribute "PN" "BW32"
						( Origin gPackager )
					)
					( objectStatus "U7C1.BW32" )
				)
				( pin "gpp_c9"
					( attribute "PN" "BY29"
						( Origin gPackager )
					)
					( objectStatus "U7C1.BY29" )
				)
				( pin "gpp_c10"
					( attribute "PN" "BV31"
						( Origin gPackager )
					)
					( objectStatus "U7C1.BV31" )
				)
				( pin "gpp_c11"
					( attribute "PN" "BV33"
						( Origin gPackager )
					)
					( objectStatus "U7C1.BV33" )
				)
				( pin "gpp_c12"
					( attribute "PN" "CA30"
						( Origin gPackager )
					)
					( objectStatus "U7C1.CA30" )
				)
				( pin "gpp_c13"
					( attribute "PN" "BV38"
						( Origin gPackager )
					)
					( objectStatus "U7C1.BV38" )
				)
				( pin "gpp_c14"
					( attribute "PN" "BY38"
						( Origin gPackager )
					)
					( objectStatus "U7C1.BY38" )
				)
				( pin "gpp_c15"
					( attribute "PN" "CA32"
						( Origin gPackager )
					)
					( objectStatus "U7C1.CA32" )
				)
				( pin "gpp_c16"
					( attribute "PN" "BW37"
						( Origin gPackager )
					)
					( objectStatus "U7C1.BW37" )
				)
				( pin "gpp_c17"
					( attribute "PN" "BY31"
						( Origin gPackager )
					)
					( objectStatus "U7C1.BY31" )
				)
				( pin "gpp_c18"
					( attribute "PN" "BY35"
						( Origin gPackager )
					)
					( objectStatus "U7C1.BY35" )
				)
				( pin "gpp_c19"
					( attribute "PN" "BW39"
						( Origin gPackager )
					)
					( objectStatus "U7C1.BW39" )
				)
				( pin "gpp_c20"
					( attribute "PN" "CA39"
						( Origin gPackager )
					)
					( objectStatus "U7C1.CA39" )
				)
				( pin "gpp_c21"
					( attribute "PN" "BY33"
						( Origin gPackager )
					)
					( objectStatus "U7C1.BY33" )
				)
				( pin "gpp_c22"
					( attribute "PN" "CA34"
						( Origin gPackager )
					)
					( objectStatus "U7C1.CA34" )
				)
				( pin "gpp_c23"
					( attribute "PN" "CA37"
						( Origin gPackager )
					)
					( objectStatus "U7C1.CA37" )
				)
				( pin "gpp_d0"
					( attribute "PN" "BR42"
						( Origin gPackager )
					)
					( objectStatus "U7C1.BR42" )
				)
				( pin "gpp_d1"
					( attribute "PN" "BK46"
						( Origin gPackager )
					)
					( objectStatus "U7C1.BK46" )
				)
				( pin "gpp_d2"
					( attribute "PN" "BJ44"
						( Origin gPackager )
					)
					( objectStatus "U7C1.BJ44" )
				)
				( pin "gpp_d3"
					( attribute "PN" "BW45"
						( Origin gPackager )
					)
					( objectStatus "U7C1.BW45" )
				)
				( pin "gpp_d4"
					( attribute "PN" "BM42"
						( Origin gPackager )
					)
					( objectStatus "U7C1.BM42" )
				)
				( pin "gpp_d5"
					( attribute "PN" "BM38"
						( Origin gPackager )
					)
					( objectStatus "U7C1.BM38" )
				)
				( pin "gpp_d6"
					( attribute "PN" "BW41"
						( Origin gPackager )
					)
					( objectStatus "U7C1.BW41" )
				)
				( pin "gpp_d7"
					( attribute "PN" "CA45"
						( Origin gPackager )
					)
					( objectStatus "U7C1.CA45" )
				)
				( pin "gpp_d8"
					( attribute "PN" "BR38"
						( Origin gPackager )
					)
					( objectStatus "U7C1.BR38" )
				)
				( pin "gpp_d9_ssata_devslp3"
					( attribute "PN" "BY42"
						( Origin gPackager )
					)
					( objectStatus "U7C1.BY42" )
				)
				( pin "gpp_d10_ssata_devslp4"
					( attribute "PN" "BV47"
						( Origin gPackager )
					)
					( objectStatus "U7C1.BV47" )
				)
				( pin "gpp_d11_ssata_devslp5"
					( attribute "PN" "BY47"
						( Origin gPackager )
					)
					( objectStatus "U7C1.BY47" )
				)
				( pin "gpp_d12_ssata_sdataout1"
					( attribute "PN" "BN40"
						( Origin gPackager )
					)
					( objectStatus "U7C1.BN40" )
				)
				( pin "gpp_d13_sml0bclk_ie"
					( attribute "PN" "BY44"
						( Origin gPackager )
					)
					( objectStatus "U7C1.BY44" )
				)
				( pin "gpp_d14_sml0bdata_ie"
					( attribute "PN" "BL44"
						( Origin gPackager )
					)
					( objectStatus "U7C1.BL44" )
				)
				( pin "gpp_d15_ssata_sdataout0"
					( attribute "PN" "BW43"
						( Origin gPackager )
					)
					( objectStatus "U7C1.BW43" )
				)
				( pin "gpp_d16_sml0balert_ie_n"
					( attribute "PN" "BV42"
						( Origin gPackager )
					)
					( objectStatus "U7C1.BV42" )
				)
				( pin "gpp_d17"
					( attribute "PN" "BW48"
						( Origin gPackager )
					)
					( objectStatus "U7C1.BW48" )
				)
				( pin "gpp_d18"
					( attribute "PN" "CA41"
						( Origin gPackager )
					)
					( objectStatus "U7C1.CA41" )
				)
				( pin "gpp_d19"
					( attribute "PN" "CA43"
						( Origin gPackager )
					)
					( objectStatus "U7C1.CA43" )
				)
				( pin "gpp_d20"
					( attribute "PN" "CA48"
						( Origin gPackager )
					)
					( objectStatus "U7C1.CA48" )
				)
				( pin "gpp_d21_ie_uart_rx"
					( attribute "PN" "BV44"
						( Origin gPackager )
					)
					( objectStatus "U7C1.BV44" )
				)
				( pin "gpp_d22_ie_uart_tx"
					( attribute "PN" "BR46"
						( Origin gPackager )
					)
					( objectStatus "U7C1.BR46" )
				)
				( pin "gpp_d23"
					( attribute "PN" "BN44"
						( Origin gPackager )
					)
					( objectStatus "U7C1.BN44" )
				)
			)
			( gate "@baseboard_fab2_lib.baseboard_fab2(sch_1):page119_i172"
				( attribute "CDS_LIB" "mstr_discrete"
					( Origin gPackager )
				)
				( attribute "CDS_LOCATION" "R2M3"
					( Origin gPackager )
				)
				( attribute "CDS_SEC" "1"
					( Origin gPackager )
				)
				( attribute "LOCATION" "R2M3"
					( Origin gFrontEnd )
				)
				( attribute "MATERIAL" "CHIP"
					( Origin gFrontEnd )
				)
				( attribute "PACK_TYPE" "0402"
					( Origin gFrontEnd )
				)
				( attribute "PART_NUMBER" "G21796-074"
					( Origin gFrontEnd )
				)
				( attribute "PHYS_PAGE" "119"
					( Origin gFrontEnd )
				)
				( attribute "ROOM" "CPLD"
					( Origin gFrontEnd )
				)
				( attribute "ROT" "0"
					( Origin gFrontEnd )
				)
				( attribute "SEC" "1"
					( Origin gFrontEnd )
				)
				( attribute "SEC_TYPE" "0402"
					( Origin gFrontEnd )
				)
				( attribute "TOLERANCE" "1%"
					( Origin gFrontEnd )
				)
				( attribute "VALUE" "33.2"
					( Origin gFrontEnd )
				)
				( attribute "VER" "1"
					( Origin gFrontEnd )
				)
				( attribute "WATTAGE" "1/16W"
					( Origin gFrontEnd )
				)
				( attribute "XY" "(-1450,2200)"
					( Origin gFrontEnd )
				)
				( attribute "CHIPS_PART_NAME" "RES"
					( Origin gPackager )
				)
				( attribute "CDS_PART_NAME" "RES_0402-33.2,1%,1/16W,CHIP,G2A"
					( Origin gPackager )
				)
				( objectStatus "R2M3" )
				( pin "a"
					( attribute "PN" "1"
						( Origin gPackager )
					)
					( objectStatus "R2M3.1" )
				)
				( pin "b"
					( attribute "PN" "2"
						( Origin gPackager )
					)
					( objectStatus "R2M3.2" )
				)
			)
			( gate "@baseboard_fab2_lib.baseboard_fab2(sch_1):page119_i173"
				( attribute "CDS_LIB" "mstr_discrete"
					( Origin gPackager )
				)
				( attribute "CDS_LOCATION" "R2N1"
					( Origin gPackager )
				)
				( attribute "CDS_SEC" "1"
					( Origin gPackager )
				)
				( attribute "LOCATION" "R2N1"
					( Origin gFrontEnd )
				)
				( attribute "MATERIAL" "CHIP"
					( Origin gFrontEnd )
				)
				( attribute "PACK_TYPE" "0402"
					( Origin gFrontEnd )
				)
				( attribute "PART_NUMBER" "G21796-074"
					( Origin gFrontEnd )
				)
				( attribute "PHYS_PAGE" "119"
					( Origin gFrontEnd )
				)
				( attribute "ROOM" "CPLD"
					( Origin gFrontEnd )
				)
				( attribute "ROT" "0"
					( Origin gFrontEnd )
				)
				( attribute "SEC" "1"
					( Origin gFrontEnd )
				)
				( attribute "SEC_TYPE" "0402"
					( Origin gFrontEnd )
				)
				( attribute "TOLERANCE" "1%"
					( Origin gFrontEnd )
				)
				( attribute "VALUE" "33.2"
					( Origin gFrontEnd )
				)
				( attribute "VER" "1"
					( Origin gFrontEnd )
				)
				( attribute "WATTAGE" "1/16W"
					( Origin gFrontEnd )
				)
				( attribute "XY" "(-1550,4400)"
					( Origin gFrontEnd )
				)
				( attribute "CHIPS_PART_NAME" "RES"
					( Origin gPackager )
				)
				( attribute "CDS_PART_NAME" "RES_0402-33.2,1%,1/16W,CHIP,G2A"
					( Origin gPackager )
				)
				( objectStatus "R2N1" )
				( pin "a"
					( attribute "PN" "1"
						( Origin gPackager )
					)
					( objectStatus "R2N1.1" )
				)
				( pin "b"
					( attribute "PN" "2"
						( Origin gPackager )
					)
					( objectStatus "R2N1.2" )
				)
			)
			( gate "@baseboard_fab2_lib.baseboard_fab2(sch_1):page119_i174"
				( attribute "CDS_LIB" "mstr_discrete"
					( Origin gPackager )
				)
				( attribute "CDS_LOCATION" "R2M7"
					( Origin gPackager )
				)
				( attribute "CDS_SEC" "1"
					( Origin gPackager )
				)
				( attribute "LOCATION" "R2M7"
					( Origin gFrontEnd )
				)
				( attribute "MATERIAL" "CHIP"
					( Origin gFrontEnd )
				)
				( attribute "PACK_TYPE" "0402"
					( Origin gFrontEnd )
				)
				( attribute "PART_NUMBER" "G21796-074"
					( Origin gFrontEnd )
				)
				( attribute "PHYS_PAGE" "119"
					( Origin gFrontEnd )
				)
				( attribute "ROOM" "CPLD"
					( Origin gFrontEnd )
				)
				( attribute "ROT" "0"
					( Origin gFrontEnd )
				)
				( attribute "SEC" "1"
					( Origin gFrontEnd )
				)
				( attribute "SEC_TYPE" "0402"
					( Origin gFrontEnd )
				)
				( attribute "TOLERANCE" "1%"
					( Origin gFrontEnd )
				)
				( attribute "VALUE" "33.2"
					( Origin gFrontEnd )
				)
				( attribute "VER" "1"
					( Origin gFrontEnd )
				)
				( attribute "WATTAGE" "1/16W"
					( Origin gFrontEnd )
				)
				( attribute "XY" "(-1475,2950)"
					( Origin gFrontEnd )
				)
				( attribute "CHIPS_PART_NAME" "RES"
					( Origin gPackager )
				)
				( attribute "CDS_PART_NAME" "RES_0402-33.2,1%,1/16W,CHIP,G2A"
					( Origin gPackager )
				)
				( objectStatus "R2M7" )
				( pin "a"
					( attribute "PN" "1"
						( Origin gPackager )
					)
					( objectStatus "R2M7.1" )
				)
				( pin "b"
					( attribute "PN" "2"
						( Origin gPackager )
					)
					( objectStatus "R2M7.2" )
				)
			)
			( gate "@baseboard_fab2_lib.baseboard_fab2(sch_1):page119_i175"
				( attribute "BOM_COST" "SB"
					( Origin gFrontEnd )
				)
				( attribute "CDS_LIB" "mstr_discrete"
					( Origin gPackager )
				)
				( attribute "CDS_LOCATION" "Q9A2"
					( Origin gPackager )
				)
				( attribute "CDS_SEC" "1"
					( Origin gPackager )
				)
				( attribute "LOCATION" "Q9A2"
					( Origin gFrontEnd )
				)
				( attribute "MATERIAL" "FET"
					( Origin gFrontEnd )
				)
				( attribute "PACK_TYPE" "SMLF"
					( Origin gFrontEnd )
				)
				( attribute "PART_NUMBER" "E40049-001"
					( Origin gFrontEnd )
				)
				( attribute "PHYS_PAGE" "119"
					( Origin gFrontEnd )
				)
				( attribute "ROOM" "SB"
					( Origin gFrontEnd )
				)
				( attribute "ROT" "0"
					( Origin gFrontEnd )
				)
				( attribute "SEC" "1"
					( Origin gFrontEnd )
				)
				( attribute "SEC_TYPE" "SMLF"
					( Origin gFrontEnd )
				)
				( attribute "VALUE" "NTJD4001N"
					( Origin gFrontEnd )
				)
				( attribute "VER" "5"
					( Origin gFrontEnd )
				)
				( attribute "XY" "(-2525,775)"
					( Origin gFrontEnd )
				)
				( attribute "CHIPS_PART_NAME" "FET_N_DUAL"
					( Origin gPackager )
				)
				( attribute "CDS_PART_NAME" "FET_N_DUAL_SMLF-NTJD4001N,FET,A"
					( Origin gPackager )
				)
				( objectStatus "Q9A2" )
				( pin "drain(0)"
					( attribute "PN" "6"
						( Origin gPackager )
					)
					( objectStatus "Q9A2.6" )
				)
				( pin "gate(0)"
					( attribute "PN" "2"
						( Origin gPackager )
					)
					( objectStatus "Q9A2.2" )
				)
				( pin "source(0)"
					( attribute "PN" "1"
						( Origin gPackager )
					)
					( objectStatus "Q9A2.1" )
				)
			)
			( gate "@baseboard_fab2_lib.baseboard_fab2(sch_1):page119_i178"
				( attribute "BOM_COST" "SB"
					( Origin gFrontEnd )
				)
				( attribute "CDS_LIB" "mstr_discrete"
					( Origin gPackager )
				)
				( attribute "CDS_LOCATION" "R9A20"
					( Origin gPackager )
				)
				( attribute "CDS_SEC" "1"
					( Origin gPackager )
				)
				( attribute "LOCATION" "R9A20"
					( Origin gFrontEnd )
				)
				( attribute "MATERIAL" "CHIP"
					( Origin gFrontEnd )
				)
				( attribute "PACK_TYPE" "0402"
					( Origin gFrontEnd )
				)
				( attribute "PART_NUMBER" "G21796-271"
					( Origin gFrontEnd )
				)
				( attribute "PHYS_PAGE" "119"
					( Origin gFrontEnd )
				)
				( attribute "ROOM" "SB"
					( Origin gFrontEnd )
				)
				( attribute "ROT" "0"
					( Origin gFrontEnd )
				)
				( attribute "SEC" "1"
					( Origin gFrontEnd )
				)
				( attribute "SEC_TYPE" "0402"
					( Origin gFrontEnd )
				)
				( attribute "TOLERANCE" "1.0%"
					( Origin gFrontEnd )
				)
				( attribute "VALUE" "221"
					( Origin gFrontEnd )
				)
				( attribute "VER" "1"
					( Origin gFrontEnd )
				)
				( attribute "WATTAGE" "1/16W"
					( Origin gFrontEnd )
				)
				( attribute "XY" "(-700,1575)"
					( Origin gFrontEnd )
				)
				( attribute "CHIPS_PART_NAME" "RES"
					( Origin gPackager )
				)
				( attribute "CDS_PART_NAME" "RES_0402-221,1.0%,1/16W,CHIP,GA"
					( Origin gPackager )
				)
				( objectStatus "R9A20" )
				( pin "a"
					( attribute "PN" "1"
						( Origin gPackager )
					)
					( objectStatus "R9A20.1" )
				)
				( pin "b"
					( attribute "PN" "2"
						( Origin gPackager )
					)
					( objectStatus "R9A20.2" )
				)
			)
			( gate "@baseboard_fab2_lib.baseboard_fab2(sch_1):page119_i179"
				( attribute "BOM_COST" "SB"
					( Origin gFrontEnd )
				)
				( attribute "CDS_LIB" "mstr_discrete"
					( Origin gPackager )
				)
				( attribute "CDS_LOCATION" "DS9A5"
					( Origin gPackager )
				)
				( attribute "CDS_SEC" "1"
					( Origin gPackager )
				)
				( attribute "COLOR" "GREEN"
					( Origin gFrontEnd )
				)
				( attribute "LOCATION" "DS9A5"
					( Origin gFrontEnd )
				)
				( attribute "MATERIAL" "IC"
					( Origin gFrontEnd )
				)
				( attribute "PACK_TYPE" "A1LF"
					( Origin gFrontEnd )
				)
				( attribute "PART_NUMBER" "C97278-010"
					( Origin gFrontEnd )
				)
				( attribute "PHYS_PAGE" "119"
					( Origin gFrontEnd )
				)
				( attribute "ROOM" "SB"
					( Origin gFrontEnd )
				)
				( attribute "ROT" "0"
					( Origin gFrontEnd )
				)
				( attribute "SEC" "1"
					( Origin gFrontEnd )
				)
				( attribute "SEC_TYPE" "A1LF"
					( Origin gFrontEnd )
				)
				( attribute "VER" "3"
					( Origin gFrontEnd )
				)
				( attribute "XY" "(-1350,1575)"
					( Origin gFrontEnd )
				)
				( attribute "CHIPS_PART_NAME" "LED"
					( Origin gPackager )
				)
				( attribute "CDS_PART_NAME" "LED_A1LF-GREEN,IC,C97278-010"
					( Origin gPackager )
				)
				( objectStatus "DS9A5" )
				( pin "a"
					( attribute "PN" "1"
						( Origin gPackager )
					)
					( objectStatus "DS9A5.1" )
				)
				( pin "c"
					( attribute "PN" "2"
						( Origin gPackager )
					)
					( objectStatus "DS9A5.2" )
				)
			)
			( gate "@baseboard_fab2_lib.baseboard_fab2(sch_1):page119_i180"
				( attribute "BOM_COST" "SB"
					( Origin gFrontEnd )
				)
				( attribute "CDS_LIB" "mstr_discrete"
					( Origin gPackager )
				)
				( attribute "CDS_LOCATION" "Q9A2"
					( Origin gPackager )
				)
				( attribute "CDS_SEC" "2"
					( Origin gPackager )
				)
				( attribute "LOCATION" "Q9A2"
					( Origin gFrontEnd )
				)
				( attribute "MATERIAL" "FET"
					( Origin gFrontEnd )
				)
				( attribute "PACK_TYPE" "SMLF"
					( Origin gFrontEnd )
				)
				( attribute "PART_NUMBER" "E40049-001"
					( Origin gFrontEnd )
				)
				( attribute "PHYS_PAGE" "119"
					( Origin gFrontEnd )
				)
				( attribute "ROOM" "SB"
					( Origin gFrontEnd )
				)
				( attribute "ROT" "0"
					( Origin gFrontEnd )
				)
				( attribute "SEC" "2"
					( Origin gFrontEnd )
				)
				( attribute "SEC_TYPE" "SMLF"
					( Origin gFrontEnd )
				)
				( attribute "VALUE" "NTJD4001N"
					( Origin gFrontEnd )
				)
				( attribute "VER" "5"
					( Origin gFrontEnd )
				)
				( attribute "XY" "(-1750,1250)"
					( Origin gFrontEnd )
				)
				( attribute "CHIPS_PART_NAME" "FET_N_DUAL"
					( Origin gPackager )
				)
				( attribute "CDS_PART_NAME" "FET_N_DUAL_SMLF-NTJD4001N,FET,A"
					( Origin gPackager )
				)
				( objectStatus "Q9A2" )
				( pin "drain(0)"
					( attribute "PN" "3"
						( Origin gPackager )
					)
					( objectStatus "Q9A2.3" )
				)
				( pin "gate(0)"
					( attribute "PN" "5"
						( Origin gPackager )
					)
					( objectStatus "Q9A2.5" )
				)
				( pin "source(0)"
					( attribute "PN" "4"
						( Origin gPackager )
					)
					( objectStatus "Q9A2.4" )
				)
			)
			( gate "@baseboard_fab2_lib.baseboard_fab2(sch_1):page119_i183"
				( attribute "BOM_COST" "SB"
					( Origin gFrontEnd )
				)
				( attribute "CDS_LIB" "mstr_discrete"
					( Origin gPackager )
				)
				( attribute "CDS_LOCATION" "R9A18"
					( Origin gPackager )
				)
				( attribute "CDS_SEC" "1"
					( Origin gPackager )
				)
				( attribute "LOCATION" "R9A18"
					( Origin gFrontEnd )
				)
				( attribute "MATERIAL" "CHIP"
					( Origin gFrontEnd )
				)
				( attribute "PACK_TYPE" "0402"
					( Origin gFrontEnd )
				)
				( attribute "PART_NUMBER" "G21796-072"
					( Origin gFrontEnd )
				)
				( attribute "PHYS_PAGE" "119"
					( Origin gFrontEnd )
				)
				( attribute "ROOM" "SB"
					( Origin gFrontEnd )
				)
				( attribute "ROT" "0"
					( Origin gFrontEnd )
				)
				( attribute "SEC" "1"
					( Origin gFrontEnd )
				)
				( attribute "SEC_TYPE" "0402"
					( Origin gFrontEnd )
				)
				( attribute "TOLERANCE" "1%"
					( Origin gFrontEnd )
				)
				( attribute "VALUE" "4.75K"
					( Origin gFrontEnd )
				)
				( attribute "VER" "2"
					( Origin gFrontEnd )
				)
				( attribute "WATTAGE" "1/16W"
					( Origin gFrontEnd )
				)
				( attribute "XY" "(-2525,1400)"
					( Origin gFrontEnd )
				)
				( attribute "CHIPS_PART_NAME" "RES"
					( Origin gPackager )
				)
				( attribute "CDS_PART_NAME" "RES_0402-4.75K,1%,1/16W,CHIP,GA"
					( Origin gPackager )
				)
				( objectStatus "R9A18" )
				( pin "a"
					( attribute "PN" "1"
						( Origin gPackager )
					)
					( objectStatus "R9A18.1" )
				)
				( pin "b"
					( attribute "PN" "2"
						( Origin gPackager )
					)
					( objectStatus "R9A18.2" )
				)
			)
			( gate "@baseboard_fab2_lib.baseboard_fab2(sch_1):page119_i186"
				( attribute "BOM_COST" "SB"
					( Origin gFrontEnd )
				)
				( attribute "CDS_LIB" "mstr_discrete"
					( Origin gPackager )
				)
				( attribute "CDS_LOCATION" "R9A21"
					( Origin gPackager )
				)
				( attribute "CDS_SEC" "1"
					( Origin gPackager )
				)
				( attribute "LOCATION" "R9A21"
					( Origin gFrontEnd )
				)
				( attribute "MATERIAL" "CHIP"
					( Origin gFrontEnd )
				)
				( attribute "PACK_TYPE" "0402"
					( Origin gFrontEnd )
				)
				( attribute "PART_NUMBER" "G21796-072"
					( Origin gFrontEnd )
				)
				( attribute "PHYS_PAGE" "119"
					( Origin gFrontEnd )
				)
				( attribute "ROOM" "SB"
					( Origin gFrontEnd )
				)
				( attribute "ROT" "0"
					( Origin gFrontEnd )
				)
				( attribute "SEC" "1"
					( Origin gFrontEnd )
				)
				( attribute "SEC_TYPE" "0402"
					( Origin gFrontEnd )
				)
				( attribute "TOLERANCE" "1%"
					( Origin gFrontEnd )
				)
				( attribute "VALUE" "4.75K"
					( Origin gFrontEnd )
				)
				( attribute "VER" "2"
					( Origin gFrontEnd )
				)
				( attribute "WATTAGE" "1/16W"
					( Origin gFrontEnd )
				)
				( attribute "XY" "(-2975,950)"
					( Origin gFrontEnd )
				)
				( attribute "CHIPS_PART_NAME" "RES"
					( Origin gPackager )
				)
				( attribute "CDS_PART_NAME" "RES_0402-4.75K,1%,1/16W,CHIP,GA"
					( Origin gPackager )
				)
				( objectStatus "R9A21" )
				( pin "a"
					( attribute "PN" "1"
						( Origin gPackager )
					)
					( objectStatus "R9A21.1" )
				)
				( pin "b"
					( attribute "PN" "2"
						( Origin gPackager )
					)
					( objectStatus "R9A21.2" )
				)
			)
			( gate "@baseboard_fab2_lib.baseboard_fab2(sch_1):page119_i189"
				( attribute "BOM_COST" "SM_CONTROLLER"
					( Origin gFrontEnd )
				)
				( attribute "CDS_LIB" "mstr_discrete"
					( Origin gPackager )
				)
				( attribute "CDS_LOCATION" "R7C26"
					( Origin gPackager )
				)
				( attribute "CDS_SEC" "1"
					( Origin gPackager )
				)
				( attribute "LOCATION" "R7C26"
					( Origin gFrontEnd )
				)
				( attribute "MATERIAL" "CHIP"
					( Origin gFrontEnd )
				)
				( attribute "PACK_TYPE" "0402"
					( Origin gFrontEnd )
				)
				( attribute "PART_NUMBER" "G21796-074"
					( Origin gFrontEnd )
				)
				( attribute "PHYS_PAGE" "119"
					( Origin gFrontEnd )
				)
				( attribute "ROOM" "SYS_CLOCK"
					( Origin gFrontEnd )
				)
				( attribute "ROT" "0"
					( Origin gFrontEnd )
				)
				( attribute "SEC" "1"
					( Origin gFrontEnd )
				)
				( attribute "SEC_TYPE" "0402"
					( Origin gFrontEnd )
				)
				( attribute "TOLERANCE" "1%"
					( Origin gFrontEnd )
				)
				( attribute "VALUE" "33.2"
					( Origin gFrontEnd )
				)
				( attribute "VER" "1"
					( Origin gFrontEnd )
				)
				( attribute "WATTAGE" "1/16W"
					( Origin gFrontEnd )
				)
				( attribute "XY" "(-6750,3700)"
					( Origin gFrontEnd )
				)
				( attribute "CHIPS_PART_NAME" "RES"
					( Origin gPackager )
				)
				( attribute "CDS_PART_NAME" "RES_0402-33.2,1%,1/16W,CHIP,G2A"
					( Origin gPackager )
				)
				( objectStatus "R7C26" )
				( pin "a"
					( attribute "PN" "1"
						( Origin gPackager )
					)
					( objectStatus "R7C26.1" )
				)
				( pin "b"
					( attribute "PN" "2"
						( Origin gPackager )
					)
					( objectStatus "R7C26.2" )
				)
			)
			( gate "@baseboard_fab2_lib.baseboard_fab2(sch_1):page119_i213"
				( attribute "CDS_LIB" "mstr_discrete"
					( Origin gPackager )
				)
				( attribute "CDS_LOCATION" "R2U48"
					( Origin gPackager )
				)
				( attribute "CDS_SEC" "1"
					( Origin gPackager )
				)
				( attribute "LOCATION" "R2U48"
					( Origin gFrontEnd )
				)
				( attribute "MATERIAL" "CHIP"
					( Origin gFrontEnd )
				)
				( attribute "PACK_TYPE" "0402"
					( Origin gFrontEnd )
				)
				( attribute "PART_NUMBER" "G21796-072"
					( Origin gFrontEnd )
				)
				( attribute "PHYS_PAGE" "119"
					( Origin gFrontEnd )
				)
				( attribute "ROT" "0"
					( Origin gFrontEnd )
				)
				( attribute "SEC" "1"
					( Origin gFrontEnd )
				)
				( attribute "SEC_TYPE" "0402"
					( Origin gFrontEnd )
				)
				( attribute "TOLERANCE" "1%"
					( Origin gFrontEnd )
				)
				( attribute "VALUE" "4.75K"
					( Origin gFrontEnd )
				)
				( attribute "VER" "2"
					( Origin gFrontEnd )
				)
				( attribute "WATTAGE" "1/16W"
					( Origin gFrontEnd )
				)
				( attribute "XY" "(-1700,4725)"
					( Origin gFrontEnd )
				)
				( attribute "CHIPS_PART_NAME" "RES"
					( Origin gPackager )
				)
				( attribute "CDS_PART_NAME" "RES_0402-4.75K,1%,1/16W,CHIP,GA"
					( Origin gPackager )
				)
				( objectStatus "R2U48" )
				( pin "a"
					( attribute "PN" "1"
						( Origin gPackager )
					)
					( objectStatus "R2U48.1" )
				)
				( pin "b"
					( attribute "PN" "2"
						( Origin gPackager )
					)
					( objectStatus "R2U48.2" )
				)
			)
			( gate "@baseboard_fab2_lib.baseboard_fab2(sch_1):page119_i215"
				( attribute "CDS_LIB" "mstr_discrete"
					( Origin gPackager )
				)
				( attribute "CDS_LOCATION" "R2U50"
					( Origin gPackager )
				)
				( attribute "CDS_SEC" "1"
					( Origin gPackager )
				)
				( attribute "LOCATION" "R2U50"
					( Origin gFrontEnd )
				)
				( attribute "MATERIAL" "EMPTY"
					( Origin gFrontEnd )
				)
				( attribute "PACK_TYPE" "0402"
					( Origin gFrontEnd )
				)
				( attribute "PART_NUMBER" "G21497-005"
					( Origin gFrontEnd )
				)
				( attribute "PHYS_PAGE" "119"
					( Origin gFrontEnd )
				)
				( attribute "ROT" "0"
					( Origin gFrontEnd )
				)
				( attribute "SEC" "1"
					( Origin gFrontEnd )
				)
				( attribute "SEC_TYPE" "0402"
					( Origin gFrontEnd )
				)
				( attribute "TOLERANCE" "5%"
					( Origin gFrontEnd )
				)
				( attribute "VALUE" "0.0"
					( Origin gFrontEnd )
				)
				( attribute "VER" "1"
					( Origin gFrontEnd )
				)
				( attribute "WATTAGE" "1/16W"
					( Origin gFrontEnd )
				)
				( attribute "XY" "(-1425,4100)"
					( Origin gFrontEnd )
				)
				( attribute "CHIPS_PART_NAME" "RES"
					( Origin gPackager )
				)
				( attribute "CDS_PART_NAME" "RES_0402-0.0,5%,1/16W,EMPTY,G2A"
					( Origin gPackager )
				)
				( objectStatus "R2U50" )
				( pin "a"
					( attribute "PN" "1"
						( Origin gPackager )
					)
					( objectStatus "R2U50.1" )
				)
				( pin "b"
					( attribute "PN" "2"
						( Origin gPackager )
					)
					( objectStatus "R2U50.2" )
				)
			)
			( gate "@baseboard_fab2_lib.baseboard_fab2(sch_1):page120_i147"
				( attribute "BOM_COST" "SB"
					( Origin gFrontEnd )
				)
				( attribute "CDS_LIB" "mstr_u_proc"
					( Origin gPackager )
				)
				( attribute "CDS_LOCATION" "U7C1"
					( Origin gPackager )
				)
				( attribute "CDS_SEC" "7"
					( Origin gPackager )
				)
				( attribute "LOCATION" "U7C1"
					( Origin gFrontEnd )
				)
				( attribute "MATERIAL" "IC"
					( Origin gFrontEnd )
				)
				( attribute "PACK_TYPE" "BGA1"
					( Origin gFrontEnd )
				)
				( attribute "PART_NUMBER" "H91415-002"
					( Origin gFrontEnd )
				)
				( attribute "PHYS_PAGE" "120"
					( Origin gFrontEnd )
				)
				( attribute "ROOM" "SB"
					( Origin gFrontEnd )
				)
				( attribute "ROT" "0"
					( Origin gFrontEnd )
				)
				( attribute "SEC" "7"
					( Origin gFrontEnd )
				)
				( attribute "SEC_TYPE" "BGA1"
					( Origin gFrontEnd )
				)
				( attribute "VER" "7"
					( Origin gFrontEnd )
				)
				( attribute "XY" "(-3975,2800)"
					( Origin gFrontEnd )
				)
				( attribute "CHIPS_PART_NAME" "LBG_CORE_QAT_EXT_D"
					( Origin gPackager )
				)
				( attribute "CDS_PART_NAME" "LBG_CORE_QAT_EXT_D_BGA1-IC,H91A"
					( Origin gPackager )
				)
				( objectStatus "U7C1" )
				( pin "gpio_rcomp_3p3"
					( attribute "PN" "BY25"
						( Origin gPackager )
					)
					( objectStatus "U7C1.BY25" )
				)
				( pin "gpp_e0_sataxpcie0_satagp0"
					( attribute "PN" "BH50"
						( Origin gPackager )
					)
					( objectStatus "U7C1.BH50" )
				)
				( pin "gpp_e1_sataxpcie1_satagp1"
					( attribute "PN" "AY52"
						( Origin gPackager )
					)
					( objectStatus "U7C1.AY52" )
				)
				( pin "gpp_e2_sataxpcie2_satagp2"
					( attribute "PN" "BG52"
						( Origin gPackager )
					)
					( objectStatus "U7C1.BG52" )
				)
				( pin "gpp_e3_cpu_gp0"
					( attribute "PN" "BE52"
						( Origin gPackager )
					)
					( objectStatus "U7C1.BE52" )
				)
				( pin "gpp_e4_sata_devslp0"
					( attribute "PN" "AV52"
						( Origin gPackager )
					)
					( objectStatus "U7C1.AV52" )
				)
				( pin "gpp_e5_sata_devslp1"
					( attribute "PN" "AT52"
						( Origin gPackager )
					)
					( objectStatus "U7C1.AT52" )
				)
				( pin "gpp_e6_sata_devslp2"
					( attribute "PN" "BB52"
						( Origin gPackager )
					)
					( objectStatus "U7C1.BB52" )
				)
				( pin "gpp_e7_cpu_gp1"
					( attribute "PN" "BJ48"
						( Origin gPackager )
					)
					( objectStatus "U7C1.BJ48" )
				)
				( pin "gpp_e8_sata_led_n"
					( attribute "PN" "AV56"
						( Origin gPackager )
					)
					( objectStatus "U7C1.AV56" )
				)
				( pin "gpp_e9_usb2_oc0_n"
					( attribute "PN" "BL48"
						( Origin gPackager )
					)
					( objectStatus "U7C1.BL48" )
				)
				( pin "gpp_e10_usb2_oc1_n"
					( attribute "PN" "BN48"
						( Origin gPackager )
					)
					( objectStatus "U7C1.BN48" )
				)
				( pin "gpp_e11_usb2_oc2_n"
					( attribute "PN" "AW54"
						( Origin gPackager )
					)
					( objectStatus "U7C1.AW54" )
				)
				( pin "gpp_e12_usb2_oc3_n"
					( attribute "PN" "AU58"
						( Origin gPackager )
					)
					( objectStatus "U7C1.AU58" )
				)
				( pin "gpp_f0_sataxpcie3_satagp3"
					( attribute "PN" "AG7"
						( Origin gPackager )
					)
					( objectStatus "U7C1.AG7" )
				)
				( pin "gpp_f1_sataxpcie4_satagp4"
					( attribute "PN" "AK9"
						( Origin gPackager )
					)
					( objectStatus "U7C1.AK9" )
				)
				( pin "gpp_f2_sataxpcie5_satagp5"
					( attribute "PN" "AK20"
						( Origin gPackager )
					)
					( objectStatus "U7C1.AK20" )
				)
				( pin "gpp_f3_sataxpcie6_satagp6"
					( attribute "PN" "AK13"
						( Origin gPackager )
					)
					( objectStatus "U7C1.AK13" )
				)
				( pin "gpp_f4_sataxpcie7_satagp7"
					( attribute "PN" "AH13"
						( Origin gPackager )
					)
					( objectStatus "U7C1.AH13" )
				)
				( pin "gpp_f5_sata_devslp3"
					( attribute "PN" "AH17"
						( Origin gPackager )
					)
					( objectStatus "U7C1.AH17" )
				)
				( pin "gpp_f6_sata_devslp4"
					( attribute "PN" "AL18"
						( Origin gPackager )
					)
					( objectStatus "U7C1.AL18" )
				)
				( pin "gpp_f7_sata_devslp5"
					( attribute "PN" "AK17"
						( Origin gPackager )
					)
					( objectStatus "U7C1.AK17" )
				)
				( pin "gpp_f8_sata_devslp6"
					( attribute "PN" "AH9"
						( Origin gPackager )
					)
					( objectStatus "U7C1.AH9" )
				)
				( pin "gpp_f9_sata_devslp7"
					( attribute "PN" "AR20"
						( Origin gPackager )
					)
					( objectStatus "U7C1.AR20" )
				)
				( pin "gpp_f10_sata_sclock"
					( attribute "PN" "AL7"
						( Origin gPackager )
					)
					( objectStatus "U7C1.AL7" )
				)
				( pin "gpp_f11_sata_sload"
					( attribute "PN" "AR9"
						( Origin gPackager )
					)
					( objectStatus "U7C1.AR9" )
				)
				( pin "gpp_f12_sata_sdataout1"
					( attribute "PN" "AP7"
						( Origin gPackager )
					)
					( objectStatus "U7C1.AP7" )
				)
				( pin "gpp_f13_sata_sdataout0"
					( attribute "PN" "AP11"
						( Origin gPackager )
					)
					( objectStatus "U7C1.AP11" )
				)
				( pin "gpp_f14_ssata_led_n"
					( attribute "PN" "AL11"
						( Origin gPackager )
					)
					( objectStatus "U7C1.AL11" )
				)
				( pin "gpp_f15_usb2_oc4_n"
					( attribute "PN" "AR13"
						( Origin gPackager )
					)
					( objectStatus "U7C1.AR13" )
				)
				( pin "gpp_f16_usb2_oc5_n"
					( attribute "PN" "AU13"
						( Origin gPackager )
					)
					( objectStatus "U7C1.AU13" )
				)
				( pin "gpp_f17_usb2_oc6_n"
					( attribute "PN" "AP15"
						( Origin gPackager )
					)
					( objectStatus "U7C1.AP15" )
				)
				( pin "gpp_f18_usb2_oc7_n"
					( attribute "PN" "AL15"
						( Origin gPackager )
					)
					( objectStatus "U7C1.AL15" )
				)
				( pin "gpp_f19_lan_smbclk"
					( attribute "PN" "AU9"
						( Origin gPackager )
					)
					( objectStatus "U7C1.AU9" )
				)
				( pin "gpp_f20_lan_smbdata"
					( attribute "PN" "AU20"
						( Origin gPackager )
					)
					( objectStatus "U7C1.AU20" )
				)
				( pin "gpp_f21_lan_smbalrt_n"
					( attribute "PN" "AR17"
						( Origin gPackager )
					)
					( objectStatus "U7C1.AR17" )
				)
				( pin "gpp_f22_ssata_sclock"
					( attribute "PN" "AP18"
						( Origin gPackager )
					)
					( objectStatus "U7C1.AP18" )
				)
				( pin "gpp_f23_ssata_sload"
					( attribute "PN" "AU17"
						( Origin gPackager )
					)
					( objectStatus "U7C1.AU17" )
				)
				( pin "gpp_g0_fantach0_fantach0ie"
					( attribute "PN" "AY11"
						( Origin gPackager )
					)
					( objectStatus "U7C1.AY11" )
				)
				( pin "gpp_g1_fantach1_fantach1ie"
					( attribute "PN" "AV15"
						( Origin gPackager )
					)
					( objectStatus "U7C1.AV15" )
				)
				( pin "gpp_g2_fantach2_fantach2ie"
					( attribute "PN" "BE22"
						( Origin gPackager )
					)
					( objectStatus "U7C1.BE22" )
				)
				( pin "gpp_g3_fantach3_fantach3ie"
					( attribute "PN" "AY7"
						( Origin gPackager )
					)
					( objectStatus "U7C1.AY7" )
				)
				( pin "gpp_g4_fantach4_fantach4ie"
					( attribute "PN" "BA9"
						( Origin gPackager )
					)
					( objectStatus "U7C1.BA9" )
				)
				( pin "gpp_g5_fantach5_fantach5ie"
					( attribute "PN" "AW20"
						( Origin gPackager )
					)
					( objectStatus "U7C1.AW20" )
				)
				( pin "gpp_g6_fantach6_fantach6ie"
					( attribute "PN" "AV18"
						( Origin gPackager )
					)
					( objectStatus "U7C1.AV18" )
				)
				( pin "gpp_g7_fantach7_fantach7ie"
					( attribute "PN" "AY15"
						( Origin gPackager )
					)
					( objectStatus "U7C1.AY15" )
				)
				( pin "gpp_g8_fanpwm0_fanpwm0ie"
					( attribute "PN" "BG11"
						( Origin gPackager )
					)
					( objectStatus "U7C1.BG11" )
				)
				( pin "gpp_g9_fanpwm1_fampwm1ie"
					( attribute "PN" "AV11"
						( Origin gPackager )
					)
					( objectStatus "U7C1.AV11" )
				)
				( pin "gpp_g10_fanpwm2_fanpwm2ie"
					( attribute "PN" "BE11"
						( Origin gPackager )
					)
					( objectStatus "U7C1.BE11" )
				)
				( pin "gpp_g11_fanpwm3_fanpmw3ie"
					( attribute "PN" "BA20"
						( Origin gPackager )
					)
					( objectStatus "U7C1.BA20" )
				)
				( pin "gpp_g12"
					( attribute "PN" "BD13"
						( Origin gPackager )
					)
					( objectStatus "U7C1.BD13" )
				)
				( pin "gpp_g13"
					( attribute "PN" "AY18"
						( Origin gPackager )
					)
					( objectStatus "U7C1.AY18" )
				)
				( pin "gpp_g14"
					( attribute "PN" "AV7"
						( Origin gPackager )
					)
					( objectStatus "U7C1.AV7" )
				)
				( pin "gpp_g15"
					( attribute "PN" "BE18"
						( Origin gPackager )
					)
					( objectStatus "U7C1.BE18" )
				)
				( pin "gpp_g16"
					( attribute "PN" "BD17"
						( Origin gPackager )
					)
					( objectStatus "U7C1.BD17" )
				)
				( pin "gpp_g17_adr_complete"
					( attribute "PN" "BD9"
						( Origin gPackager )
					)
					( objectStatus "U7C1.BD9" )
				)
				( pin "gpp_g18_nmi_n"
					( attribute "PN" "BE7"
						( Origin gPackager )
					)
					( objectStatus "U7C1.BE7" )
				)
				( pin "gpp_g19_smi_n"
					( attribute "PN" "BE15"
						( Origin gPackager )
					)
					( objectStatus "U7C1.BE15" )
				)
				( pin "gpp_g20_ssata_devslp0"
					( attribute "PN" "BA17"
						( Origin gPackager )
					)
					( objectStatus "U7C1.BA17" )
				)
				( pin "gpp_g21_ssata_devslp1"
					( attribute "PN" "BG7"
						( Origin gPackager )
					)
					( objectStatus "U7C1.BG7" )
				)
				( pin "gpp_g22_ssata_devslp2"
					( attribute "PN" "BD20"
						( Origin gPackager )
					)
					( objectStatus "U7C1.BD20" )
				)
				( pin "gpp_g23_ssataxpcie0_ssatagp0"
					( attribute "PN" "BA13"
						( Origin gPackager )
					)
					( objectStatus "U7C1.BA13" )
				)
				( pin "gpp_h0_srcclkreq6_n"
					( attribute "PN" "AT4"
						( Origin gPackager )
					)
					( objectStatus "U7C1.AT4" )
				)
				( pin "gpp_h1_srcclkreq7_n"
					( attribute "PN" "AW4"
						( Origin gPackager )
					)
					( objectStatus "U7C1.AW4" )
				)
				( pin "gpp_h2_srcclkreq8_n"
					( attribute "PN" "AV3"
						( Origin gPackager )
					)
					( objectStatus "U7C1.AV3" )
				)
				( pin "gpp_h3_srcclkreq9_n"
					( attribute "PN" "AR1"
						( Origin gPackager )
					)
					( objectStatus "U7C1.AR1" )
				)
				( pin "gpp_h4_srcclkreq10_n"
					( attribute "PN" "AT2"
						( Origin gPackager )
					)
					( objectStatus "U7C1.AT2" )
				)
				( pin "gpp_h5_srcclkreq11_n"
					( attribute "PN" "AY3"
						( Origin gPackager )
					)
					( objectStatus "U7C1.AY3" )
				)
				( pin "gpp_h6_srcclkreq12_n"
					( attribute "PN" "AW2"
						( Origin gPackager )
					)
					( objectStatus "U7C1.AW2" )
				)
				( pin "gpp_h7_srcclkreq13_n"
					( attribute "PN" "AV1"
						( Origin gPackager )
					)
					( objectStatus "U7C1.AV1" )
				)
				( pin "gpp_h8_srcclkreq14_n"
					( attribute "PN" "AR3"
						( Origin gPackager )
					)
					( objectStatus "U7C1.AR3" )
				)
				( pin "gpp_h9_srcclkreq15_n"
					( attribute "PN" "BE2"
						( Origin gPackager )
					)
					( objectStatus "U7C1.BE2" )
				)
				( pin "gpp_h10_sml2clk_ie"
					( attribute "PN" "BA4"
						( Origin gPackager )
					)
					( objectStatus "U7C1.BA4" )
				)
				( pin "gpp_h11_sml2data_ie"
					( attribute "PN" "BD1"
						( Origin gPackager )
					)
					( objectStatus "U7C1.BD1" )
				)
				( pin "gpp_h12_sml2alert_n_ie_n"
					( attribute "PN" "BB1"
						( Origin gPackager )
					)
					( objectStatus "U7C1.BB1" )
				)
				( pin "gpp_h13_sml3clk_ie"
					( attribute "PN" "AY1"
						( Origin gPackager )
					)
					( objectStatus "U7C1.AY1" )
				)
				( pin "gpp_h14_sml3data_ie"
					( attribute "PN" "BC2"
						( Origin gPackager )
					)
					( objectStatus "U7C1.BC2" )
				)
				( pin "gpp_h15_sml3alert_n_ie_n"
					( attribute "PN" "BB3"
						( Origin gPackager )
					)
					( objectStatus "U7C1.BB3" )
				)
				( pin "gpp_h16_sml4clk_ie"
					( attribute "PN" "BF1"
						( Origin gPackager )
					)
					( objectStatus "U7C1.BF1" )
				)
				( pin "gpp_h17_sml4data_ie"
					( attribute "PN" "BE4"
						( Origin gPackager )
					)
					( objectStatus "U7C1.BE4" )
				)
				( pin "gpp_h18_sml4alert_n_ie_n"
					( attribute "PN" "BC4"
						( Origin gPackager )
					)
					( objectStatus "U7C1.BC4" )
				)
				( pin "gpp_h19_ssataxpcie1_ssatagp1"
					( attribute "PN" "BD3"
						( Origin gPackager )
					)
					( objectStatus "U7C1.BD3" )
				)
				( pin "gpp_h20_ssataxpcie2_ssatagp2"
					( attribute "PN" "BF3"
						( Origin gPackager )
					)
					( objectStatus "U7C1.BF3" )
				)
				( pin "gpp_h21_ssataxpcie3_ssatagp3"
					( attribute "PN" "BA2"
						( Origin gPackager )
					)
					( objectStatus "U7C1.BA2" )
				)
				( pin "gpp_h22_ssataxpcie4_ssatagp4"
					( attribute "PN" "BH2"
						( Origin gPackager )
					)
					( objectStatus "U7C1.BH2" )
				)
				( pin "gpp_h23_ssataxpcie5_ssatagp5"
					( attribute "PN" "BH4"
						( Origin gPackager )
					)
					( objectStatus "U7C1.BH4" )
				)
				( pin "gpp_i0_lan_tdo"
					( attribute "PN" "CA20"
						( Origin gPackager )
					)
					( objectStatus "U7C1.CA20" )
				)
				( pin "gpp_i1_lan_tck"
					( attribute "PN" "BV21"
						( Origin gPackager )
					)
					( objectStatus "U7C1.BV21" )
				)
				( pin "gpp_i2_lan_tms"
					( attribute "PN" "CA22"
						( Origin gPackager )
					)
					( objectStatus "U7C1.CA22" )
				)
				( pin "gpp_i3_lan_tdi"
					( attribute "PN" "BY23"
						( Origin gPackager )
					)
					( objectStatus "U7C1.BY23" )
				)
				( pin "gpp_i4_do_reset_in_n"
					( attribute "PN" "BW20"
						( Origin gPackager )
					)
					( objectStatus "U7C1.BW20" )
				)
				( pin "gpp_i5_do_reset_out_n"
					( attribute "PN" "BW24"
						( Origin gPackager )
					)
					( objectStatus "U7C1.BW24" )
				)
				( pin "gpp_i6_reset_done"
					( attribute "PN" "BV23"
						( Origin gPackager )
					)
					( objectStatus "U7C1.BV23" )
				)
				( pin "gpp_i7_lan_trst_n"
					( attribute "PN" "CA24"
						( Origin gPackager )
					)
					( objectStatus "U7C1.CA24" )
				)
				( pin "gpp_i8_pci_dis_n"
					( attribute "PN" "BW22"
						( Origin gPackager )
					)
					( objectStatus "U7C1.BW22" )
				)
				( pin "gpp_i9_lan_dis_n"
					( attribute "PN" "BY21"
						( Origin gPackager )
					)
					( objectStatus "U7C1.BY21" )
				)
				( pin "gpp_i10"
					( attribute "PN" "BV25"
						( Origin gPackager )
					)
					( objectStatus "U7C1.BV25" )
				)
				( pin "gpp_j0_lan_led_p0_0"
					( attribute "PN" "BL1"
						( Origin gPackager )
					)
					( objectStatus "U7C1.BL1" )
				)
				( pin "gpp_j1_lan_led_p0_1"
					( attribute "PN" "BK4"
						( Origin gPackager )
					)
					( objectStatus "U7C1.BK4" )
				)
				( pin "gpp_j2_lan_led_p1_0"
					( attribute "PN" "BP4"
						( Origin gPackager )
					)
					( objectStatus "U7C1.BP4" )
				)
				( pin "gpp_j3_lan_led_p1_1"
					( attribute "PN" "BK2"
						( Origin gPackager )
					)
					( objectStatus "U7C1.BK2" )
				)
				( pin "gpp_j4_lan_led_p2_0"
					( attribute "PN" "BL3"
						( Origin gPackager )
					)
					( objectStatus "U7C1.BL3" )
				)
				( pin "gpp_j5_lan_led_p2_1"
					( attribute "PN" "BU6"
						( Origin gPackager )
					)
					( objectStatus "U7C1.BU6" )
				)
				( pin "gpp_j6_lan_led_p3_0"
					( attribute "PN" "CA13"
						( Origin gPackager )
					)
					( objectStatus "U7C1.CA13" )
				)
				( pin "gpp_j7_lan_led_p3_1"
					( attribute "PN" "BM2"
						( Origin gPackager )
					)
					( objectStatus "U7C1.BM2" )
				)
				( pin "gpp_j8_lan_i2c_scl_mdc_p0"
					( attribute "PN" "BM4"
						( Origin gPackager )
					)
					( objectStatus "U7C1.BM4" )
				)
				( pin "gpp_j9_lan_i2c_sda_mdio_p0"
					( attribute "PN" "BN3"
						( Origin gPackager )
					)
					( objectStatus "U7C1.BN3" )
				)
				( pin "gpp_j10_lan_i2c_scl_mdc_p1"
					( attribute "PN" "BW5"
						( Origin gPackager )
					)
					( objectStatus "U7C1.BW5" )
				)
				( pin "gpp_j11_lan_i2c_sda_mdio_p1"
					( attribute "PN" "BV8"
						( Origin gPackager )
					)
					( objectStatus "U7C1.BV8" )
				)
				( pin "gpp_j12_lan_i2c_scl_mdc_p2"
					( attribute "PN" "BT5"
						( Origin gPackager )
					)
					( objectStatus "U7C1.BT5" )
				)
				( pin "gpp_j13_lan_i2c_sda_mdio_p2"
					( attribute "PN" "BW11"
						( Origin gPackager )
					)
					( objectStatus "U7C1.BW11" )
				)
				( pin "gpp_j14_lan_i2c_scl_mdc_p3"
					( attribute "PN" "BW6"
						( Origin gPackager )
					)
					( objectStatus "U7C1.BW6" )
				)
				( pin "gpp_j15_lan_i2c_sda_mdio_p3"
					( attribute "PN" "BW9"
						( Origin gPackager )
					)
					( objectStatus "U7C1.BW9" )
				)
				( pin "gpp_j16_lan_sdp_p0_0"
					( attribute "PN" "BV10"
						( Origin gPackager )
					)
					( objectStatus "U7C1.BV10" )
				)
				( pin "gpp_j17_lan_sdp_p0_1"
					( attribute "PN" "CA11"
						( Origin gPackager )
					)
					( objectStatus "U7C1.CA11" )
				)
				( pin "gpp_j18_lan_sdp_p1_0"
					( attribute "PN" "BY10"
						( Origin gPackager )
					)
					( objectStatus "U7C1.BY10" )
				)
				( pin "gpp_j19_lan_sdp_p1_1"
					( attribute "PN" "BY14"
						( Origin gPackager )
					)
					( objectStatus "U7C1.BY14" )
				)
				( pin "gpp_j20_lan_sdp_p2_0"
					( attribute "PN" "BW13"
						( Origin gPackager )
					)
					( objectStatus "U7C1.BW13" )
				)
				( pin "gpp_j21_lan_sdp_p2_1"
					( attribute "PN" "BV12"
						( Origin gPackager )
					)
					( objectStatus "U7C1.BV12" )
				)
				( pin "gpp_j22_lan_sdp_p3_0"
					( attribute "PN" "BY12"
						( Origin gPackager )
					)
					( objectStatus "U7C1.BY12" )
				)
				( pin "gpp_j23_lan_sdp_p3_1"
					( attribute "PN" "BV14"
						( Origin gPackager )
					)
					( objectStatus "U7C1.BV14" )
				)
			)
			( gate "@baseboard_fab2_lib.baseboard_fab2(sch_1):page120_i148"
				( attribute "CDS_LIB" "mstr_discrete"
					( Origin gPackager )
				)
				( attribute "CDS_LOCATION" "R8C21"
					( Origin gPackager )
				)
				( attribute "CDS_SEC" "1"
					( Origin gPackager )
				)
				( attribute "LOCATION" "R8C21"
					( Origin gFrontEnd )
				)
				( attribute "MATERIAL" "CHIP"
					( Origin gFrontEnd )
				)
				( attribute "PACK_TYPE" "0402"
					( Origin gFrontEnd )
				)
				( attribute "PART_NUMBER" "G21796-017"
					( Origin gFrontEnd )
				)
				( attribute "PHYS_PAGE" "120"
					( Origin gFrontEnd )
				)
				( attribute "ROOM" "SB"
					( Origin gFrontEnd )
				)
				( attribute "ROT" "0"
					( Origin gFrontEnd )
				)
				( attribute "SEC" "1"
					( Origin gFrontEnd )
				)
				( attribute "SEC_TYPE" "0402"
					( Origin gFrontEnd )
				)
				( attribute "TOLERANCE" "1%"
					( Origin gFrontEnd )
				)
				( attribute "VALUE" "100.0"
					( Origin gFrontEnd )
				)
				( attribute "VER" "2"
					( Origin gFrontEnd )
				)
				( attribute "WATTAGE" "1/16W"
					( Origin gFrontEnd )
				)
				( attribute "XY" "(-775,2825)"
					( Origin gFrontEnd )
				)
				( attribute "CHIPS_PART_NAME" "RES"
					( Origin gPackager )
				)
				( attribute "CDS_PART_NAME" "RES_0402-100.0,1%,1/16W,CHIP,GA"
					( Origin gPackager )
				)
				( objectStatus "R8C21" )
				( pin "a"
					( attribute "PN" "1"
						( Origin gPackager )
					)
					( objectStatus "R8C21.1" )
				)
				( pin "b"
					( attribute "PN" "2"
						( Origin gPackager )
					)
					( objectStatus "R8C21.2" )
				)
			)
			( gate "@baseboard_fab2_lib.baseboard_fab2(sch_1):page120_i218"
				( attribute "CDS_LIB" "mstr_discrete"
					( Origin gPackager )
				)
				( attribute "CDS_LOCATION" "R2M1"
					( Origin gPackager )
				)
				( attribute "CDS_SEC" "1"
					( Origin gPackager )
				)
				( attribute "LOCATION" "R2M1"
					( Origin gFrontEnd )
				)
				( attribute "MATERIAL" "CHIP"
					( Origin gFrontEnd )
				)
				( attribute "PACK_TYPE" "0402"
					( Origin gFrontEnd )
				)
				( attribute "PART_NUMBER" "G21796-074"
					( Origin gFrontEnd )
				)
				( attribute "PHYS_PAGE" "120"
					( Origin gFrontEnd )
				)
				( attribute "ROOM" "CPLD"
					( Origin gFrontEnd )
				)
				( attribute "ROT" "0"
					( Origin gFrontEnd )
				)
				( attribute "SEC" "1"
					( Origin gFrontEnd )
				)
				( attribute "SEC_TYPE" "0402"
					( Origin gFrontEnd )
				)
				( attribute "TOLERANCE" "1%"
					( Origin gFrontEnd )
				)
				( attribute "VALUE" "33.2"
					( Origin gFrontEnd )
				)
				( attribute "VER" "1"
					( Origin gFrontEnd )
				)
				( attribute "WATTAGE" "1/16W"
					( Origin gFrontEnd )
				)
				( attribute "XY" "(-6375,3850)"
					( Origin gFrontEnd )
				)
				( attribute "CHIPS_PART_NAME" "RES"
					( Origin gPackager )
				)
				( attribute "CDS_PART_NAME" "RES_0402-33.2,1%,1/16W,CHIP,G2A"
					( Origin gPackager )
				)
				( objectStatus "R2M1" )
				( pin "a"
					( attribute "PN" "1"
						( Origin gPackager )
					)
					( objectStatus "R2M1.1" )
				)
				( pin "b"
					( attribute "PN" "2"
						( Origin gPackager )
					)
					( objectStatus "R2M1.2" )
				)
			)
			( gate "@baseboard_fab2_lib.baseboard_fab2(sch_1):page120_i219"
				( attribute "CDS_LIB" "mstr_discrete"
					( Origin gPackager )
				)
				( attribute "CDS_LOCATION" "R2N26"
					( Origin gPackager )
				)
				( attribute "CDS_SEC" "1"
					( Origin gPackager )
				)
				( attribute "LOCATION" "R2N26"
					( Origin gFrontEnd )
				)
				( attribute "MATERIAL" "CHIP"
					( Origin gFrontEnd )
				)
				( attribute "PACK_TYPE" "0402"
					( Origin gFrontEnd )
				)
				( attribute "PART_NUMBER" "G21796-074"
					( Origin gFrontEnd )
				)
				( attribute "PHYS_PAGE" "120"
					( Origin gFrontEnd )
				)
				( attribute "ROOM" "CPLD"
					( Origin gFrontEnd )
				)
				( attribute "ROT" "0"
					( Origin gFrontEnd )
				)
				( attribute "SEC" "1"
					( Origin gFrontEnd )
				)
				( attribute "SEC_TYPE" "0402"
					( Origin gFrontEnd )
				)
				( attribute "TOLERANCE" "1%"
					( Origin gFrontEnd )
				)
				( attribute "VALUE" "33.2"
					( Origin gFrontEnd )
				)
				( attribute "VER" "1"
					( Origin gFrontEnd )
				)
				( attribute "WATTAGE" "1/16W"
					( Origin gFrontEnd )
				)
				( attribute "XY" "(-6325,2050)"
					( Origin gFrontEnd )
				)
				( attribute "CHIPS_PART_NAME" "RES"
					( Origin gPackager )
				)
				( attribute "CDS_PART_NAME" "RES_0402-33.2,1%,1/16W,CHIP,G2A"
					( Origin gPackager )
				)
				( objectStatus "R2N26" )
				( pin "a"
					( attribute "PN" "1"
						( Origin gPackager )
					)
					( objectStatus "R2N26.1" )
				)
				( pin "b"
					( attribute "PN" "2"
						( Origin gPackager )
					)
					( objectStatus "R2N26.2" )
				)
			)
			( gate "@baseboard_fab2_lib.baseboard_fab2(sch_1):page121_i31"
				( attribute "CDS_LIB" "mstr_discrete"
					( Origin gPackager )
				)
				( attribute "CDS_LOCATION" "R7C15"
					( Origin gPackager )
				)
				( attribute "CDS_SEC" "1"
					( Origin gPackager )
				)
				( attribute "LOCATION" "R7C15"
					( Origin gFrontEnd )
				)
				( attribute "MATERIAL" "CHIP"
					( Origin gFrontEnd )
				)
				( attribute "PACK_TYPE" "0402"
					( Origin gFrontEnd )
				)
				( attribute "PART_NUMBER" "G21497-005"
					( Origin gFrontEnd )
				)
				( attribute "PHYS_PAGE" "121"
					( Origin gFrontEnd )
				)
				( attribute "ROOM" "SB"
					( Origin gFrontEnd )
				)
				( attribute "ROT" "0"
					( Origin gFrontEnd )
				)
				( attribute "SEC" "1"
					( Origin gPackager )
				)
				( attribute "TOLERANCE" "5%"
					( Origin gFrontEnd )
				)
				( attribute "VALUE" "0.0"
					( Origin gFrontEnd )
				)
				( attribute "VER" "1"
					( Origin gFrontEnd )
				)
				( attribute "WATTAGE" "1/16W"
					( Origin gFrontEnd )
				)
				( attribute "XY" "(-1925,3150)"
					( Origin gFrontEnd )
				)
				( attribute "CHIPS_PART_NAME" "RES"
					( Origin gPackager )
				)
				( attribute "CDS_PART_NAME" "RES_0402-0.0,5%,1/16W,CHIP,G21A"
					( Origin gPackager )
				)
				( objectStatus "R7C15" )
				( pin "a"
					( attribute "PN" "1"
						( Origin gPackager )
					)
					( objectStatus "R7C15.1" )
				)
				( pin "b"
					( attribute "PN" "2"
						( Origin gPackager )
					)
					( objectStatus "R7C15.2" )
				)
			)
			( gate "@baseboard_fab2_lib.baseboard_fab2(sch_1):page121_i33"
				( attribute "CDS_LIB" "mstr_discrete"
					( Origin gPackager )
				)
				( attribute "CDS_LOCATION" "R7C16"
					( Origin gPackager )
				)
				( attribute "CDS_SEC" "1"
					( Origin gPackager )
				)
				( attribute "LOCATION" "R7C16"
					( Origin gFrontEnd )
				)
				( attribute "MATERIAL" "CHIP"
					( Origin gFrontEnd )
				)
				( attribute "PACK_TYPE" "0402"
					( Origin gFrontEnd )
				)
				( attribute "PART_NUMBER" "G21796-074"
					( Origin gFrontEnd )
				)
				( attribute "PHYS_PAGE" "121"
					( Origin gFrontEnd )
				)
				( attribute "ROOM" "SB"
					( Origin gFrontEnd )
				)
				( attribute "ROT" "0"
					( Origin gFrontEnd )
				)
				( attribute "SEC" "1"
					( Origin gPackager )
				)
				( attribute "TOLERANCE" "1%"
					( Origin gFrontEnd )
				)
				( attribute "VALUE" "33.2"
					( Origin gFrontEnd )
				)
				( attribute "VER" "1"
					( Origin gFrontEnd )
				)
				( attribute "WATTAGE" "1/16W"
					( Origin gFrontEnd )
				)
				( attribute "XY" "(-1950,3550)"
					( Origin gFrontEnd )
				)
				( attribute "CHIPS_PART_NAME" "RES"
					( Origin gPackager )
				)
				( attribute "CDS_PART_NAME" "RES_0402-33.2,1%,1/16W,CHIP,G2A"
					( Origin gPackager )
				)
				( objectStatus "R7C16" )
				( pin "a"
					( attribute "PN" "1"
						( Origin gPackager )
					)
					( objectStatus "R7C16.1" )
				)
				( pin "b"
					( attribute "PN" "2"
						( Origin gPackager )
					)
					( objectStatus "R7C16.2" )
				)
			)
			( gate "@baseboard_fab2_lib.baseboard_fab2(sch_1):page121_i34"
				( attribute "BOM_COST" "SB"
					( Origin gFrontEnd )
				)
				( attribute "CDS_LIB" "mstr_u_proc"
					( Origin gPackager )
				)
				( attribute "CDS_LOCATION" "U7C1"
					( Origin gPackager )
				)
				( attribute "CDS_SEC" "8"
					( Origin gPackager )
				)
				( attribute "LOCATION" "U7C1"
					( Origin gFrontEnd )
				)
				( attribute "MATERIAL" "IC"
					( Origin gFrontEnd )
				)
				( attribute "PACK_TYPE" "BGA1"
					( Origin gFrontEnd )
				)
				( attribute "PART_NUMBER" "H91415-002"
					( Origin gFrontEnd )
				)
				( attribute "PHYS_PAGE" "121"
					( Origin gFrontEnd )
				)
				( attribute "ROOM" "SB"
					( Origin gFrontEnd )
				)
				( attribute "ROT" "0"
					( Origin gFrontEnd )
				)
				( attribute "SEC" "8"
					( Origin gFrontEnd )
				)
				( attribute "SEC_TYPE" "BGA1"
					( Origin gFrontEnd )
				)
				( attribute "VER" "8"
					( Origin gFrontEnd )
				)
				( attribute "XY" "(-4050,2800)"
					( Origin gFrontEnd )
				)
				( attribute "CHIPS_PART_NAME" "LBG_CORE_QAT_EXT_D"
					( Origin gPackager )
				)
				( attribute "CDS_PART_NAME" "LBG_CORE_QAT_EXT_D_BGA1-IC,H91A"
					( Origin gPackager )
				)
				( objectStatus "U7C1" )
				( pin "cgc_dut_detect_n"
					( attribute "PN" "C70"
						( Origin gPackager )
					)
					( objectStatus "U7C1.C70" )
				)
				( pin "gpio_rcomp_1p8_3p3"
					( attribute "PN" "AM4"
						( Origin gPackager )
					)
					( objectStatus "U7C1.AM4" )
				)
				( pin "gpp_k0_lan_ncsi_clk_in"
					( attribute "PN" "AJ1"
						( Origin gPackager )
					)
					( objectStatus "U7C1.AJ1" )
				)
				( pin "gpp_k1_lan_ncsi_txd0"
					( attribute "PN" "AM2"
						( Origin gPackager )
					)
					( objectStatus "U7C1.AM2" )
				)
				( pin "gpp_k2_lan_ncsi_txd1"
					( attribute "PN" "AK2"
						( Origin gPackager )
					)
					( objectStatus "U7C1.AK2" )
				)
				( pin "gpp_k3_lan_ncsi_tx_en"
					( attribute "PN" "AL3"
						( Origin gPackager )
					)
					( objectStatus "U7C1.AL3" )
				)
				( pin "gpp_k4_lan_ncsi_crs_dv"
					( attribute "PN" "AN3"
						( Origin gPackager )
					)
					( objectStatus "U7C1.AN3" )
				)
				( pin "gpp_k5_lan_ncsi_rxd0"
					( attribute "PN" "AL1"
						( Origin gPackager )
					)
					( objectStatus "U7C1.AL1" )
				)
				( pin "gpp_k6_lan_ncsi_rxd1"
					( attribute "PN" "AN1"
						( Origin gPackager )
					)
					( objectStatus "U7C1.AN1" )
				)
				( pin "gpp_k7"
					( attribute "PN" "AH2"
						( Origin gPackager )
					)
					( objectStatus "U7C1.AH2" )
				)
				( pin "gpp_k8_lan_ncsi_arb_in"
					( attribute "PN" "AJ3"
						( Origin gPackager )
					)
					( objectStatus "U7C1.AJ3" )
				)
				( pin "gpp_k9_lan_ncsi_arb_out"
					( attribute "PN" "AK4"
						( Origin gPackager )
					)
					( objectStatus "U7C1.AK4" )
				)
				( pin "gpp_k10_pe_rst_n"
					( attribute "PN" "AH4"
						( Origin gPackager )
					)
					( objectStatus "U7C1.AH4" )
				)
				( pin "gpp_l2_testch0_d0"
					( attribute "PN" "AE18"
						( Origin gPackager )
					)
					( objectStatus "U7C1.AE18" )
				)
				( pin "gpp_l3_testch0_d1"
					( attribute "PN" "AE15"
						( Origin gPackager )
					)
					( objectStatus "U7C1.AE15" )
				)
				( pin "gpp_l4_testch0_d2"
					( attribute "PN" "AE11"
						( Origin gPackager )
					)
					( objectStatus "U7C1.AE11" )
				)
				( pin "gpp_l5_testch0_d3"
					( attribute "PN" "Y18"
						( Origin gPackager )
					)
					( objectStatus "U7C1.Y18" )
				)
				( pin "gpp_l6_testch0_d4"
					( attribute "PN" "AA20"
						( Origin gPackager )
					)
					( objectStatus "U7C1.AA20" )
				)
				( pin "gpp_l7_testch0_d5"
					( attribute "PN" "AA17"
						( Origin gPackager )
					)
					( objectStatus "U7C1.AA17" )
				)
				( pin "gpp_l8_testch0_d6"
					( attribute "PN" "AD9"
						( Origin gPackager )
					)
					( objectStatus "U7C1.AD9" )
				)
				( pin "gpp_l9_testch0_d7"
					( attribute "PN" "AD17"
						( Origin gPackager )
					)
					( objectStatus "U7C1.AD17" )
				)
				( pin "gpp_l10_testch0_clk"
					( attribute "PN" "AF20"
						( Origin gPackager )
					)
					( objectStatus "U7C1.AF20" )
				)
				( pin "gpp_l11_testch1_d0"
					( attribute "PN" "AD20"
						( Origin gPackager )
					)
					( objectStatus "U7C1.AD20" )
				)
				( pin "gpp_l12_testch1_d1"
					( attribute "PN" "Y15"
						( Origin gPackager )
					)
					( objectStatus "U7C1.Y15" )
				)
				( pin "gpp_l13_testch1_d2"
					( attribute "PN" "AD13"
						( Origin gPackager )
					)
					( objectStatus "U7C1.AD13" )
				)
				( pin "gpp_l14_testch1_d3"
					( attribute "PN" "AA13"
						( Origin gPackager )
					)
					( objectStatus "U7C1.AA13" )
				)
				( pin "gpp_l15_testch1_d4"
					( attribute "PN" "Y11"
						( Origin gPackager )
					)
					( objectStatus "U7C1.Y11" )
				)
				( pin "gpp_l16_testch1_d5"
					( attribute "PN" "Y7"
						( Origin gPackager )
					)
					( objectStatus "U7C1.Y7" )
				)
				( pin "gpp_l17_testch1_d6"
					( attribute "PN" "AA9"
						( Origin gPackager )
					)
					( objectStatus "U7C1.AA9" )
				)
				( pin "gpp_l18_testch1_d7"
					( attribute "PN" "AE7"
						( Origin gPackager )
					)
					( objectStatus "U7C1.AE7" )
				)
				( pin "gpp_l19_testch1_clk"
					( attribute "PN" "AG11"
						( Origin gPackager )
					)
					( objectStatus "U7C1.AG11" )
				)
				( pin "hda_bclk"
					( attribute "PN" "P18"
						( Origin gPackager )
					)
					( objectStatus "U7C1.P18" )
				)
				( pin "hda_rst_n"
					( attribute "PN" "M18"
						( Origin gPackager )
					)
					( objectStatus "U7C1.M18" )
				)
				( pin "hda_sdi_0"
					( attribute "PN" "K20"
						( Origin gPackager )
					)
					( objectStatus "U7C1.K20" )
				)
				( pin "hda_sdi_1"
					( attribute "PN" "V18"
						( Origin gPackager )
					)
					( objectStatus "U7C1.V18" )
				)
				( pin "hda_sdo"
					( attribute "PN" "U24"
						( Origin gPackager )
					)
					( objectStatus "U7C1.U24" )
				)
				( pin "hda_sync"
					( attribute "PN" "H20"
						( Origin gPackager )
					)
					( objectStatus "U7C1.H20" )
				)
				( pin "intruder_n"
					( attribute "PN" "AG18"
						( Origin gPackager )
					)
					( objectStatus "U7C1.AG18" )
				)
				( pin "rsvd(0)"
					( attribute "PN" "AF61"
						( Origin gPackager )
					)
					( objectStatus "U7C1.AF61" )
				)
				( pin "rsvd(1)"
					( attribute "PN" "AC56"
						( Origin gPackager )
					)
					( objectStatus "U7C1.AC56" )
				)
				( pin "rsvd(2)"
					( attribute "PN" "AA58"
						( Origin gPackager )
					)
					( objectStatus "U7C1.AA58" )
				)
				( pin "rsvd(3)"
					( attribute "PN" "V11"
						( Origin gPackager )
					)
					( objectStatus "U7C1.V11" )
				)
				( pin "rsvd(4)"
					( attribute "PN" "P37"
						( Origin gPackager )
					)
					( objectStatus "U7C1.P37" )
				)
				( pin "rsvd(5)"
					( attribute "PN" "AG15"
						( Origin gPackager )
					)
					( objectStatus "U7C1.AG15" )
				)
				( pin "rsvd(6)"
					( attribute "PN" "AT69"
						( Origin gPackager )
					)
					( objectStatus "U7C1.AT69" )
				)
				( pin "rsvd(7)"
					( attribute "PN" "F8"
						( Origin gPackager )
					)
					( objectStatus "U7C1.F8" )
				)
				( pin "rsvd(8)"
					( attribute "PN" "F69"
						( Origin gPackager )
					)
					( objectStatus "U7C1.F69" )
				)
				( pin "rsvd(9)"
					( attribute "PN" "F66"
						( Origin gPackager )
					)
					( objectStatus "U7C1.F66" )
				)
				( pin "rsvd(10)"
					( attribute "PN" "D8"
						( Origin gPackager )
					)
					( objectStatus "U7C1.D8" )
				)
				( pin "rsvd(11)"
					( attribute "PN" "C18"
						( Origin gPackager )
					)
					( objectStatus "U7C1.C18" )
				)
				( pin "rsvd(12)"
					( attribute "PN" "C68"
						( Origin gPackager )
					)
					( objectStatus "U7C1.C68" )
				)
				( pin "rsvd(13)"
					( attribute "PN" "C67"
						( Origin gPackager )
					)
					( objectStatus "U7C1.C67" )
				)
				( pin "rsvd(14)"
					( attribute "PN" "E18"
						( Origin gPackager )
					)
					( objectStatus "U7C1.E18" )
				)
				( pin "rsvd(15)"
					( attribute "PN" "C6"
						( Origin gPackager )
					)
					( objectStatus "U7C1.C6" )
				)
				( pin "rsvd(16)"
					( attribute "PN" "C5"
						( Origin gPackager )
					)
					( objectStatus "U7C1.C5" )
				)
				( pin "rsvd(17)"
					( attribute "PN" "B10"
						( Origin gPackager )
					)
					( objectStatus "U7C1.B10" )
				)
				( pin "rsvd(18)"
					( attribute "PN" "C11"
						( Origin gPackager )
					)
					( objectStatus "U7C1.C11" )
				)
				( pin "rsvd(19)"
					( attribute "PN" "C9"
						( Origin gPackager )
					)
					( objectStatus "U7C1.C9" )
				)
				( pin "rsvd(20)"
					( attribute "PN" "D10"
						( Origin gPackager )
					)
					( objectStatus "U7C1.D10" )
				)
				( pin "rsvd(21)"
					( attribute "PN" "A11"
						( Origin gPackager )
					)
					( objectStatus "U7C1.A11" )
				)
				( pin "rsvd(22)"
					( attribute "PN" "AT71"
						( Origin gPackager )
					)
					( objectStatus "U7C1.AT71" )
				)
				( pin "rsvd(23)"
					( attribute "PN" "P40"
						( Origin gPackager )
					)
					( objectStatus "U7C1.P40" )
				)
				( pin "rsvd(24)"
					( attribute "PN" "P44"
						( Origin gPackager )
					)
					( objectStatus "U7C1.P44" )
				)
				( pin "rsvd(25)"
					( attribute "PN" "P48"
						( Origin gPackager )
					)
					( objectStatus "U7C1.P48" )
				)
				( pin "rsvd(26)"
					( attribute "PN" "BH24"
						( Origin gPackager )
					)
					( objectStatus "U7C1.BH24" )
				)
				( pin "rsvd(27)"
					( attribute "PN" "BG26"
						( Origin gPackager )
					)
					( objectStatus "U7C1.BG26" )
				)
				( pin "rsvd(28)"
					( attribute "CDS_NOT_ON_SYM" "TRUE"
						( Origin gFrontEnd )
					)
				)
				( pin "rsvd(29)"
					( attribute "CDS_NOT_ON_SYM" "TRUE"
						( Origin gFrontEnd )
					)
				)
				( pin "rsvd(30)"
					( attribute "CDS_NOT_ON_SYM" "TRUE"
						( Origin gFrontEnd )
					)
				)
				( pin "rsvd(31)"
					( attribute "CDS_NOT_ON_SYM" "TRUE"
						( Origin gFrontEnd )
					)
				)
				( pin "rsvd(32)"
					( attribute "CDS_NOT_ON_SYM" "TRUE"
						( Origin gFrontEnd )
					)
				)
				( pin "rsvd(33)"
					( attribute "CDS_NOT_ON_SYM" "TRUE"
						( Origin gFrontEnd )
					)
				)
				( pin "rsvd(34)"
					( attribute "CDS_NOT_ON_SYM" "TRUE"
						( Origin gFrontEnd )
					)
				)
				( pin "rsvd(35)"
					( attribute "CDS_NOT_ON_SYM" "TRUE"
						( Origin gFrontEnd )
					)
				)
				( pin "rsvd(36)"
					( attribute "CDS_NOT_ON_SYM" "TRUE"
						( Origin gFrontEnd )
					)
				)
				( pin "rsvd(37)"
					( attribute "CDS_NOT_ON_SYM" "TRUE"
						( Origin gFrontEnd )
					)
				)
				( pin "rsvd(38)"
					( attribute "CDS_NOT_ON_SYM" "TRUE"
						( Origin gFrontEnd )
					)
				)
				( pin "rsvd(39)"
					( attribute "CDS_NOT_ON_SYM" "TRUE"
						( Origin gFrontEnd )
					)
				)
				( pin "rsvd(40)"
					( attribute "CDS_NOT_ON_SYM" "TRUE"
						( Origin gFrontEnd )
					)
				)
				( pin "rsvd(41)"
					( attribute "CDS_NOT_ON_SYM" "TRUE"
						( Origin gFrontEnd )
					)
				)
				( pin "rsvd(42)"
					( attribute "CDS_NOT_ON_SYM" "TRUE"
						( Origin gFrontEnd )
					)
				)
				( pin "rsvd(43)"
					( attribute "CDS_NOT_ON_SYM" "TRUE"
						( Origin gFrontEnd )
					)
				)
				( pin "rsvd(44)"
					( attribute "CDS_NOT_ON_SYM" "TRUE"
						( Origin gFrontEnd )
					)
				)
				( pin "rsvd(45)"
					( attribute "CDS_NOT_ON_SYM" "TRUE"
						( Origin gFrontEnd )
					)
				)
				( pin "rsvd(46)"
					( attribute "PN" "BW3"
						( Origin gPackager )
					)
					( objectStatus "U7C1.BW3" )
				)
				( pin "rsvd(47)"
					( attribute "CDS_NOT_ON_SYM" "TRUE"
						( Origin gFrontEnd )
					)
				)
				( pin "rsvd(48)"
					( attribute "CDS_NOT_ON_SYM" "TRUE"
						( Origin gFrontEnd )
					)
				)
				( pin "rsvd(49)"
					( attribute "CDS_NOT_ON_SYM" "TRUE"
						( Origin gFrontEnd )
					)
				)
				( pin "rsvd(50)"
					( attribute "CDS_NOT_ON_SYM" "TRUE"
						( Origin gFrontEnd )
					)
				)
				( pin "rsvd(51)"
					( attribute "CDS_NOT_ON_SYM" "TRUE"
						( Origin gFrontEnd )
					)
				)
				( pin "rsvd(52)"
					( attribute "CDS_NOT_ON_SYM" "TRUE"
						( Origin gFrontEnd )
					)
				)
				( pin "rsvd(53)"
					( attribute "CDS_NOT_ON_SYM" "TRUE"
						( Origin gFrontEnd )
					)
				)
				( pin "rsvd(54)"
					( attribute "CDS_NOT_ON_SYM" "TRUE"
						( Origin gFrontEnd )
					)
				)
				( pin "rsvd(55)"
					( attribute "CDS_NOT_ON_SYM" "TRUE"
						( Origin gFrontEnd )
					)
				)
				( pin "rsvd(56)"
					( attribute "CDS_NOT_ON_SYM" "TRUE"
						( Origin gFrontEnd )
					)
				)
				( pin "rsvd(57)"
					( attribute "CDS_NOT_ON_SYM" "TRUE"
						( Origin gFrontEnd )
					)
				)
				( pin "rsvd(58)"
					( attribute "CDS_NOT_ON_SYM" "TRUE"
						( Origin gFrontEnd )
					)
				)
				( pin "rsvd(59)"
					( attribute "CDS_NOT_ON_SYM" "TRUE"
						( Origin gFrontEnd )
					)
				)
				( pin "rsvd(60)"
					( attribute "CDS_NOT_ON_SYM" "TRUE"
						( Origin gFrontEnd )
					)
				)
				( pin "rsvd(61)"
					( attribute "CDS_NOT_ON_SYM" "TRUE"
						( Origin gFrontEnd )
					)
				)
				( pin "rsvd(62)"
					( attribute "CDS_NOT_ON_SYM" "TRUE"
						( Origin gFrontEnd )
					)
				)
				( pin "rsvd(63)"
					( attribute "CDS_NOT_ON_SYM" "TRUE"
						( Origin gFrontEnd )
					)
				)
				( pin "rsvd(64)"
					( attribute "CDS_NOT_ON_SYM" "TRUE"
						( Origin gFrontEnd )
					)
				)
				( pin "rsvd(65)"
					( attribute "CDS_NOT_ON_SYM" "TRUE"
						( Origin gFrontEnd )
					)
				)
				( pin "rsvd(66)"
					( attribute "PN" "U20"
						( Origin gPackager )
					)
					( objectStatus "U7C1.U20" )
				)
				( pin "rsvd(67)"
					( attribute "PN" "R20"
						( Origin gPackager )
					)
					( objectStatus "U7C1.R20" )
				)
				( pin "rsvd(68)"
					( attribute "PN" "V22"
						( Origin gPackager )
					)
					( objectStatus "U7C1.V22" )
				)
				( pin "rtcrst_n"
					( attribute "PN" "P11"
						( Origin gPackager )
					)
					( objectStatus "U7C1.P11" )
				)
				( pin "spi0_clk"
					( attribute "PN" "K2"
						( Origin gPackager )
					)
					( objectStatus "U7C1.K2" )
				)
				( pin "spi0_flash_cs0_n"
					( attribute "PN" "J3"
						( Origin gPackager )
					)
					( objectStatus "U7C1.J3" )
				)
				( pin "spi0_flash_cs1_n"
					( attribute "PN" "G7"
						( Origin gPackager )
					)
					( objectStatus "U7C1.G7" )
				)
				( pin "spi0_io2"
					( attribute "PN" "F5"
						( Origin gPackager )
					)
					( objectStatus "U7C1.F5" )
				)
				( pin "spi0_io3"
					( attribute "PN" "L1"
						( Origin gPackager )
					)
					( objectStatus "U7C1.L1" )
				)
				( pin "spi0_miso_io1"
					( attribute "PN" "L3"
						( Origin gPackager )
					)
					( objectStatus "U7C1.L3" )
				)
				( pin "spi0_mosi_io0"
					( attribute "PN" "H4"
						( Origin gPackager )
					)
					( objectStatus "U7C1.H4" )
				)
				( pin "spi0_tpm_cs_n"
					( attribute "PN" "K4"
						( Origin gPackager )
					)
					( objectStatus "U7C1.K4" )
				)
				( pin "srtcrst_n"
					( attribute "PN" "G18"
						( Origin gPackager )
					)
					( objectStatus "U7C1.G18" )
				)
			)
			( gate "@baseboard_fab2_lib.baseboard_fab2(sch_1):page121_i35"
				( attribute "CDS_LIB" "mstr_discrete"
					( Origin gPackager )
				)
				( attribute "CDS_LOCATION" "R8C26"
					( Origin gPackager )
				)
				( attribute "CDS_SEC" "1"
					( Origin gPackager )
				)
				( attribute "LOCATION" "R8C26"
					( Origin gFrontEnd )
				)
				( attribute "MATERIAL" "CHIP"
					( Origin gFrontEnd )
				)
				( attribute "PACK_TYPE" "0402"
					( Origin gFrontEnd )
				)
				( attribute "PART_NUMBER" "G21796-017"
					( Origin gFrontEnd )
				)
				( attribute "PHYS_PAGE" "121"
					( Origin gFrontEnd )
				)
				( attribute "ROOM" "SB"
					( Origin gFrontEnd )
				)
				( attribute "ROT" "0"
					( Origin gFrontEnd )
				)
				( attribute "SEC" "1"
					( Origin gFrontEnd )
				)
				( attribute "SEC_TYPE" "0402"
					( Origin gFrontEnd )
				)
				( attribute "TOLERANCE" "1%"
					( Origin gFrontEnd )
				)
				( attribute "VALUE" "100.0"
					( Origin gFrontEnd )
				)
				( attribute "VER" "2"
					( Origin gFrontEnd )
				)
				( attribute "WATTAGE" "1/16W"
					( Origin gFrontEnd )
				)
				( attribute "XY" "(-7750,3675)"
					( Origin gFrontEnd )
				)
				( attribute "CHIPS_PART_NAME" "RES"
					( Origin gPackager )
				)
				( attribute "CDS_PART_NAME" "RES_0402-100.0,1%,1/16W,CHIP,GA"
					( Origin gPackager )
				)
				( objectStatus "R8C26" )
				( pin "a"
					( attribute "PN" "1"
						( Origin gPackager )
					)
					( objectStatus "R8C26.1" )
				)
				( pin "b"
					( attribute "PN" "2"
						( Origin gPackager )
					)
					( objectStatus "R8C26.2" )
				)
			)
			( gate "@baseboard_fab2_lib.baseboard_fab2(sch_1):page121_i37"
				( attribute "CDS_LIB" "mstr_discrete"
					( Origin gPackager )
				)
				( attribute "CDS_LOCATION" "R3N10"
					( Origin gPackager )
				)
				( attribute "CDS_SEC" "1"
					( Origin gPackager )
				)
				( attribute "LOCATION" "R3N10"
					( Origin gFrontEnd )
				)
				( attribute "MATERIAL" "CHIP"
					( Origin gFrontEnd )
				)
				( attribute "PACK_TYPE" "0402"
					( Origin gFrontEnd )
				)
				( attribute "PART_NUMBER" "G21796-016"
					( Origin gFrontEnd )
				)
				( attribute "PHYS_PAGE" "121"
					( Origin gFrontEnd )
				)
				( attribute "ROOM" "SB"
					( Origin gFrontEnd )
				)
				( attribute "ROT" "0"
					( Origin gFrontEnd )
				)
				( attribute "SEC" "1"
					( Origin gFrontEnd )
				)
				( attribute "SEC_TYPE" "0402"
					( Origin gFrontEnd )
				)
				( attribute "TOLERANCE" "1%"
					( Origin gFrontEnd )
				)
				( attribute "VALUE" "10.0K"
					( Origin gFrontEnd )
				)
				( attribute "VER" "2"
					( Origin gFrontEnd )
				)
				( attribute "WATTAGE" "1/16W"
					( Origin gFrontEnd )
				)
				( attribute "XY" "(-8075,2525)"
					( Origin gFrontEnd )
				)
				( attribute "CHIPS_PART_NAME" "RES"
					( Origin gPackager )
				)
				( attribute "CDS_PART_NAME" "RES_0402-10.0K,1%,1/16W,CHIP,GA"
					( Origin gPackager )
				)
				( objectStatus "R3N10" )
				( pin "a"
					( attribute "PN" "1"
						( Origin gPackager )
					)
					( objectStatus "R3N10.1" )
				)
				( pin "b"
					( attribute "PN" "2"
						( Origin gPackager )
					)
					( objectStatus "R3N10.2" )
				)
			)
			( gate "@baseboard_fab2_lib.baseboard_fab2(sch_1):page121_i73"
				( attribute "BOM_COST" "NT_GBE_BASE"
					( Origin gFrontEnd )
				)
				( attribute "CDS_LIB" "mstr_discrete"
					( Origin gPackager )
				)
				( attribute "CDS_LOCATION" "R7C20"
					( Origin gPackager )
				)
				( attribute "CDS_SEC" "1"
					( Origin gPackager )
				)
				( attribute "LOCATION" "R7C20"
					( Origin gFrontEnd )
				)
				( attribute "MATERIAL" "CHIP"
					( Origin gFrontEnd )
				)
				( attribute "PACK_TYPE" "0402"
					( Origin gFrontEnd )
				)
				( attribute "PART_NUMBER" "G21796-016"
					( Origin gFrontEnd )
				)
				( attribute "PHYS_PAGE" "121"
					( Origin gFrontEnd )
				)
				( attribute "ROOM" "NIC_SPRV"
					( Origin gFrontEnd )
				)
				( attribute "ROT" "0"
					( Origin gFrontEnd )
				)
				( attribute "SEC" "1"
					( Origin gFrontEnd )
				)
				( attribute "SEC_TYPE" "0402"
					( Origin gFrontEnd )
				)
				( attribute "TOLERANCE" "1%"
					( Origin gFrontEnd )
				)
				( attribute "VALUE" "10.0K"
					( Origin gFrontEnd )
				)
				( attribute "VER" "2"
					( Origin gFrontEnd )
				)
				( attribute "WATTAGE" "1/16W"
					( Origin gFrontEnd )
				)
				( attribute "XY" "(-8125,950)"
					( Origin gFrontEnd )
				)
				( attribute "CHIPS_PART_NAME" "RES"
					( Origin gPackager )
				)
				( attribute "CDS_PART_NAME" "RES_0402-10.0K,1%,1/16W,CHIP,GA"
					( Origin gPackager )
				)
				( objectStatus "R7C20" )
				( pin "a"
					( attribute "PN" "1"
						( Origin gPackager )
					)
					( objectStatus "R7C20.1" )
				)
				( pin "b"
					( attribute "PN" "2"
						( Origin gPackager )
					)
					( objectStatus "R7C20.2" )
				)
			)
			( gate "@baseboard_fab2_lib.baseboard_fab2(sch_1):page121_i89"
				( attribute "CDS_LIB" "mstr_discrete"
					( Origin gPackager )
				)
				( attribute "CDS_LOCATION" "R3P3"
					( Origin gPackager )
				)
				( attribute "CDS_SEC" "1"
					( Origin gPackager )
				)
				( attribute "LOCATION" "R3P3"
					( Origin gFrontEnd )
				)
				( attribute "MATERIAL" "CHIP"
					( Origin gFrontEnd )
				)
				( attribute "PACK_TYPE" "0402"
					( Origin gFrontEnd )
				)
				( attribute "PART_NUMBER" "G21497-005"
					( Origin gFrontEnd )
				)
				( attribute "PHYS_PAGE" "121"
					( Origin gFrontEnd )
				)
				( attribute "ROT" "0"
					( Origin gFrontEnd )
				)
				( attribute "SEC" "1"
					( Origin gFrontEnd )
				)
				( attribute "SEC_TYPE" "0402"
					( Origin gFrontEnd )
				)
				( attribute "TOLERANCE" "5%"
					( Origin gFrontEnd )
				)
				( attribute "VALUE" "0.0"
					( Origin gFrontEnd )
				)
				( attribute "VER" "1"
					( Origin gFrontEnd )
				)
				( attribute "WATTAGE" "1/16W"
					( Origin gFrontEnd )
				)
				( attribute "XY" "(-5100,550)"
					( Origin gFrontEnd )
				)
				( attribute "CHIPS_PART_NAME" "RES"
					( Origin gPackager )
				)
				( attribute "CDS_PART_NAME" "RES_0402-0.0,5%,1/16W,CHIP,G21A"
					( Origin gPackager )
				)
				( objectStatus "R3P3" )
				( pin "a"
					( attribute "PN" "1"
						( Origin gPackager )
					)
					( objectStatus "R3P3.1" )
				)
				( pin "b"
					( attribute "PN" "2"
						( Origin gPackager )
					)
					( objectStatus "R3P3.2" )
				)
			)
			( gate "@baseboard_fab2_lib.baseboard_fab2(sch_1):page121_i90"
				( attribute "CDS_LIB" "mstr_discrete"
					( Origin gPackager )
				)
				( attribute "CDS_LOCATION" "R3P2"
					( Origin gPackager )
				)
				( attribute "CDS_SEC" "1"
					( Origin gPackager )
				)
				( attribute "LOCATION" "R3P2"
					( Origin gFrontEnd )
				)
				( attribute "MATERIAL" "CHIP"
					( Origin gFrontEnd )
				)
				( attribute "PACK_TYPE" "0402"
					( Origin gFrontEnd )
				)
				( attribute "PART_NUMBER" "G21497-005"
					( Origin gFrontEnd )
				)
				( attribute "PHYS_PAGE" "121"
					( Origin gFrontEnd )
				)
				( attribute "ROT" "0"
					( Origin gFrontEnd )
				)
				( attribute "SEC" "1"
					( Origin gFrontEnd )
				)
				( attribute "SEC_TYPE" "0402"
					( Origin gFrontEnd )
				)
				( attribute "TOLERANCE" "5%"
					( Origin gFrontEnd )
				)
				( attribute "VALUE" "0.0"
					( Origin gFrontEnd )
				)
				( attribute "VER" "1"
					( Origin gFrontEnd )
				)
				( attribute "WATTAGE" "1/16W"
					( Origin gFrontEnd )
				)
				( attribute "XY" "(-5100,850)"
					( Origin gFrontEnd )
				)
				( attribute "CHIPS_PART_NAME" "RES"
					( Origin gPackager )
				)
				( attribute "CDS_PART_NAME" "RES_0402-0.0,5%,1/16W,CHIP,G21A"
					( Origin gPackager )
				)
				( objectStatus "R3P2" )
				( pin "a"
					( attribute "PN" "1"
						( Origin gPackager )
					)
					( objectStatus "R3P2.1" )
				)
				( pin "b"
					( attribute "PN" "2"
						( Origin gPackager )
					)
					( objectStatus "R3P2.2" )
				)
			)
			( gate "@baseboard_fab2_lib.baseboard_fab2(sch_1):page121_i91"
				( attribute "CDS_LIB" "mstr_discrete"
					( Origin gPackager )
				)
				( attribute "CDS_LOCATION" "R2P1"
					( Origin gPackager )
				)
				( attribute "CDS_SEC" "1"
					( Origin gPackager )
				)
				( attribute "LOCATION" "R2P1"
					( Origin gFrontEnd )
				)
				( attribute "MATERIAL" "CHIP"
					( Origin gFrontEnd )
				)
				( attribute "PACK_TYPE" "0402"
					( Origin gFrontEnd )
				)
				( attribute "PART_NUMBER" "G21497-005"
					( Origin gFrontEnd )
				)
				( attribute "PHYS_PAGE" "121"
					( Origin gFrontEnd )
				)
				( attribute "ROT" "0"
					( Origin gFrontEnd )
				)
				( attribute "SEC" "1"
					( Origin gFrontEnd )
				)
				( attribute "SEC_TYPE" "0402"
					( Origin gFrontEnd )
				)
				( attribute "TOLERANCE" "5%"
					( Origin gFrontEnd )
				)
				( attribute "VALUE" "0.0"
					( Origin gFrontEnd )
				)
				( attribute "VER" "1"
					( Origin gFrontEnd )
				)
				( attribute "WATTAGE" "1/16W"
					( Origin gFrontEnd )
				)
				( attribute "XY" "(-5100,700)"
					( Origin gFrontEnd )
				)
				( attribute "CHIPS_PART_NAME" "RES"
					( Origin gPackager )
				)
				( attribute "CDS_PART_NAME" "RES_0402-0.0,5%,1/16W,CHIP,G21A"
					( Origin gPackager )
				)
				( objectStatus "R2P1" )
				( pin "a"
					( attribute "PN" "1"
						( Origin gPackager )
					)
					( objectStatus "R2P1.1" )
				)
				( pin "b"
					( attribute "PN" "2"
						( Origin gPackager )
					)
					( objectStatus "R2P1.2" )
				)
			)
			( gate "@baseboard_fab2_lib.baseboard_fab2(sch_1):page121_i98"
				( attribute "CDS_LIB" "mstr_discrete"
					( Origin gPackager )
				)
				( attribute "CDS_LOCATION" "R7C14"
					( Origin gPackager )
				)
				( attribute "CDS_SEC" "1"
					( Origin gPackager )
				)
				( attribute "LOCATION" "R7C14"
					( Origin gFrontEnd )
				)
				( attribute "MATERIAL" "CHIP"
					( Origin gFrontEnd )
				)
				( attribute "PACK_TYPE" "0402"
					( Origin gFrontEnd )
				)
				( attribute "PART_NUMBER" "G21796-074"
					( Origin gFrontEnd )
				)
				( attribute "PHYS_PAGE" "121"
					( Origin gFrontEnd )
				)
				( attribute "ROOM" "SB"
					( Origin gFrontEnd )
				)
				( attribute "ROT" "0"
					( Origin gFrontEnd )
				)
				( attribute "SEC" "1"
					( Origin gFrontEnd )
				)
				( attribute "SEC_TYPE" "0402"
					( Origin gFrontEnd )
				)
				( attribute "TOLERANCE" "1%"
					( Origin gFrontEnd )
				)
				( attribute "VALUE" "33.2"
					( Origin gFrontEnd )
				)
				( attribute "VER" "1"
					( Origin gFrontEnd )
				)
				( attribute "WATTAGE" "1/16W"
					( Origin gFrontEnd )
				)
				( attribute "XY" "(-5100,1025)"
					( Origin gFrontEnd )
				)
				( attribute "CHIPS_PART_NAME" "RES"
					( Origin gPackager )
				)
				( attribute "CDS_PART_NAME" "RES_0402-33.2,1%,1/16W,CHIP,G2A"
					( Origin gPackager )
				)
				( objectStatus "R7C14" )
				( pin "a"
					( attribute "PN" "1"
						( Origin gPackager )
					)
					( objectStatus "R7C14.1" )
				)
				( pin "b"
					( attribute "PN" "2"
						( Origin gPackager )
					)
					( objectStatus "R7C14.2" )
				)
			)
			( gate "@baseboard_fab2_lib.baseboard_fab2(sch_1):page121_i101"
				( attribute "CDS_LIB" "mstr_discrete"
					( Origin gPackager )
				)
				( attribute "CDS_LOCATION" "R8D11"
					( Origin gPackager )
				)
				( attribute "CDS_SEC" "1"
					( Origin gPackager )
				)
				( attribute "LOCATION" "R8D11"
					( Origin gFrontEnd )
				)
				( attribute "MATERIAL" "CHIP"
					( Origin gFrontEnd )
				)
				( attribute "PACK_TYPE" "0402"
					( Origin gFrontEnd )
				)
				( attribute "PART_NUMBER" "G21796-074"
					( Origin gFrontEnd )
				)
				( attribute "PHYS_PAGE" "121"
					( Origin gFrontEnd )
				)
				( attribute "ROOM" "SB"
					( Origin gFrontEnd )
				)
				( attribute "ROT" "0"
					( Origin gFrontEnd )
				)
				( attribute "SEC" "1"
					( Origin gFrontEnd )
				)
				( attribute "SEC_TYPE" "0402"
					( Origin gFrontEnd )
				)
				( attribute "TOLERANCE" "1%"
					( Origin gFrontEnd )
				)
				( attribute "VALUE" "33.2"
					( Origin gFrontEnd )
				)
				( attribute "VER" "1"
					( Origin gFrontEnd )
				)
				( attribute "WATTAGE" "1/16W"
					( Origin gFrontEnd )
				)
				( attribute "XY" "(-5100,1175)"
					( Origin gFrontEnd )
				)
				( attribute "CHIPS_PART_NAME" "RES"
					( Origin gPackager )
				)
				( attribute "CDS_PART_NAME" "RES_0402-33.2,1%,1/16W,CHIP,G2A"
					( Origin gPackager )
				)
				( objectStatus "R8D11" )
				( pin "a"
					( attribute "PN" "1"
						( Origin gPackager )
					)
					( objectStatus "R8D11.1" )
				)
				( pin "b"
					( attribute "PN" "2"
						( Origin gPackager )
					)
					( objectStatus "R8D11.2" )
				)
			)
			( gate "@baseboard_fab2_lib.baseboard_fab2(sch_1):page122_i63"
				( attribute "BOM_COST" "SB"
					( Origin gFrontEnd )
				)
				( attribute "CDS_LIB" "mstr_u_proc"
					( Origin gPackager )
				)
				( attribute "CDS_LOCATION" "U7C1"
					( Origin gPackager )
				)
				( attribute "CDS_SEC" "9"
					( Origin gPackager )
				)
				( attribute "LOCATION" "U7C1"
					( Origin gFrontEnd )
				)
				( attribute "MATERIAL" "IC"
					( Origin gFrontEnd )
				)
				( attribute "PACK_TYPE" "BGA1"
					( Origin gFrontEnd )
				)
				( attribute "PART_NUMBER" "H91415-002"
					( Origin gFrontEnd )
				)
				( attribute "PHYS_PAGE" "122"
					( Origin gFrontEnd )
				)
				( attribute "ROOM" "SB"
					( Origin gFrontEnd )
				)
				( attribute "ROT" "0"
					( Origin gFrontEnd )
				)
				( attribute "SEC" "9"
					( Origin gFrontEnd )
				)
				( attribute "SEC_TYPE" "BGA1"
					( Origin gFrontEnd )
				)
				( attribute "VER" "9"
					( Origin gFrontEnd )
				)
				( attribute "XY" "(-3900,3075)"
					( Origin gFrontEnd )
				)
				( attribute "CHIPS_PART_NAME" "LBG_CORE_QAT_EXT_D"
					( Origin gPackager )
				)
				( attribute "CDS_PART_NAME" "LBG_CORE_QAT_EXT_D_BGA1-IC,H91A"
					( Origin gPackager )
				)
				( objectStatus "U7C1" )
				( pin "rsvd(28)"
					( attribute "PN" "R35"
						( Origin gPackager )
					)
					( objectStatus "U7C1.R35" )
				)
				( pin "rsvd(29)"
					( attribute "PN" "P33"
						( Origin gPackager )
					)
					( objectStatus "U7C1.P33" )
				)
				( pin "rsvd(30)"
					( attribute "PN" "R31"
						( Origin gPackager )
					)
					( objectStatus "U7C1.R31" )
				)
				( pin "rsvd(31)"
					( attribute "PN" "P29"
						( Origin gPackager )
					)
					( objectStatus "U7C1.P29" )
				)
				( pin "rsvd(32)"
					( attribute "CDS_NOT_ON_SYM" "TRUE"
						( Origin gFrontEnd )
					)
				)
				( pin "rsvd(33)"
					( attribute "CDS_NOT_ON_SYM" "TRUE"
						( Origin gFrontEnd )
					)
				)
				( pin "rsvd(34)"
					( attribute "CDS_NOT_ON_SYM" "TRUE"
						( Origin gFrontEnd )
					)
				)
				( pin "rsvd(35)"
					( attribute "CDS_NOT_ON_SYM" "TRUE"
						( Origin gFrontEnd )
					)
				)
				( pin "rsvd(36)"
					( attribute "CDS_NOT_ON_SYM" "TRUE"
						( Origin gFrontEnd )
					)
				)
				( pin "rsvd(37)"
					( attribute "CDS_NOT_ON_SYM" "TRUE"
						( Origin gFrontEnd )
					)
				)
				( pin "rsvd(38)"
					( attribute "CDS_NOT_ON_SYM" "TRUE"
						( Origin gFrontEnd )
					)
				)
				( pin "rsvd(39)"
					( attribute "CDS_NOT_ON_SYM" "TRUE"
						( Origin gFrontEnd )
					)
				)
				( pin "rsvd(40)"
					( attribute "CDS_NOT_ON_SYM" "TRUE"
						( Origin gFrontEnd )
					)
				)
				( pin "rsvd(41)"
					( attribute "CDS_NOT_ON_SYM" "TRUE"
						( Origin gFrontEnd )
					)
				)
				( pin "rsvd(42)"
					( attribute "CDS_NOT_ON_SYM" "TRUE"
						( Origin gFrontEnd )
					)
				)
				( pin "rsvd(43)"
					( attribute "CDS_NOT_ON_SYM" "TRUE"
						( Origin gFrontEnd )
					)
				)
				( pin "rsvd(44)"
					( attribute "CDS_NOT_ON_SYM" "TRUE"
						( Origin gFrontEnd )
					)
				)
				( pin "rsvd(45)"
					( attribute "CDS_NOT_ON_SYM" "TRUE"
						( Origin gFrontEnd )
					)
				)
				( pin "rsvd(46)"
					( attribute "CDS_NOT_ON_SYM" "TRUE"
						( Origin gFrontEnd )
					)
				)
				( pin "rsvd(47)"
					( attribute "CDS_NOT_ON_SYM" "TRUE"
						( Origin gFrontEnd )
					)
				)
				( pin "rsvd(48)"
					( attribute "CDS_NOT_ON_SYM" "TRUE"
						( Origin gFrontEnd )
					)
				)
				( pin "rsvd(49)"
					( attribute "CDS_NOT_ON_SYM" "TRUE"
						( Origin gFrontEnd )
					)
				)
				( pin "rsvd(50)"
					( attribute "CDS_NOT_ON_SYM" "TRUE"
						( Origin gFrontEnd )
					)
				)
				( pin "rsvd(51)"
					( attribute "CDS_NOT_ON_SYM" "TRUE"
						( Origin gFrontEnd )
					)
				)
				( pin "rsvd(52)"
					( attribute "CDS_NOT_ON_SYM" "TRUE"
						( Origin gFrontEnd )
					)
				)
				( pin "rsvd(53)"
					( attribute "CDS_NOT_ON_SYM" "TRUE"
						( Origin gFrontEnd )
					)
				)
				( pin "rsvd(54)"
					( attribute "CDS_NOT_ON_SYM" "TRUE"
						( Origin gFrontEnd )
					)
				)
				( pin "rsvd(55)"
					( attribute "CDS_NOT_ON_SYM" "TRUE"
						( Origin gFrontEnd )
					)
				)
				( pin "rsvd(56)"
					( attribute "CDS_NOT_ON_SYM" "TRUE"
						( Origin gFrontEnd )
					)
				)
				( pin "rsvd(57)"
					( attribute "CDS_NOT_ON_SYM" "TRUE"
						( Origin gFrontEnd )
					)
				)
				( pin "rsvd(58)"
					( attribute "PN" "AP27"
						( Origin gPackager )
					)
					( objectStatus "U7C1.AP27" )
				)
				( pin "rsvd(59)"
					( attribute "PN" "AT27"
						( Origin gPackager )
					)
					( objectStatus "U7C1.AT27" )
				)
				( pin "vcca_clkfilt_1p05(0)"
					( attribute "PN" "W50"
						( Origin gPackager )
					)
					( objectStatus "U7C1.W50" )
				)
				( pin "vcca_clkfilt_1p05(1)"
					( attribute "PN" "AG45"
						( Origin gPackager )
					)
					( objectStatus "U7C1.AG45" )
				)
				( pin "vcca_clkfilt_1p05(2)"
					( attribute "PN" "AJ46"
						( Origin gPackager )
					)
					( objectStatus "U7C1.AJ46" )
				)
				( pin "vcca_clkfilt_1p05(3)"
					( attribute "PN" "AJ48"
						( Origin gPackager )
					)
					( objectStatus "U7C1.AJ48" )
				)
				( pin "vcca_clkfilt_1p05(4)"
					( attribute "PN" "AE46"
						( Origin gPackager )
					)
					( objectStatus "U7C1.AE46" )
				)
				( pin "vcca_clkunf_1p05(0)"
					( attribute "PN" "AH50"
						( Origin gPackager )
					)
					( objectStatus "U7C1.AH50" )
				)
				( pin "vcca_clkunf_1p05(1)"
					( attribute "PN" "U50"
						( Origin gPackager )
					)
					( objectStatus "U7C1.U50" )
				)
				( pin "vcca_clkxtal_1p05"
					( attribute "PN" "AD50"
						( Origin gPackager )
					)
					( objectStatus "U7C1.AD50" )
				)
				( pin "vcca_pll0_1p05"
					( attribute "PN" "AG48"
						( Origin gPackager )
					)
					( objectStatus "U7C1.AG48" )
				)
				( pin "vcca_pll1_1p05"
					( attribute "PN" "AE45"
						( Origin gPackager )
					)
					( objectStatus "U7C1.AE45" )
				)
				( pin "vccmphy_1p05(0)"
					( attribute "PN" "AW45"
						( Origin gPackager )
					)
					( objectStatus "U7C1.AW45" )
				)
				( pin "vccmphy_1p05(1)"
					( attribute "PN" "AW43"
						( Origin gPackager )
					)
					( objectStatus "U7C1.AW43" )
				)
				( pin "vccmphy_1p05(2)"
					( attribute "PN" "AJ43"
						( Origin gPackager )
					)
					( objectStatus "U7C1.AJ43" )
				)
				( pin "vccmphy_1p05(3)"
					( attribute "PN" "AU45"
						( Origin gPackager )
					)
					( objectStatus "U7C1.AU45" )
				)
				( pin "vccmphy_1p05(4)"
					( attribute "PN" "AU43"
						( Origin gPackager )
					)
					( objectStatus "U7C1.AU43" )
				)
				( pin "vccmphy_1p05(5)"
					( attribute "PN" "AT45"
						( Origin gPackager )
					)
					( objectStatus "U7C1.AT45" )
				)
				( pin "vccmphy_1p05(6)"
					( attribute "PN" "AT43"
						( Origin gPackager )
					)
					( objectStatus "U7C1.AT43" )
				)
				( pin "vccmphy_1p05(7)"
					( attribute "PN" "AP45"
						( Origin gPackager )
					)
					( objectStatus "U7C1.AP45" )
				)
				( pin "vccmphy_1p05(8)"
					( attribute "PN" "AP43"
						( Origin gPackager )
					)
					( objectStatus "U7C1.AP43" )
				)
				( pin "vccmphy_1p05(9)"
					( attribute "PN" "AM45"
						( Origin gPackager )
					)
					( objectStatus "U7C1.AM45" )
				)
				( pin "vccmphy_1p05(10)"
					( attribute "PN" "AM43"
						( Origin gPackager )
					)
					( objectStatus "U7C1.AM43" )
				)
				( pin "vccmphy_1p05(11)"
					( attribute "PN" "AK45"
						( Origin gPackager )
					)
					( objectStatus "U7C1.AK45" )
				)
				( pin "vccmphy_1p05(12)"
					( attribute "PN" "AK43"
						( Origin gPackager )
					)
					( objectStatus "U7C1.AK43" )
				)
				( pin "vccp10gbe_hv_1p8(0)"
					( attribute "PN" "BA29"
						( Origin gPackager )
					)
					( objectStatus "U7C1.BA29" )
				)
				( pin "vccp10gbe_hv_1p8(1)"
					( attribute "PN" "BA27"
						( Origin gPackager )
					)
					( objectStatus "U7C1.BA27" )
				)
				( pin "vccp10gbe_lv_1p05(0)"
					( attribute "PN" "BB37"
						( Origin gPackager )
					)
					( objectStatus "U7C1.BB37" )
				)
				( pin "vccp10gbe_lv_1p05(1)"
					( attribute "PN" "BB33"
						( Origin gPackager )
					)
					( objectStatus "U7C1.BB33" )
				)
				( pin "vccp10gbe_lv_1p05(2)"
					( attribute "PN" "BA37"
						( Origin gPackager )
					)
					( objectStatus "U7C1.BA37" )
				)
				( pin "vccp10gbe_lv_1p05(3)"
					( attribute "PN" "BA36"
						( Origin gPackager )
					)
					( objectStatus "U7C1.BA36" )
				)
				( pin "vccp10gbe_lv_1p05(4)"
					( attribute "PN" "BA34"
						( Origin gPackager )
					)
					( objectStatus "U7C1.BA34" )
				)
				( pin "vccp10gbe_lv_1p05(5)"
					( attribute "PN" "BA32"
						( Origin gPackager )
					)
					( objectStatus "U7C1.BA32" )
				)
				( pin "vccp10gbe_lv_1p05(6)"
					( attribute "PN" "BA30"
						( Origin gPackager )
					)
					( objectStatus "U7C1.BA30" )
				)
				( pin "vccp10gbepll_1p05(0)"
					( attribute "PN" "BD38"
						( Origin gPackager )
					)
					( objectStatus "U7C1.BD38" )
				)
				( pin "vccp10gbepll_1p05(1)"
					( attribute "PN" "BB40"
						( Origin gPackager )
					)
					( objectStatus "U7C1.BB40" )
				)
				( pin "vccp10gbepll_1p05(2)"
					( attribute "PN" "BA41"
						( Origin gPackager )
					)
					( objectStatus "U7C1.BA41" )
				)
				( pin "vccp10gbepll_1p05(3)"
					( attribute "PN" "BA39"
						( Origin gPackager )
					)
					( objectStatus "U7C1.BA39" )
				)
				( pin "vccp_1p8(0)"
					( attribute "PN" "BD46"
						( Origin gPackager )
					)
					( objectStatus "U7C1.BD46" )
				)
				( pin "vccp_1p8(1)"
					( attribute "PN" "AE26"
						( Origin gPackager )
					)
					( objectStatus "U7C1.AE26" )
				)
				( pin "vccp_3p3(0)"
					( attribute "PN" "BA46"
						( Origin gPackager )
					)
					( objectStatus "U7C1.BA46" )
				)
				( pin "vccp_3p3(1)"
					( attribute "PN" "BA45"
						( Origin gPackager )
					)
					( objectStatus "U7C1.BA45" )
				)
				( pin "vccp_3p3(2)"
					( attribute "PN" "AD24"
						( Origin gPackager )
					)
					( objectStatus "U7C1.AD24" )
				)
				( pin "vccp_3p3(3)"
					( attribute "CDS_NOT_ON_SYM" "TRUE"
						( Origin gFrontEnd )
					)
				)
				( pin "vccp_3p3(4)"
					( attribute "CDS_NOT_ON_SYM" "TRUE"
						( Origin gFrontEnd )
					)
				)
				( pin "vccp_3p3(5)"
					( attribute "PN" "AN24"
						( Origin gPackager )
					)
					( objectStatus "U7C1.AN24" )
				)
				( pin "vccp_hsiopll_1p05(0)"
					( attribute "PN" "AW48"
						( Origin gPackager )
					)
					( objectStatus "U7C1.AW48" )
				)
				( pin "vccp_hsiopll_1p05(1)"
					( attribute "CDS_NOT_ON_SYM" "TRUE"
						( Origin gFrontEnd )
					)
				)
				( pin "vccp_hsiopll_1p05(2)"
					( attribute "PN" "AU48"
						( Origin gPackager )
					)
					( objectStatus "U7C1.AU48" )
				)
				( pin "vccp_hsiopll_1p05(3)"
					( attribute "PN" "AP48"
						( Origin gPackager )
					)
					( objectStatus "U7C1.AP48" )
				)
				( pin "vccp_hsiopllunf_1p05"
					( attribute "PN" "AT48"
						( Origin gPackager )
					)
					( objectStatus "U7C1.AT48" )
				)
				( pin "vccp_uppll_1p05(0)"
					( attribute "PN" "AN50"
						( Origin gPackager )
					)
					( objectStatus "U7C1.AN50" )
				)
				( pin "vccp_uppll_1p05(1)"
					( attribute "CDS_NOT_ON_SYM" "TRUE"
						( Origin gFrontEnd )
					)
				)
				( pin "vccp_uppll_1p05(2)"
					( attribute "PN" "AK50"
						( Origin gPackager )
					)
					( objectStatus "U7C1.AK50" )
				)
				( pin "vccp_uppllunf_1p05"
					( attribute "PN" "AM48"
						( Origin gPackager )
					)
					( objectStatus "U7C1.AM48" )
				)
				( pin "vccpdsw_3p3"
					( attribute "PN" "AH24"
						( Origin gPackager )
					)
					( objectStatus "U7C1.AH24" )
				)
				( pin "vccpgpp_1p8(0)"
					( attribute "PN" "AU29"
						( Origin gPackager )
					)
					( objectStatus "U7C1.AU29" )
				)
				( pin "vccpgpp_1p8(1)"
					( attribute "PN" "AW29"
						( Origin gPackager )
					)
					( objectStatus "U7C1.AW29" )
				)
				( pin "vccpgpp_1p8(2)"
					( attribute "PN" "AT29"
						( Origin gPackager )
					)
					( objectStatus "U7C1.AT29" )
				)
				( pin "vccpgpp_1p8(3)"
					( attribute "PN" "AM29"
						( Origin gPackager )
					)
					( objectStatus "U7C1.AM29" )
				)
				( pin "vccpgpp_1p8(4)"
					( attribute "PN" "AP29"
						( Origin gPackager )
					)
					( objectStatus "U7C1.AP29" )
				)
				( pin "vccpgpp_1p8(5)"
					( attribute "PN" "AW27"
						( Origin gPackager )
					)
					( objectStatus "U7C1.AW27" )
				)
				( pin "vccpgpp_1p8(6)"
					( attribute "PN" "AK24"
						( Origin gPackager )
					)
					( objectStatus "U7C1.AK24" )
				)
				( pin "vccpgppa"
					( attribute "PN" "AW24"
						( Origin gPackager )
					)
					( objectStatus "U7C1.AW24" )
				)
				( pin "vccpgppb"
					( attribute "PN" "BE26"
						( Origin gPackager )
					)
					( objectStatus "U7C1.BE26" )
				)
				( pin "vccpgppc"
					( attribute "PN" "BE40"
						( Origin gPackager )
					)
					( objectStatus "U7C1.BE40" )
				)
				( pin "vccpgppd"
					( attribute "PN" "BA43"
						( Origin gPackager )
					)
					( objectStatus "U7C1.BA43" )
				)
				( pin "vccpgppe"
					( attribute "PN" "BE44"
						( Origin gPackager )
					)
					( objectStatus "U7C1.BE44" )
				)
				( pin "vccpgppf"
					( attribute "PN" "AU27"
						( Origin gPackager )
					)
					( objectStatus "U7C1.AU27" )
				)
				( pin "vccpgppg"
					( attribute "PN" "BA26"
						( Origin gPackager )
					)
					( objectStatus "U7C1.BA26" )
				)
				( pin "vccpgpph"
					( attribute "PN" "BA24"
						( Origin gPackager )
					)
					( objectStatus "U7C1.BA24" )
				)
				( pin "vccpgppj"
					( attribute "PN" "BB26"
						( Origin gPackager )
					)
					( objectStatus "U7C1.BB26" )
				)
				( pin "vccpgppk"
					( attribute "PN" "AU24"
						( Origin gPackager )
					)
					( objectStatus "U7C1.AU24" )
				)
				( pin "vccphda_1p8"
					( attribute "PN" "AG27"
						( Origin gPackager )
					)
					( objectStatus "U7C1.AG27" )
				)
				( pin "vccprim_1p05(0)"
					( attribute "PN" "BF46"
						( Origin gPackager )
					)
					( objectStatus "U7C1.BF46" )
				)
				( pin "vccprim_1p05(1)"
					( attribute "PN" "BE48"
						( Origin gPackager )
					)
					( objectStatus "U7C1.BE48" )
				)
				( pin "vccprim_1p05(2)"
					( attribute "PN" "AU39"
						( Origin gPackager )
					)
					( objectStatus "U7C1.AU39" )
				)
				( pin "vccprim_1p05(3)"
					( attribute "PN" "AU37"
						( Origin gPackager )
					)
					( objectStatus "U7C1.AU37" )
				)
				( pin "vccprim_1p05(4)"
					( attribute "PN" "AT39"
						( Origin gPackager )
					)
					( objectStatus "U7C1.AT39" )
				)
				( pin "vccprim_1p05(5)"
					( attribute "PN" "AM27"
						( Origin gPackager )
					)
					( objectStatus "U7C1.AM27" )
				)
				( pin "vccprim_1p05(6)"
					( attribute "PN" "AJ29"
						( Origin gPackager )
					)
					( objectStatus "U7C1.AJ29" )
				)
				( pin "vccprim_1p05(7)"
					( attribute "PN" "AC26"
						( Origin gPackager )
					)
					( objectStatus "U7C1.AC26" )
				)
				( pin "vccprim_1p05(8)"
					( attribute "PN" "AA46"
						( Origin gPackager )
					)
					( objectStatus "U7C1.AA46" )
				)
				( pin "vccprim_1p05(9)"
					( attribute "PN" "AA45"
						( Origin gPackager )
					)
					( objectStatus "U7C1.AA45" )
				)
				( pin "vccprim_1p05(10)"
					( attribute "PN" "Y46"
						( Origin gPackager )
					)
					( objectStatus "U7C1.Y46" )
				)
				( pin "vccprim_1p05(11)"
					( attribute "PN" "Y45"
						( Origin gPackager )
					)
					( objectStatus "U7C1.Y45" )
				)
				( pin "vccprim_1p05(12)"
					( attribute "PN" "V44"
						( Origin gPackager )
					)
					( objectStatus "U7C1.V44" )
				)
				( pin "vccprim_1p05(13)"
					( attribute "PN" "U46"
						( Origin gPackager )
					)
					( objectStatus "U7C1.U46" )
				)
				( pin "vccprim_1p05(14)"
					( attribute "PN" "T44"
						( Origin gPackager )
					)
					( objectStatus "U7C1.T44" )
				)
				( pin "vccprim_1p05(15)"
					( attribute "PN" "R46"
						( Origin gPackager )
					)
					( objectStatus "U7C1.R46" )
				)
				( pin "vccprim_1p05(16)"
					( attribute "PN" "R42"
						( Origin gPackager )
					)
					( objectStatus "U7C1.R42" )
				)
				( pin "vccprim_1p05(17)"
					( attribute "PN" "AK27"
						( Origin gPackager )
					)
					( objectStatus "U7C1.AK27" )
				)
				( pin "vccprim_1p05(18)"
					( attribute "PN" "AA24"
						( Origin gPackager )
					)
					( objectStatus "U7C1.AA24" )
				)
				( pin "vccprim_1p05(19)"
					( attribute "PN" "Y26"
						( Origin gPackager )
					)
					( objectStatus "U7C1.Y26" )
				)
				( pin "vccprtc"
					( attribute "PN" "AJ27"
						( Origin gPackager )
					)
					( objectStatus "U7C1.AJ27" )
				)
				( pin "vccprtcprim_3p3"
					( attribute "PN" "AG29"
						( Origin gPackager )
					)
					( objectStatus "U7C1.AG29" )
				)
				( pin "vccpspi"
					( attribute "PN" "AR24"
						( Origin gPackager )
					)
					( objectStatus "U7C1.AR24" )
				)
				( pin "vccpspi_1p8"
					( attribute "PN" "AK29"
						( Origin gPackager )
					)
					( objectStatus "U7C1.AK29" )
				)
				( pin "vccpusbdsw_3p3"
					( attribute "PN" "BA48"
						( Origin gPackager )
					)
					( objectStatus "U7C1.BA48" )
				)
				( pin "vccrtcext"
					( attribute "PN" "AG22"
						( Origin gPackager )
					)
					( objectStatus "U7C1.AG22" )
				)
			)
			( gate "@baseboard_fab2_lib.baseboard_fab2(sch_1):page123_i13"
				( attribute "BOM_COST" "SB"
					( Origin gFrontEnd )
				)
				( attribute "CDS_LIB" "mstr_u_proc"
					( Origin gPackager )
				)
				( attribute "CDS_LOCATION" "U7C1"
					( Origin gPackager )
				)
				( attribute "CDS_SEC" "11"
					( Origin gPackager )
				)
				( attribute "LOCATION" "U7C1"
					( Origin gFrontEnd )
				)
				( attribute "MATERIAL" "IC"
					( Origin gFrontEnd )
				)
				( attribute "PACK_TYPE" "BGA1"
					( Origin gFrontEnd )
				)
				( attribute "PART_NUMBER" "H91415-002"
					( Origin gFrontEnd )
				)
				( attribute "PHYS_PAGE" "123"
					( Origin gFrontEnd )
				)
				( attribute "ROOM" "SB"
					( Origin gFrontEnd )
				)
				( attribute "ROT" "0"
					( Origin gFrontEnd )
				)
				( attribute "SEC" "11"
					( Origin gFrontEnd )
				)
				( attribute "SEC_TYPE" "BGA1"
					( Origin gFrontEnd )
				)
				( attribute "VER" "11"
					( Origin gFrontEnd )
				)
				( attribute "XY" "(-1625,2575)"
					( Origin gFrontEnd )
				)
				( attribute "CHIPS_PART_NAME" "LBG_CORE_QAT_EXT_D"
					( Origin gPackager )
				)
				( attribute "CDS_PART_NAME" "LBG_CORE_QAT_EXT_D_BGA1-IC,H91A"
					( Origin gPackager )
				)
				( objectStatus "U7C1" )
				( pin "vss(355)"
					( attribute "PN" "N31"
						( Origin gPackager )
					)
					( objectStatus "U7C1.N31" )
				)
				( pin "vss(356)"
					( attribute "PN" "N27"
						( Origin gPackager )
					)
					( objectStatus "U7C1.N27" )
				)
				( pin "vss(357)"
					( attribute "PN" "N24"
						( Origin gPackager )
					)
					( objectStatus "U7C1.N24" )
				)
				( pin "vss(358)"
					( attribute "PN" "N20"
						( Origin gPackager )
					)
					( objectStatus "U7C1.N20" )
				)
				( pin "vss(359)"
					( attribute "PN" "N17"
						( Origin gPackager )
					)
					( objectStatus "U7C1.N17" )
				)
				( pin "vss(360)"
					( attribute "PN" "N13"
						( Origin gPackager )
					)
					( objectStatus "U7C1.N13" )
				)
				( pin "vss(361)"
					( attribute "PN" "M48"
						( Origin gPackager )
					)
					( objectStatus "U7C1.M48" )
				)
				( pin "vss(362)"
					( attribute "PN" "M44"
						( Origin gPackager )
					)
					( objectStatus "U7C1.M44" )
				)
				( pin "vss(363)"
					( attribute "PN" "N50"
						( Origin gPackager )
					)
					( objectStatus "U7C1.N50" )
				)
				( pin "vss(364)"
					( attribute "PN" "N42"
						( Origin gPackager )
					)
					( objectStatus "U7C1.N42" )
				)
				( pin "vss(365)"
					( attribute "PN" "M40"
						( Origin gPackager )
					)
					( objectStatus "U7C1.M40" )
				)
				( pin "vss(366)"
					( attribute "PN" "M4"
						( Origin gPackager )
					)
					( objectStatus "U7C1.M4" )
				)
				( pin "vss(367)"
					( attribute "PN" "M37"
						( Origin gPackager )
					)
					( objectStatus "U7C1.M37" )
				)
				( pin "vss(368)"
					( attribute "PN" "M33"
						( Origin gPackager )
					)
					( objectStatus "U7C1.M33" )
				)
				( pin "vss(369)"
					( attribute "PN" "M29"
						( Origin gPackager )
					)
					( objectStatus "U7C1.M29" )
				)
				( pin "vss(370)"
					( attribute "PN" "M26"
						( Origin gPackager )
					)
					( objectStatus "U7C1.M26" )
				)
				( pin "vss(371)"
					( attribute "PN" "M22"
						( Origin gPackager )
					)
					( objectStatus "U7C1.M22" )
				)
				( pin "vss(372)"
					( attribute "PN" "M2"
						( Origin gPackager )
					)
					( objectStatus "U7C1.M2" )
				)
				( pin "vss(373)"
					( attribute "PN" "L68"
						( Origin gPackager )
					)
					( objectStatus "U7C1.L68" )
				)
				( pin "vss(374)"
					( attribute "PN" "L5"
						( Origin gPackager )
					)
					( objectStatus "U7C1.L5" )
				)
				( pin "vss(375)"
					( attribute "PN" "K71"
						( Origin gPackager )
					)
					( objectStatus "U7C1.K71" )
				)
				( pin "vss(376)"
					( attribute "PN" "K69"
						( Origin gPackager )
					)
					( objectStatus "U7C1.K69" )
				)
				( pin "vss(377)"
					( attribute "PN" "K54"
						( Origin gPackager )
					)
					( objectStatus "U7C1.K54" )
				)
				( pin "vss(378)"
					( attribute "PN" "J70"
						( Origin gPackager )
					)
					( objectStatus "U7C1.J70" )
				)
				( pin "vss(379)"
					( attribute "PN" "J68"
						( Origin gPackager )
					)
					( objectStatus "U7C1.J68" )
				)
				( pin "vss(380)"
					( attribute "PN" "J59"
						( Origin gPackager )
					)
					( objectStatus "U7C1.J59" )
				)
				( pin "vss(381)"
					( attribute "PN" "J44"
						( Origin gPackager )
					)
					( objectStatus "U7C1.J44" )
				)
				( pin "vss(382)"
					( attribute "PN" "J37"
						( Origin gPackager )
					)
					( objectStatus "U7C1.J37" )
				)
				( pin "vss(383)"
					( attribute "PN" "J22"
						( Origin gPackager )
					)
					( objectStatus "U7C1.J22" )
				)
				( pin "vss(384)"
					( attribute "PN" "J15"
						( Origin gPackager )
					)
					( objectStatus "U7C1.J15" )
				)
				( pin "vss(385)"
					( attribute "PN" "J11"
						( Origin gPackager )
					)
					( objectStatus "U7C1.J11" )
				)
				( pin "vss(386)"
					( attribute "PN" "H65"
						( Origin gPackager )
					)
					( objectStatus "U7C1.H65" )
				)
				( pin "vss(387)"
					( attribute "PN" "J7"
						( Origin gPackager )
					)
					( objectStatus "U7C1.J7" )
				)
				( pin "vss(388)"
					( attribute "PN" "J5"
						( Origin gPackager )
					)
					( objectStatus "U7C1.J5" )
				)
				( pin "vss(389)"
					( attribute "PN" "J29"
						( Origin gPackager )
					)
					( objectStatus "U7C1.J29" )
				)
				( pin "vss(390)"
					( attribute "PN" "H58"
						( Origin gPackager )
					)
					( objectStatus "U7C1.H58" )
				)
				( pin "vss(391)"
					( attribute "PN" "G66"
						( Origin gPackager )
					)
					( objectStatus "U7C1.G66" )
				)
				( pin "vss(392)"
					( attribute "PN" "G63"
						( Origin gPackager )
					)
					( objectStatus "U7C1.G63" )
				)
				( pin "vss(393)"
					( attribute "PN" "G6"
						( Origin gPackager )
					)
					( objectStatus "U7C1.G6" )
				)
				( pin "vss(394)"
					( attribute "PN" "G48"
						( Origin gPackager )
					)
					( objectStatus "U7C1.G48" )
				)
				( pin "vss(395)"
					( attribute "PN" "G37"
						( Origin gPackager )
					)
					( objectStatus "U7C1.G37" )
				)
				( pin "vss(396)"
					( attribute "PN" "G29"
						( Origin gPackager )
					)
					( objectStatus "U7C1.G29" )
				)
				( pin "vss(397)"
					( attribute "PN" "G22"
						( Origin gPackager )
					)
					( objectStatus "U7C1.G22" )
				)
				( pin "vss(398)"
					( attribute "PN" "E9"
						( Origin gPackager )
					)
					( objectStatus "U7C1.E9" )
				)
				( pin "vss(399)"
					( attribute "PN" "G59"
						( Origin gPackager )
					)
					( objectStatus "U7C1.G59" )
				)
				( pin "vss(400)"
					( attribute "PN" "E63"
						( Origin gPackager )
					)
					( objectStatus "U7C1.E63" )
				)
				( pin "vss(401)"
					( attribute "PN" "E61"
						( Origin gPackager )
					)
					( objectStatus "U7C1.E61" )
				)
				( pin "vss(402)"
					( attribute "PN" "E6"
						( Origin gPackager )
					)
					( objectStatus "U7C1.E6" )
				)
				( pin "vss(403)"
					( attribute "PN" "E57"
						( Origin gPackager )
					)
					( objectStatus "U7C1.E57" )
				)
				( pin "vss(404)"
					( attribute "PN" "E54"
						( Origin gPackager )
					)
					( objectStatus "U7C1.E54" )
				)
				( pin "vss(405)"
					( attribute "PN" "E52"
						( Origin gPackager )
					)
					( objectStatus "U7C1.E52" )
				)
				( pin "vss(406)"
					( attribute "PN" "E50"
						( Origin gPackager )
					)
					( objectStatus "U7C1.E50" )
				)
				( pin "vss(407)"
					( attribute "PN" "E48"
						( Origin gPackager )
					)
					( objectStatus "U7C1.E48" )
				)
				( pin "vss(408)"
					( attribute "PN" "E45"
						( Origin gPackager )
					)
					( objectStatus "U7C1.E45" )
				)
				( pin "vss(409)"
					( attribute "PN" "E43"
						( Origin gPackager )
					)
					( objectStatus "U7C1.E43" )
				)
				( pin "vss(410)"
					( attribute "PN" "E41"
						( Origin gPackager )
					)
					( objectStatus "U7C1.E41" )
				)
				( pin "vss(411)"
					( attribute "PN" "E39"
						( Origin gPackager )
					)
					( objectStatus "U7C1.E39" )
				)
				( pin "vss(412)"
					( attribute "PN" "E37"
						( Origin gPackager )
					)
					( objectStatus "U7C1.E37" )
				)
				( pin "vss(413)"
					( attribute "PN" "E34"
						( Origin gPackager )
					)
					( objectStatus "U7C1.E34" )
				)
				( pin "vss(414)"
					( attribute "PN" "E32"
						( Origin gPackager )
					)
					( objectStatus "U7C1.E32" )
				)
				( pin "vss(415)"
					( attribute "PN" "E30"
						( Origin gPackager )
					)
					( objectStatus "U7C1.E30" )
				)
				( pin "vss(416)"
					( attribute "PN" "E28"
						( Origin gPackager )
					)
					( objectStatus "U7C1.E28" )
				)
				( pin "vss(417)"
					( attribute "PN" "E26"
						( Origin gPackager )
					)
					( objectStatus "U7C1.E26" )
				)
				( pin "vss(418)"
					( attribute "PN" "E24"
						( Origin gPackager )
					)
					( objectStatus "U7C1.E24" )
				)
				( pin "vss(419)"
					( attribute "PN" "E22"
						( Origin gPackager )
					)
					( objectStatus "U7C1.E22" )
				)
				( pin "vss(420)"
					( attribute "PN" "E20"
						( Origin gPackager )
					)
					( objectStatus "U7C1.E20" )
				)
				( pin "vss(421)"
					( attribute "PN" "E15"
						( Origin gPackager )
					)
					( objectStatus "U7C1.E15" )
				)
				( pin "vss(422)"
					( attribute "PN" "E13"
						( Origin gPackager )
					)
					( objectStatus "U7C1.E13" )
				)
				( pin "vss(423)"
					( attribute "PN" "E11"
						( Origin gPackager )
					)
					( objectStatus "U7C1.E11" )
				)
				( pin "vss(424)"
					( attribute "PN" "D47"
						( Origin gPackager )
					)
					( objectStatus "U7C1.D47" )
				)
				( pin "vss(425)"
					( attribute "PN" "E65"
						( Origin gPackager )
					)
					( objectStatus "U7C1.E65" )
				)
				( pin "vss(426)"
					( attribute "PN" "E59"
						( Origin gPackager )
					)
					( objectStatus "U7C1.E59" )
				)
				( pin "vss(427)"
					( attribute "PN" "D27"
						( Origin gPackager )
					)
					( objectStatus "U7C1.D27" )
				)
				( pin "vss(428)"
					( attribute "PN" "D25"
						( Origin gPackager )
					)
					( objectStatus "U7C1.D25" )
				)
				( pin "vss(429)"
					( attribute "PN" "D19"
						( Origin gPackager )
					)
					( objectStatus "U7C1.D19" )
				)
				( pin "vss(430)"
					( attribute "PN" "D16"
						( Origin gPackager )
					)
					( objectStatus "U7C1.D16" )
				)
				( pin "vss(431)"
					( attribute "PN" "D12"
						( Origin gPackager )
					)
					( objectStatus "U7C1.D12" )
				)
				( pin "vss(432)"
					( attribute "PN" "C65"
						( Origin gPackager )
					)
					( objectStatus "U7C1.C65" )
				)
				( pin "vss(433)"
					( attribute "PN" "C41"
						( Origin gPackager )
					)
					( objectStatus "U7C1.C41" )
				)
				( pin "vss(434)"
					( attribute "PN" "C37"
						( Origin gPackager )
					)
					( objectStatus "U7C1.C37" )
				)
				( pin "vss(435)"
					( attribute "PN" "C34"
						( Origin gPackager )
					)
					( objectStatus "U7C1.C34" )
				)
				( pin "vss(436)"
					( attribute "PN" "C30"
						( Origin gPackager )
					)
					( objectStatus "U7C1.C30" )
				)
				( pin "vss(437)"
					( attribute "PN" "C22"
						( Origin gPackager )
					)
					( objectStatus "U7C1.C22" )
				)
				( pin "vss(438)"
					( attribute "PN" "B47"
						( Origin gPackager )
					)
					( objectStatus "U7C1.B47" )
				)
				( pin "vss(439)"
					( attribute "PN" "B27"
						( Origin gPackager )
					)
					( objectStatus "U7C1.B27" )
				)
				( pin "vss(440)"
					( attribute "PN" "B25"
						( Origin gPackager )
					)
					( objectStatus "U7C1.B25" )
				)
				( pin "vss(441)"
					( attribute "PN" "B19"
						( Origin gPackager )
					)
					( objectStatus "U7C1.B19" )
				)
				( pin "vss(442)"
					( attribute "PN" "B12"
						( Origin gPackager )
					)
					( objectStatus "U7C1.B12" )
				)
				( pin "vss(443)"
					( attribute "PN" "A41"
						( Origin gPackager )
					)
					( objectStatus "U7C1.A41" )
				)
				( pin "vss(444)"
					( attribute "PN" "A37"
						( Origin gPackager )
					)
					( objectStatus "U7C1.A37" )
				)
				( pin "vss(445)"
					( attribute "PN" "A34"
						( Origin gPackager )
					)
					( objectStatus "U7C1.A34" )
				)
				( pin "vss(446)"
					( attribute "PN" "A30"
						( Origin gPackager )
					)
					( objectStatus "U7C1.A30" )
				)
				( pin "vss(447)"
					( attribute "PN" "A22"
						( Origin gPackager )
					)
					( objectStatus "U7C1.A22" )
				)
				( pin "vss(448)"
					( attribute "PN" "A18"
						( Origin gPackager )
					)
					( objectStatus "U7C1.A18" )
				)
				( pin "vss(449)"
					( attribute "PN" "Y70"
						( Origin gPackager )
					)
					( objectStatus "U7C1.Y70" )
				)
				( pin "vss(450)"
					( attribute "PN" "Y72"
						( Origin gPackager )
					)
					( objectStatus "U7C1.Y72" )
				)
				( pin "vss(451)"
					( attribute "PN" "AT37"
						( Origin gPackager )
					)
					( objectStatus "U7C1.AT37" )
				)
				( pin "vss(452)"
					( attribute "PN" "BB48"
						( Origin gPackager )
					)
					( objectStatus "U7C1.BB48" )
				)
				( pin "vss(453)"
					( attribute "PN" "CA70"
						( Origin gPackager )
					)
					( objectStatus "U7C1.CA70" )
				)
				( pin "vss(454)"
					( attribute "PN" "BW72"
						( Origin gPackager )
					)
					( objectStatus "U7C1.BW72" )
				)
				( pin "vss(455)"
					( attribute "PN" "BW70"
						( Origin gPackager )
					)
					( objectStatus "U7C1.BW70" )
				)
				( pin "vss(456)"
					( attribute "PN" "BU72"
						( Origin gPackager )
					)
					( objectStatus "U7C1.BU72" )
				)
				( pin "vss(457)"
					( attribute "PN" "BR72"
						( Origin gPackager )
					)
					( objectStatus "U7C1.BR72" )
				)
				( pin "vss(458)"
					( attribute "PN" "G72"
						( Origin gPackager )
					)
					( objectStatus "U7C1.G72" )
				)
				( pin "vss(459)"
					( attribute "PN" "G1"
						( Origin gPackager )
					)
					( objectStatus "U7C1.G1" )
				)
				( pin "vss(460)"
					( attribute "PN" "E72"
						( Origin gPackager )
					)
					( objectStatus "U7C1.E72" )
				)
				( pin "vss(461)"
					( attribute "PN" "E1"
						( Origin gPackager )
					)
					( objectStatus "U7C1.E1" )
				)
				( pin "vss(462)"
					( attribute "PN" "C72"
						( Origin gPackager )
					)
					( objectStatus "U7C1.C72" )
				)
				( pin "vss(463)"
					( attribute "PN" "C3"
						( Origin gPackager )
					)
					( objectStatus "U7C1.C3" )
				)
				( pin "vss(464)"
					( attribute "PN" "BR1"
						( Origin gPackager )
					)
					( objectStatus "U7C1.BR1" )
				)
				( pin "vss(465)"
					( attribute "PN" "BU1"
						( Origin gPackager )
					)
					( objectStatus "U7C1.BU1" )
				)
				( pin "vss(466)"
					( attribute "PN" "BW1"
						( Origin gPackager )
					)
					( objectStatus "U7C1.BW1" )
				)
				( pin "vss(467)"
					( attribute "PN" "CA3"
						( Origin gPackager )
					)
					( objectStatus "U7C1.CA3" )
				)
				( pin "vss(468)"
					( attribute "PN" "A70"
						( Origin gPackager )
					)
					( objectStatus "U7C1.A70" )
				)
				( pin "vss(469)"
					( attribute "PN" "CA5"
						( Origin gPackager )
					)
					( objectStatus "U7C1.CA5" )
				)
				( pin "vss(470)"
					( attribute "PN" "CA7"
						( Origin gPackager )
					)
					( objectStatus "U7C1.CA7" )
				)
				( pin "vss(471)"
					( attribute "PN" "CA9"
						( Origin gPackager )
					)
					( objectStatus "U7C1.CA9" )
				)
				( pin "vss(472)"
					( attribute "PN" "CA65"
						( Origin gPackager )
					)
					( objectStatus "U7C1.CA65" )
				)
				( pin "vss(473)"
					( attribute "PN" "CA66"
						( Origin gPackager )
					)
					( objectStatus "U7C1.CA66" )
				)
				( pin "vss(474)"
					( attribute "PN" "CA68"
						( Origin gPackager )
					)
					( objectStatus "U7C1.CA68" )
				)
				( pin "vss(475)"
					( attribute "PN" "BN72"
						( Origin gPackager )
					)
					( objectStatus "U7C1.BN72" )
				)
				( pin "vss(476)"
					( attribute "PN" "BN1"
						( Origin gPackager )
					)
					( objectStatus "U7C1.BN1" )
				)
				( pin "vss(477)"
					( attribute "PN" "J72"
						( Origin gPackager )
					)
					( objectStatus "U7C1.J72" )
				)
				( pin "vss(478)"
					( attribute "PN" "J1"
						( Origin gPackager )
					)
					( objectStatus "U7C1.J1" )
				)
				( pin "vss(479)"
					( attribute "PN" "A68"
						( Origin gPackager )
					)
					( objectStatus "U7C1.A68" )
				)
				( pin "vss(480)"
					( attribute "PN" "A66"
						( Origin gPackager )
					)
					( objectStatus "U7C1.A66" )
				)
				( pin "vss(481)"
					( attribute "PN" "A65"
						( Origin gPackager )
					)
					( objectStatus "U7C1.A65" )
				)
				( pin "vss(482)"
					( attribute "PN" "A9"
						( Origin gPackager )
					)
					( objectStatus "U7C1.A9" )
				)
				( pin "vss(483)"
					( attribute "PN" "A7"
						( Origin gPackager )
					)
					( objectStatus "U7C1.A7" )
				)
				( pin "vss(484)"
					( attribute "PN" "A5"
						( Origin gPackager )
					)
					( objectStatus "U7C1.A5" )
				)
				( pin "vss(485)"
					( attribute "PN" "E3"
						( Origin gPackager )
					)
					( objectStatus "U7C1.E3" )
				)
				( pin "vss(486)"
					( attribute "PN" "F3"
						( Origin gPackager )
					)
					( objectStatus "U7C1.F3" )
				)
				( pin "vss(487)"
					( attribute "PN" "BR3"
						( Origin gPackager )
					)
					( objectStatus "U7C1.BR3" )
				)
				( pin "vss(488)"
					( attribute "PN" "BU3"
						( Origin gPackager )
					)
					( objectStatus "U7C1.BU3" )
				)
				( pin "vss(489)"
					( attribute "PN" "E70"
						( Origin gPackager )
					)
					( objectStatus "U7C1.E70" )
				)
				( pin "vss(490)"
					( attribute "PN" "F70"
						( Origin gPackager )
					)
					( objectStatus "U7C1.F70" )
				)
				( pin "vss(491)"
					( attribute "PN" "BR70"
						( Origin gPackager )
					)
					( objectStatus "U7C1.BR70" )
				)
				( pin "vss(492)"
					( attribute "PN" "BU70"
						( Origin gPackager )
					)
					( objectStatus "U7C1.BU70" )
				)
				( pin "vss(493)"
					( attribute "PN" "BT69"
						( Origin gPackager )
					)
					( objectStatus "U7C1.BT69" )
				)
				( pin "vss(494)"
					( attribute "PN" "BP69"
						( Origin gPackager )
					)
					( objectStatus "U7C1.BP69" )
				)
			)
			( gate "@baseboard_fab2_lib.baseboard_fab2(sch_1):page123_i21"
				( attribute "BOM_COST" "SB"
					( Origin gFrontEnd )
				)
				( attribute "CDS_LIB" "mstr_u_proc"
					( Origin gPackager )
				)
				( attribute "CDS_LOCATION" "U7C1"
					( Origin gPackager )
				)
				( attribute "CDS_SEC" "10"
					( Origin gPackager )
				)
				( attribute "LOCATION" "U7C1"
					( Origin gFrontEnd )
				)
				( attribute "MATERIAL" "IC"
					( Origin gFrontEnd )
				)
				( attribute "PACK_TYPE" "BGA1"
					( Origin gFrontEnd )
				)
				( attribute "PART_NUMBER" "H91415-002"
					( Origin gFrontEnd )
				)
				( attribute "PHYS_PAGE" "123"
					( Origin gFrontEnd )
				)
				( attribute "ROOM" "SB"
					( Origin gFrontEnd )
				)
				( attribute "ROT" "0"
					( Origin gFrontEnd )
				)
				( attribute "SEC" "10"
					( Origin gFrontEnd )
				)
				( attribute "SEC_TYPE" "BGA1"
					( Origin gFrontEnd )
				)
				( attribute "VER" "10"
					( Origin gFrontEnd )
				)
				( attribute "XY" "(-5375,2600)"
					( Origin gFrontEnd )
				)
				( attribute "CHIPS_PART_NAME" "LBG_CORE_QAT_EXT_D"
					( Origin gPackager )
				)
				( attribute "CDS_PART_NAME" "LBG_CORE_QAT_EXT_D_BGA1-IC,H91A"
					( Origin gPackager )
				)
				( objectStatus "U7C1" )
				( pin "vccmphy_1p05(13)"
					( attribute "PN" "AE27"
						( Origin gPackager )
					)
					( objectStatus "U7C1.AE27" )
				)
				( pin "vccprim_avid(0)"
					( attribute "PN" "AU36"
						( Origin gPackager )
					)
					( objectStatus "U7C1.AU36" )
				)
				( pin "vccprim_avid(1)"
					( attribute "PN" "AU34"
						( Origin gPackager )
					)
					( objectStatus "U7C1.AU34" )
				)
				( pin "vccprim_avid(2)"
					( attribute "PN" "AU32"
						( Origin gPackager )
					)
					( objectStatus "U7C1.AU32" )
				)
				( pin "vccprim_avid(3)"
					( attribute "PN" "AT36"
						( Origin gPackager )
					)
					( objectStatus "U7C1.AT36" )
				)
				( pin "vccprim_avid(4)"
					( attribute "PN" "AT34"
						( Origin gPackager )
					)
					( objectStatus "U7C1.AT34" )
				)
				( pin "vccprim_avid(5)"
					( attribute "PN" "AT32"
						( Origin gPackager )
					)
					( objectStatus "U7C1.AT32" )
				)
				( pin "vccprim_avid(6)"
					( attribute "PN" "AP39"
						( Origin gPackager )
					)
					( objectStatus "U7C1.AP39" )
				)
				( pin "vccprim_avid(7)"
					( attribute "PN" "AP37"
						( Origin gPackager )
					)
					( objectStatus "U7C1.AP37" )
				)
				( pin "vccprim_avid(8)"
					( attribute "PN" "AP36"
						( Origin gPackager )
					)
					( objectStatus "U7C1.AP36" )
				)
				( pin "vccprim_avid(9)"
					( attribute "PN" "AP34"
						( Origin gPackager )
					)
					( objectStatus "U7C1.AP34" )
				)
				( pin "vccprim_avid(10)"
					( attribute "PN" "AP32"
						( Origin gPackager )
					)
					( objectStatus "U7C1.AP32" )
				)
				( pin "vccprim_avid(11)"
					( attribute "PN" "AM39"
						( Origin gPackager )
					)
					( objectStatus "U7C1.AM39" )
				)
				( pin "vccprim_avid(12)"
					( attribute "PN" "AM37"
						( Origin gPackager )
					)
					( objectStatus "U7C1.AM37" )
				)
				( pin "vccprim_avid(13)"
					( attribute "PN" "AM36"
						( Origin gPackager )
					)
					( objectStatus "U7C1.AM36" )
				)
				( pin "vccprim_avid(14)"
					( attribute "PN" "AM34"
						( Origin gPackager )
					)
					( objectStatus "U7C1.AM34" )
				)
				( pin "vccprim_avid(15)"
					( attribute "PN" "AM32"
						( Origin gPackager )
					)
					( objectStatus "U7C1.AM32" )
				)
				( pin "vccprim_avid(16)"
					( attribute "PN" "AK39"
						( Origin gPackager )
					)
					( objectStatus "U7C1.AK39" )
				)
				( pin "vccprim_avid(17)"
					( attribute "PN" "AK37"
						( Origin gPackager )
					)
					( objectStatus "U7C1.AK37" )
				)
				( pin "vccprim_avid(18)"
					( attribute "PN" "AK34"
						( Origin gPackager )
					)
					( objectStatus "U7C1.AK34" )
				)
				( pin "vccprim_avid(19)"
					( attribute "PN" "AG39"
						( Origin gPackager )
					)
					( objectStatus "U7C1.AG39" )
				)
				( pin "vccprim_avid(20)"
					( attribute "PN" "AG37"
						( Origin gPackager )
					)
					( objectStatus "U7C1.AG37" )
				)
				( pin "vccprim_avid(21)"
					( attribute "PN" "AG36"
						( Origin gPackager )
					)
					( objectStatus "U7C1.AG36" )
				)
				( pin "vccprim_avid(22)"
					( attribute "PN" "AG34"
						( Origin gPackager )
					)
					( objectStatus "U7C1.AG34" )
				)
				( pin "vccprim_avid(23)"
					( attribute "PN" "AG32"
						( Origin gPackager )
					)
					( objectStatus "U7C1.AG32" )
				)
				( pin "vccprim_avid(24)"
					( attribute "PN" "AE41"
						( Origin gPackager )
					)
					( objectStatus "U7C1.AE41" )
				)
				( pin "vccprim_avid(25)"
					( attribute "PN" "AE39"
						( Origin gPackager )
					)
					( objectStatus "U7C1.AE39" )
				)
				( pin "vccprim_avid(26)"
					( attribute "PN" "AE37"
						( Origin gPackager )
					)
					( objectStatus "U7C1.AE37" )
				)
				( pin "vccprim_avid(27)"
					( attribute "PN" "AE36"
						( Origin gPackager )
					)
					( objectStatus "U7C1.AE36" )
				)
				( pin "vccprim_avid(28)"
					( attribute "PN" "AE34"
						( Origin gPackager )
					)
					( objectStatus "U7C1.AE34" )
				)
				( pin "vccprim_avid(29)"
					( attribute "PN" "AE32"
						( Origin gPackager )
					)
					( objectStatus "U7C1.AE32" )
				)
				( pin "vccprim_avid(30)"
					( attribute "PN" "AE30"
						( Origin gPackager )
					)
					( objectStatus "U7C1.AE30" )
				)
				( pin "vccprim_avid(31)"
					( attribute "PN" "U27"
						( Origin gPackager )
					)
					( objectStatus "U7C1.U27" )
				)
				( pin "vccprim_avid(32)"
					( attribute "PN" "AC41"
						( Origin gPackager )
					)
					( objectStatus "U7C1.AC41" )
				)
				( pin "vccprim_avid(33)"
					( attribute "PN" "AC39"
						( Origin gPackager )
					)
					( objectStatus "U7C1.AC39" )
				)
				( pin "vccprim_avid(34)"
					( attribute "PN" "AC37"
						( Origin gPackager )
					)
					( objectStatus "U7C1.AC37" )
				)
				( pin "vccprim_avid(35)"
					( attribute "PN" "AC36"
						( Origin gPackager )
					)
					( objectStatus "U7C1.AC36" )
				)
				( pin "vccprim_avid(36)"
					( attribute "PN" "AC34"
						( Origin gPackager )
					)
					( objectStatus "U7C1.AC34" )
				)
				( pin "vccprim_avid(37)"
					( attribute "PN" "AC32"
						( Origin gPackager )
					)
					( objectStatus "U7C1.AC32" )
				)
				( pin "vccprim_avid(38)"
					( attribute "PN" "AC30"
						( Origin gPackager )
					)
					( objectStatus "U7C1.AC30" )
				)
				( pin "vccprim_avid(39)"
					( attribute "PN" "AC29"
						( Origin gPackager )
					)
					( objectStatus "U7C1.AC29" )
				)
				( pin "vccprim_avid(40)"
					( attribute "PN" "AA41"
						( Origin gPackager )
					)
					( objectStatus "U7C1.AA41" )
				)
				( pin "vccprim_avid(41)"
					( attribute "PN" "AA39"
						( Origin gPackager )
					)
					( objectStatus "U7C1.AA39" )
				)
				( pin "vccprim_avid(42)"
					( attribute "PN" "AA37"
						( Origin gPackager )
					)
					( objectStatus "U7C1.AA37" )
				)
				( pin "vccprim_avid(43)"
					( attribute "PN" "AA36"
						( Origin gPackager )
					)
					( objectStatus "U7C1.AA36" )
				)
				( pin "vccprim_avid(44)"
					( attribute "PN" "AA34"
						( Origin gPackager )
					)
					( objectStatus "U7C1.AA34" )
				)
				( pin "vccprim_avid(45)"
					( attribute "PN" "AA32"
						( Origin gPackager )
					)
					( objectStatus "U7C1.AA32" )
				)
				( pin "vccprim_avid(46)"
					( attribute "PN" "AA30"
						( Origin gPackager )
					)
					( objectStatus "U7C1.AA30" )
				)
				( pin "vccprim_avid(47)"
					( attribute "PN" "AA29"
						( Origin gPackager )
					)
					( objectStatus "U7C1.AA29" )
				)
				( pin "vccprim_avid(48)"
					( attribute "PN" "Y41"
						( Origin gPackager )
					)
					( objectStatus "U7C1.Y41" )
				)
				( pin "vccprim_avid(49)"
					( attribute "PN" "Y39"
						( Origin gPackager )
					)
					( objectStatus "U7C1.Y39" )
				)
				( pin "vccprim_avid(50)"
					( attribute "PN" "Y37"
						( Origin gPackager )
					)
					( objectStatus "U7C1.Y37" )
				)
				( pin "vccprim_avid(51)"
					( attribute "PN" "Y36"
						( Origin gPackager )
					)
					( objectStatus "U7C1.Y36" )
				)
				( pin "vccprim_avid(52)"
					( attribute "PN" "Y34"
						( Origin gPackager )
					)
					( objectStatus "U7C1.Y34" )
				)
				( pin "vccprim_avid(53)"
					( attribute "PN" "Y32"
						( Origin gPackager )
					)
					( objectStatus "U7C1.Y32" )
				)
				( pin "vccprim_avid(54)"
					( attribute "PN" "Y30"
						( Origin gPackager )
					)
					( objectStatus "U7C1.Y30" )
				)
				( pin "vccprim_avid(55)"
					( attribute "PN" "Y29"
						( Origin gPackager )
					)
					( objectStatus "U7C1.Y29" )
				)
				( pin "vccprim_avid(56)"
					( attribute "PN" "V40"
						( Origin gPackager )
					)
					( objectStatus "U7C1.V40" )
				)
				( pin "vccprim_avid(57)"
					( attribute "PN" "V33"
						( Origin gPackager )
					)
					( objectStatus "U7C1.V33" )
				)
				( pin "vccprim_avid(58)"
					( attribute "PN" "V29"
						( Origin gPackager )
					)
					( objectStatus "U7C1.V29" )
				)
				( pin "vccprim_avid(59)"
					( attribute "PN" "U38"
						( Origin gPackager )
					)
					( objectStatus "U7C1.U38" )
				)
				( pin "vccprim_avid(60)"
					( attribute "PN" "U35"
						( Origin gPackager )
					)
					( objectStatus "U7C1.U35" )
				)
				( pin "vccprim_avid(61)"
					( attribute "PN" "U31"
						( Origin gPackager )
					)
					( objectStatus "U7C1.U31" )
				)
				( pin "vccprim_avid(62)"
					( attribute "PN" "AK32"
						( Origin gPackager )
					)
					( objectStatus "U7C1.AK32" )
				)
				( pin "vccprim_avid_qat_sense"
					( attribute "PN" "V37"
						( Origin gPackager )
					)
					( objectStatus "U7C1.V37" )
				)
				( pin "vccprim_avid_sense"
					( attribute "PN" "AK36"
						( Origin gPackager )
					)
					( objectStatus "U7C1.AK36" )
				)
			)
			( gate "@baseboard_fab2_lib.baseboard_fab2(sch_1):page124_i15"
				( attribute "BOM_COST" "SB"
					( Origin gFrontEnd )
				)
				( attribute "CDS_LIB" "mstr_u_proc"
					( Origin gPackager )
				)
				( attribute "CDS_LOCATION" "U7C1"
					( Origin gPackager )
				)
				( attribute "CDS_SEC" "14"
					( Origin gPackager )
				)
				( attribute "LOCATION" "U7C1"
					( Origin gFrontEnd )
				)
				( attribute "MATERIAL" "IC"
					( Origin gFrontEnd )
				)
				( attribute "PACK_TYPE" "BGA1"
					( Origin gFrontEnd )
				)
				( attribute "PART_NUMBER" "H91415-002"
					( Origin gFrontEnd )
				)
				( attribute "PHYS_PAGE" "124"
					( Origin gFrontEnd )
				)
				( attribute "ROOM" "SB"
					( Origin gFrontEnd )
				)
				( attribute "ROT" "0"
					( Origin gFrontEnd )
				)
				( attribute "SEC" "14"
					( Origin gFrontEnd )
				)
				( attribute "SEC_TYPE" "BGA1"
					( Origin gFrontEnd )
				)
				( attribute "VER" "14"
					( Origin gFrontEnd )
				)
				( attribute "XY" "(1200,2700)"
					( Origin gFrontEnd )
				)
				( attribute "CHIPS_PART_NAME" "LBG_CORE_QAT_EXT_D"
					( Origin gPackager )
				)
				( attribute "CDS_PART_NAME" "LBG_CORE_QAT_EXT_D_BGA1-IC,H91A"
					( Origin gPackager )
				)
				( objectStatus "U7C1" )
				( pin "vss(0)"
					( attribute "PN" "CA52"
						( Origin gPackager )
					)
					( objectStatus "U7C1.CA52" )
				)
				( pin "vss(1)"
					( attribute "PN" "CA50"
						( Origin gPackager )
					)
					( objectStatus "U7C1.CA50" )
				)
				( pin "vss(2)"
					( attribute "PN" "CA26"
						( Origin gPackager )
					)
					( objectStatus "U7C1.CA26" )
				)
				( pin "vss(3)"
					( attribute "PN" "CA18"
						( Origin gPackager )
					)
					( objectStatus "U7C1.CA18" )
				)
				( pin "vss(4)"
					( attribute "PN" "CA15"
						( Origin gPackager )
					)
					( objectStatus "U7C1.CA15" )
				)
				( pin "vss(5)"
					( attribute "PN" "BY49"
						( Origin gPackager )
					)
					( objectStatus "U7C1.BY49" )
				)
				( pin "vss(6)"
					( attribute "PN" "BY40"
						( Origin gPackager )
					)
					( objectStatus "U7C1.BY40" )
				)
				( pin "vss(7)"
					( attribute "PN" "BW52"
						( Origin gPackager )
					)
					( objectStatus "U7C1.BW52" )
				)
				( pin "vss(8)"
					( attribute "PN" "BW26"
						( Origin gPackager )
					)
					( objectStatus "U7C1.BW26" )
				)
				( pin "vss(9)"
					( attribute "PN" "BW18"
						( Origin gPackager )
					)
					( objectStatus "U7C1.BW18" )
				)
				( pin "vss(10)"
					( attribute "PN" "BW15"
						( Origin gPackager )
					)
					( objectStatus "U7C1.BW15" )
				)
				( pin "vss(11)"
					( attribute "PN" "BV40"
						( Origin gPackager )
					)
					( objectStatus "U7C1.BV40" )
				)
				( pin "vss(12)"
					( attribute "PN" "BU9"
						( Origin gPackager )
					)
					( objectStatus "U7C1.BU9" )
				)
				( pin "vss(13)"
					( attribute "PN" "BU63"
						( Origin gPackager )
					)
					( objectStatus "U7C1.BU63" )
				)
				( pin "vss(14)"
					( attribute "PN" "BU61"
						( Origin gPackager )
					)
					( objectStatus "U7C1.BU61" )
				)
				( pin "vss(15)"
					( attribute "PN" "BU59"
						( Origin gPackager )
					)
					( objectStatus "U7C1.BU59" )
				)
				( pin "vss(16)"
					( attribute "PN" "BU57"
						( Origin gPackager )
					)
					( objectStatus "U7C1.BU57" )
				)
				( pin "vss(17)"
					( attribute "PN" "BU54"
						( Origin gPackager )
					)
					( objectStatus "U7C1.BU54" )
				)
				( pin "vss(18)"
					( attribute "PN" "BU52"
						( Origin gPackager )
					)
					( objectStatus "U7C1.BU52" )
				)
				( pin "vss(19)"
					( attribute "PN" "BU50"
						( Origin gPackager )
					)
					( objectStatus "U7C1.BU50" )
				)
				( pin "vss(20)"
					( attribute "PN" "BU48"
						( Origin gPackager )
					)
					( objectStatus "U7C1.BU48" )
				)
				( pin "vss(21)"
					( attribute "PN" "BU45"
						( Origin gPackager )
					)
					( objectStatus "U7C1.BU45" )
				)
				( pin "vss(22)"
					( attribute "PN" "BU43"
						( Origin gPackager )
					)
					( objectStatus "U7C1.BU43" )
				)
				( pin "vss(23)"
					( attribute "PN" "BU41"
						( Origin gPackager )
					)
					( objectStatus "U7C1.BU41" )
				)
				( pin "vss(24)"
					( attribute "PN" "BU39"
						( Origin gPackager )
					)
					( objectStatus "U7C1.BU39" )
				)
				( pin "vss(25)"
					( attribute "PN" "BU37"
						( Origin gPackager )
					)
					( objectStatus "U7C1.BU37" )
				)
				( pin "vss(26)"
					( attribute "PN" "BU34"
						( Origin gPackager )
					)
					( objectStatus "U7C1.BU34" )
				)
				( pin "vss(27)"
					( attribute "PN" "BU32"
						( Origin gPackager )
					)
					( objectStatus "U7C1.BU32" )
				)
				( pin "vss(28)"
					( attribute "PN" "BU30"
						( Origin gPackager )
					)
					( objectStatus "U7C1.BU30" )
				)
				( pin "vss(29)"
					( attribute "PN" "BU28"
						( Origin gPackager )
					)
					( objectStatus "U7C1.BU28" )
				)
				( pin "vss(30)"
					( attribute "PN" "BU26"
						( Origin gPackager )
					)
					( objectStatus "U7C1.BU26" )
				)
				( pin "vss(31)"
					( attribute "PN" "BU24"
						( Origin gPackager )
					)
					( objectStatus "U7C1.BU24" )
				)
				( pin "vss(32)"
					( attribute "PN" "BU22"
						( Origin gPackager )
					)
					( objectStatus "U7C1.BU22" )
				)
				( pin "vss(33)"
					( attribute "PN" "BU20"
						( Origin gPackager )
					)
					( objectStatus "U7C1.BU20" )
				)
				( pin "vss(34)"
					( attribute "PN" "BU18"
						( Origin gPackager )
					)
					( objectStatus "U7C1.BU18" )
				)
				( pin "vss(35)"
					( attribute "PN" "BU15"
						( Origin gPackager )
					)
					( objectStatus "U7C1.BU15" )
				)
				( pin "vss(36)"
					( attribute "PN" "BV49"
						( Origin gPackager )
					)
					( objectStatus "U7C1.BV49" )
				)
				( pin "vss(37)"
					( attribute "PN" "BU11"
						( Origin gPackager )
					)
					( objectStatus "U7C1.BU11" )
				)
				( pin "vss(38)"
					( attribute "PN" "BU13"
						( Origin gPackager )
					)
					( objectStatus "U7C1.BU13" )
				)
				( pin "vss(39)"
					( attribute "PN" "BT66"
						( Origin gPackager )
					)
					( objectStatus "U7C1.BT66" )
				)
				( pin "vss(40)"
					( attribute "PN" "BR6"
						( Origin gPackager )
					)
					( objectStatus "U7C1.BR6" )
				)
				( pin "vss(41)"
					( attribute "PN" "BR58"
						( Origin gPackager )
					)
					( objectStatus "U7C1.BR58" )
				)
				( pin "vss(42)"
					( attribute "PN" "BR54"
						( Origin gPackager )
					)
					( objectStatus "U7C1.BR54" )
				)
				( pin "vss(43)"
					( attribute "PN" "BT8"
						( Origin gPackager )
					)
					( objectStatus "U7C1.BT8" )
				)
				( pin "vss(44)"
					( attribute "PN" "BR50"
						( Origin gPackager )
					)
					( objectStatus "U7C1.BR50" )
				)
				( pin "vss(45)"
					( attribute "PN" "BR20"
						( Origin gPackager )
					)
					( objectStatus "U7C1.BR20" )
				)
				( pin "vss(46)"
					( attribute "PN" "BN66"
						( Origin gPackager )
					)
					( objectStatus "U7C1.BN66" )
				)
				( pin "vss(47)"
					( attribute "PN" "BN52"
						( Origin gPackager )
					)
					( objectStatus "U7C1.BN52" )
				)
				( pin "vss(48)"
					( attribute "PN" "BN5"
						( Origin gPackager )
					)
					( objectStatus "U7C1.BN5" )
				)
				( pin "vss(49)"
					( attribute "PN" "BN59"
						( Origin gPackager )
					)
					( objectStatus "U7C1.BN59" )
				)
				( pin "vss(50)"
					( attribute "PN" "BN22"
						( Origin gPackager )
					)
					( objectStatus "U7C1.BN22" )
				)
				( pin "vss(51)"
					( attribute "PN" "BM9"
						( Origin gPackager )
					)
					( objectStatus "U7C1.BM9" )
				)
				( pin "vss(52)"
					( attribute "PN" "BM71"
						( Origin gPackager )
					)
					( objectStatus "U7C1.BM71" )
				)
				( pin "vss(53)"
					( attribute "PN" "BM69"
						( Origin gPackager )
					)
					( objectStatus "U7C1.BM69" )
				)
				( pin "vss(54)"
					( attribute "PN" "BM58"
						( Origin gPackager )
					)
					( objectStatus "U7C1.BM58" )
				)
				( pin "vss(55)"
					( attribute "PN" "BM50"
						( Origin gPackager )
					)
					( objectStatus "U7C1.BM50" )
				)
				( pin "vss(56)"
					( attribute "PN" "BM46"
						( Origin gPackager )
					)
					( objectStatus "U7C1.BM46" )
				)
				( pin "vss(57)"
					( attribute "PN" "BN37"
						( Origin gPackager )
					)
					( objectStatus "U7C1.BN37" )
				)
				( pin "vss(58)"
					( attribute "PN" "BM17"
						( Origin gPackager )
					)
					( objectStatus "U7C1.BM17" )
				)
				( pin "vss(59)"
					( attribute "PN" "BM13"
						( Origin gPackager )
					)
					( objectStatus "U7C1.BM13" )
				)
				( pin "vss(60)"
					( attribute "PN" "BL72"
						( Origin gPackager )
					)
					( objectStatus "U7C1.BL72" )
				)
				( pin "vss(61)"
					( attribute "PN" "BL70"
						( Origin gPackager )
					)
					( objectStatus "U7C1.BL70" )
				)
				( pin "vss(62)"
					( attribute "PN" "BL63"
						( Origin gPackager )
					)
					( objectStatus "U7C1.BL63" )
				)
				( pin "vss(63)"
					( attribute "PN" "BL5"
						( Origin gPackager )
					)
					( objectStatus "U7C1.BL5" )
				)
				( pin "vss(64)"
					( attribute "PN" "BL37"
						( Origin gPackager )
					)
					( objectStatus "U7C1.BL37" )
				)
				( pin "vss(65)"
					( attribute "PN" "BL68"
						( Origin gPackager )
					)
					( objectStatus "U7C1.BL68" )
				)
				( pin "vss(66)"
					( attribute "PN" "BL40"
						( Origin gPackager )
					)
					( objectStatus "U7C1.BL40" )
				)
				( pin "vss(67)"
					( attribute "PN" "BL22"
						( Origin gPackager )
					)
					( objectStatus "U7C1.BL22" )
				)
				( pin "vss(68)"
					( attribute "PN" "BK50"
						( Origin gPackager )
					)
					( objectStatus "U7C1.BK50" )
				)
				( pin "vss(69)"
					( attribute "PN" "BK42"
						( Origin gPackager )
					)
					( objectStatus "U7C1.BK42" )
				)
				( pin "vss(70)"
					( attribute "PN" "BK38"
						( Origin gPackager )
					)
					( objectStatus "U7C1.BK38" )
				)
				( pin "vss(71)"
					( attribute "PN" "BK35"
						( Origin gPackager )
					)
					( objectStatus "U7C1.BK35" )
				)
				( pin "vss(72)"
					( attribute "PN" "BK31"
						( Origin gPackager )
					)
					( objectStatus "U7C1.BK31" )
				)
				( pin "vss(73)"
					( attribute "PN" "BK27"
						( Origin gPackager )
					)
					( objectStatus "U7C1.BK27" )
				)
				( pin "vss(74)"
					( attribute "PN" "BK24"
						( Origin gPackager )
					)
					( objectStatus "U7C1.BK24" )
				)
			)
			( gate "@baseboard_fab2_lib.baseboard_fab2(sch_1):page124_i16"
				( attribute "BOM_COST" "SB"
					( Origin gFrontEnd )
				)
				( attribute "CDS_LIB" "mstr_u_proc"
					( Origin gPackager )
				)
				( attribute "CDS_LOCATION" "U7C1"
					( Origin gPackager )
				)
				( attribute "CDS_SEC" "13"
					( Origin gPackager )
				)
				( attribute "LOCATION" "U7C1"
					( Origin gFrontEnd )
				)
				( attribute "MATERIAL" "IC"
					( Origin gFrontEnd )
				)
				( attribute "PACK_TYPE" "BGA1"
					( Origin gFrontEnd )
				)
				( attribute "PART_NUMBER" "H91415-002"
					( Origin gFrontEnd )
				)
				( attribute "PHYS_PAGE" "124"
					( Origin gFrontEnd )
				)
				( attribute "ROOM" "SB"
					( Origin gFrontEnd )
				)
				( attribute "ROT" "0"
					( Origin gFrontEnd )
				)
				( attribute "SEC" "13"
					( Origin gFrontEnd )
				)
				( attribute "SEC_TYPE" "BGA1"
					( Origin gFrontEnd )
				)
				( attribute "VER" "13"
					( Origin gFrontEnd )
				)
				( attribute "XY" "(-1475,2725)"
					( Origin gFrontEnd )
				)
				( attribute "CHIPS_PART_NAME" "LBG_CORE_QAT_EXT_D"
					( Origin gPackager )
				)
				( attribute "CDS_PART_NAME" "LBG_CORE_QAT_EXT_D_BGA1-IC,H91A"
					( Origin gPackager )
				)
				( objectStatus "U7C1" )
				( pin "vss(75)"
					( attribute "PN" "BJ68"
						( Origin gPackager )
					)
					( objectStatus "U7C1.BJ68" )
				)
				( pin "vss(76)"
					( attribute "PN" "BJ52"
						( Origin gPackager )
					)
					( objectStatus "U7C1.BJ52" )
				)
				( pin "vss(77)"
					( attribute "PN" "BJ33"
						( Origin gPackager )
					)
					( objectStatus "U7C1.BJ33" )
				)
				( pin "vss(78)"
					( attribute "PN" "BJ3"
						( Origin gPackager )
					)
					( objectStatus "U7C1.BJ3" )
				)
				( pin "vss(79)"
					( attribute "PN" "BJ26"
						( Origin gPackager )
					)
					( objectStatus "U7C1.BJ26" )
				)
				( pin "vss(80)"
					( attribute "PN" "BJ18"
						( Origin gPackager )
					)
					( objectStatus "U7C1.BJ18" )
				)
				( pin "vss(81)"
					( attribute "PN" "BJ15"
						( Origin gPackager )
					)
					( objectStatus "U7C1.BJ15" )
				)
				( pin "vss(82)"
					( attribute "PN" "BJ7"
						( Origin gPackager )
					)
					( objectStatus "U7C1.BJ7" )
				)
				( pin "vss(83)"
					( attribute "PN" "BJ5"
						( Origin gPackager )
					)
					( objectStatus "U7C1.BJ5" )
				)
				( pin "vss(84)"
					( attribute "PN" "BJ11"
						( Origin gPackager )
					)
					( objectStatus "U7C1.BJ11" )
				)
				( pin "vss(85)"
					( attribute "PN" "BJ1"
						( Origin gPackager )
					)
					( objectStatus "U7C1.BJ1" )
				)
				( pin "vss(86)"
					( attribute "PN" "BH54"
						( Origin gPackager )
					)
					( objectStatus "U7C1.BH54" )
				)
				( pin "vss(87)"
					( attribute "PN" "BH46"
						( Origin gPackager )
					)
					( objectStatus "U7C1.BH46" )
				)
				( pin "vss(88)"
					( attribute "PN" "BH42"
						( Origin gPackager )
					)
					( objectStatus "U7C1.BH42" )
				)
				( pin "vss(89)"
					( attribute "PN" "BH38"
						( Origin gPackager )
					)
					( objectStatus "U7C1.BH38" )
				)
				( pin "vss(90)"
					( attribute "PN" "BH27"
						( Origin gPackager )
					)
					( objectStatus "U7C1.BH27" )
				)
				( pin "vss(91)"
					( attribute "PN" "BG63"
						( Origin gPackager )
					)
					( objectStatus "U7C1.BG63" )
				)
				( pin "vss(92)"
					( attribute "PN" "BG59"
						( Origin gPackager )
					)
					( objectStatus "U7C1.BG59" )
				)
				( pin "vss(93)"
					( attribute "PN" "BG48"
						( Origin gPackager )
					)
					( objectStatus "U7C1.BG48" )
				)
				( pin "vss(94)"
					( attribute "PN" "BG33"
						( Origin gPackager )
					)
					( objectStatus "U7C1.BG33" )
				)
				( pin "vss(95)"
					( attribute "PN" "BF9"
						( Origin gPackager )
					)
					( objectStatus "U7C1.BF9" )
				)
				( pin "vss(96)"
					( attribute "PN" "BF68"
						( Origin gPackager )
					)
					( objectStatus "U7C1.BF68" )
				)
				( pin "vss(97)"
					( attribute "PN" "BF65"
						( Origin gPackager )
					)
					( objectStatus "U7C1.BF65" )
				)
				( pin "vss(98)"
					( attribute "PN" "BF61"
						( Origin gPackager )
					)
					( objectStatus "U7C1.BF61" )
				)
				( pin "vss(99)"
					( attribute "PN" "BF58"
						( Origin gPackager )
					)
					( objectStatus "U7C1.BF58" )
				)
				( pin "vss(100)"
					( attribute "PN" "BF50"
						( Origin gPackager )
					)
					( objectStatus "U7C1.BF50" )
				)
				( pin "vss(101)"
					( attribute "PN" "BF5"
						( Origin gPackager )
					)
					( objectStatus "U7C1.BF5" )
				)
				( pin "vss(102)"
					( attribute "PN" "BF42"
						( Origin gPackager )
					)
					( objectStatus "U7C1.BF42" )
				)
				( pin "vss(103)"
					( attribute "PN" "BF38"
						( Origin gPackager )
					)
					( objectStatus "U7C1.BF38" )
				)
				( pin "vss(104)"
					( attribute "PN" "BF27"
						( Origin gPackager )
					)
					( objectStatus "U7C1.BF27" )
				)
				( pin "vss(105)"
					( attribute "PN" "BF24"
						( Origin gPackager )
					)
					( objectStatus "U7C1.BF24" )
				)
				( pin "vss(106)"
					( attribute "PN" "BF20"
						( Origin gPackager )
					)
					( objectStatus "U7C1.BF20" )
				)
				( pin "vss(107)"
					( attribute "PN" "BG44"
						( Origin gPackager )
					)
					( objectStatus "U7C1.BG44" )
				)
				( pin "vss(108)"
					( attribute "PN" "BF54"
						( Origin gPackager )
					)
					( objectStatus "U7C1.BF54" )
				)
				( pin "vss(109)"
					( attribute "PN" "BF17"
						( Origin gPackager )
					)
					( objectStatus "U7C1.BF17" )
				)
				( pin "vss(110)"
					( attribute "PN" "BF13"
						( Origin gPackager )
					)
					( objectStatus "U7C1.BF13" )
				)
				( pin "vss(111)"
					( attribute "PN" "BE66"
						( Origin gPackager )
					)
					( objectStatus "U7C1.BE66" )
				)
				( pin "vss(112)"
					( attribute "PN" "BE63"
						( Origin gPackager )
					)
					( objectStatus "U7C1.BE63" )
				)
				( pin "vss(113)"
					( attribute "PN" "BE59"
						( Origin gPackager )
					)
					( objectStatus "U7C1.BE59" )
				)
				( pin "vss(114)"
					( attribute "PN" "BE56"
						( Origin gPackager )
					)
					( objectStatus "U7C1.BE56" )
				)
				( pin "vss(115)"
					( attribute "PN" "BE37"
						( Origin gPackager )
					)
					( objectStatus "U7C1.BE37" )
				)
				( pin "vss(116)"
					( attribute "PN" "BE33"
						( Origin gPackager )
					)
					( objectStatus "U7C1.BE33" )
				)
				( pin "vss(117)"
					( attribute "PN" "BE29"
						( Origin gPackager )
					)
					( objectStatus "U7C1.BE29" )
				)
				( pin "vss(118)"
					( attribute "PN" "BD68"
						( Origin gPackager )
					)
					( objectStatus "U7C1.BD68" )
				)
				( pin "vss(119)"
					( attribute "PN" "BD54"
						( Origin gPackager )
					)
					( objectStatus "U7C1.BD54" )
				)
				( pin "vss(120)"
					( attribute "PN" "BD50"
						( Origin gPackager )
					)
					( objectStatus "U7C1.BD50" )
				)
				( pin "vss(121)"
					( attribute "PN" "BD5"
						( Origin gPackager )
					)
					( objectStatus "U7C1.BD5" )
				)
				( pin "vss(122)"
					( attribute "PN" "BD35"
						( Origin gPackager )
					)
					( objectStatus "U7C1.BD35" )
				)
				( pin "vss(123)"
					( attribute "PN" "BD31"
						( Origin gPackager )
					)
					( objectStatus "U7C1.BD31" )
				)
				( pin "vss(124)"
					( attribute "PN" "BD27"
						( Origin gPackager )
					)
					( objectStatus "U7C1.BD27" )
				)
				( pin "vss(125)"
					( attribute "PN" "BD24"
						( Origin gPackager )
					)
					( objectStatus "U7C1.BD24" )
				)
				( pin "vss(126)"
					( attribute "PN" "BC71"
						( Origin gPackager )
					)
					( objectStatus "U7C1.BC71" )
				)
				( pin "vss(127)"
					( attribute "PN" "BC69"
						( Origin gPackager )
					)
					( objectStatus "U7C1.BC69" )
				)
				( pin "vss(128)"
					( attribute "PN" "BB72"
						( Origin gPackager )
					)
					( objectStatus "U7C1.BB72" )
				)
				( pin "vss(129)"
					( attribute "PN" "BB70"
						( Origin gPackager )
					)
					( objectStatus "U7C1.BB70" )
				)
				( pin "vss(130)"
					( attribute "PN" "BB68"
						( Origin gPackager )
					)
					( objectStatus "U7C1.BB68" )
				)
				( pin "vss(131)"
					( attribute "PN" "BB66"
						( Origin gPackager )
					)
					( objectStatus "U7C1.BB66" )
				)
				( pin "vss(132)"
					( attribute "PN" "BB59"
						( Origin gPackager )
					)
					( objectStatus "U7C1.BB59" )
				)
				( pin "vss(133)"
					( attribute "PN" "BB44"
						( Origin gPackager )
					)
					( objectStatus "U7C1.BB44" )
				)
				( pin "vss(134)"
					( attribute "PN" "BB22"
						( Origin gPackager )
					)
					( objectStatus "U7C1.BB22" )
				)
				( pin "vss(135)"
					( attribute "PN" "BB18"
						( Origin gPackager )
					)
					( objectStatus "U7C1.BB18" )
				)
				( pin "vss(136)"
					( attribute "PN" "BB15"
						( Origin gPackager )
					)
					( objectStatus "U7C1.BB15" )
				)
				( pin "vss(137)"
					( attribute "PN" "BB11"
						( Origin gPackager )
					)
					( objectStatus "U7C1.BB11" )
				)
				( pin "vss(138)"
					( attribute "PN" "BB7"
						( Origin gPackager )
					)
					( objectStatus "U7C1.BB7" )
				)
				( pin "vss(139)"
					( attribute "PN" "BB5"
						( Origin gPackager )
					)
					( objectStatus "U7C1.BB5" )
				)
				( pin "vss(140)"
					( attribute "PN" "BA58"
						( Origin gPackager )
					)
					( objectStatus "U7C1.BA58" )
				)
				( pin "vss(141)"
					( attribute "PN" "BA54"
						( Origin gPackager )
					)
					( objectStatus "U7C1.BA54" )
				)
				( pin "vss(142)"
					( attribute "PN" "BA50"
						( Origin gPackager )
					)
					( objectStatus "U7C1.BA50" )
				)
				( pin "vss(143)"
					( attribute "PN" "AY68"
						( Origin gPackager )
					)
					( objectStatus "U7C1.AY68" )
				)
				( pin "vss(144)"
					( attribute "PN" "AY63"
						( Origin gPackager )
					)
					( objectStatus "U7C1.AY63" )
				)
				( pin "vss(145)"
					( attribute "PN" "AY56"
						( Origin gPackager )
					)
					( objectStatus "U7C1.AY56" )
				)
				( pin "vss(146)"
					( attribute "PN" "AY22"
						( Origin gPackager )
					)
					( objectStatus "U7C1.AY22" )
				)
				( pin "vss(147)"
					( attribute "PN" "AY5"
						( Origin gPackager )
					)
					( objectStatus "U7C1.AY5" )
				)
				( pin "vss(148)"
					( attribute "PN" "AW61"
						( Origin gPackager )
					)
					( objectStatus "U7C1.AW61" )
				)
				( pin "vss(149)"
					( attribute "PN" "AW58"
						( Origin gPackager )
					)
					( objectStatus "U7C1.AW58" )
				)
				( pin "vss(150)"
					( attribute "PN" "AW50"
						( Origin gPackager )
					)
					( objectStatus "U7C1.AW50" )
				)
				( pin "vss(151)"
					( attribute "PN" "AW46"
						( Origin gPackager )
					)
					( objectStatus "U7C1.AW46" )
				)
				( pin "vss(152)"
					( attribute "PN" "AW41"
						( Origin gPackager )
					)
					( objectStatus "U7C1.AW41" )
				)
				( pin "vss(153)"
					( attribute "PN" "AW39"
						( Origin gPackager )
					)
					( objectStatus "U7C1.AW39" )
				)
				( pin "vss(154)"
					( attribute "PN" "AW37"
						( Origin gPackager )
					)
					( objectStatus "U7C1.AW37" )
				)
				( pin "vss(155)"
					( attribute "PN" "AW36"
						( Origin gPackager )
					)
					( objectStatus "U7C1.AW36" )
				)
				( pin "vss(156)"
					( attribute "PN" "AW34"
						( Origin gPackager )
					)
					( objectStatus "U7C1.AW34" )
				)
				( pin "vss(157)"
					( attribute "PN" "AW32"
						( Origin gPackager )
					)
					( objectStatus "U7C1.AW32" )
				)
				( pin "vss(158)"
					( attribute "PN" "AW30"
						( Origin gPackager )
					)
					( objectStatus "U7C1.AW30" )
				)
				( pin "vss(159)"
					( attribute "PN" "AW26"
						( Origin gPackager )
					)
					( objectStatus "U7C1.AW26" )
				)
				( pin "vss(160)"
					( attribute "PN" "AW17"
						( Origin gPackager )
					)
					( objectStatus "U7C1.AW17" )
				)
				( pin "vss(161)"
					( attribute "PN" "AW13"
						( Origin gPackager )
					)
					( objectStatus "U7C1.AW13" )
				)
				( pin "vss(162)"
					( attribute "PN" "AW9"
						( Origin gPackager )
					)
					( objectStatus "U7C1.AW9" )
				)
				( pin "vss(163)"
					( attribute "PN" "AV68"
						( Origin gPackager )
					)
					( objectStatus "U7C1.AV68" )
				)
				( pin "vss(164)"
					( attribute "PN" "AV59"
						( Origin gPackager )
					)
					( objectStatus "U7C1.AV59" )
				)
				( pin "vss(165)"
					( attribute "PN" "AV22"
						( Origin gPackager )
					)
					( objectStatus "U7C1.AV22" )
				)
				( pin "vss(166)"
					( attribute "PN" "AV5"
						( Origin gPackager )
					)
					( objectStatus "U7C1.AV5" )
				)
				( pin "vss(167)"
					( attribute "PN" "AU61"
						( Origin gPackager )
					)
					( objectStatus "U7C1.AU61" )
				)
				( pin "vss(168)"
					( attribute "PN" "AU54"
						( Origin gPackager )
					)
					( objectStatus "U7C1.AU54" )
				)
				( pin "vss(169)"
					( attribute "PN" "AU50"
						( Origin gPackager )
					)
					( objectStatus "U7C1.AU50" )
				)
				( pin "vss(170)"
					( attribute "PN" "AU46"
						( Origin gPackager )
					)
					( objectStatus "U7C1.AU46" )
				)
				( pin "vss(171)"
					( attribute "PN" "AU41"
						( Origin gPackager )
					)
					( objectStatus "U7C1.AU41" )
				)
				( pin "vss(172)"
					( attribute "PN" "AE22"
						( Origin gPackager )
					)
					( objectStatus "U7C1.AE22" )
				)
				( pin "vss(173)"
					( attribute "PN" "AU30"
						( Origin gPackager )
					)
					( objectStatus "U7C1.AU30" )
				)
				( pin "vss(174)"
					( attribute "PN" "AU26"
						( Origin gPackager )
					)
					( objectStatus "U7C1.AU26" )
				)
				( pin "vss(175)"
					( attribute "PN" "AT59"
						( Origin gPackager )
					)
					( objectStatus "U7C1.AT59" )
				)
				( pin "vss(176)"
					( attribute "PN" "AT46"
						( Origin gPackager )
					)
					( objectStatus "U7C1.AT46" )
				)
				( pin "vss(177)"
					( attribute "PN" "AT41"
						( Origin gPackager )
					)
					( objectStatus "U7C1.AT41" )
				)
				( pin "vss(178)"
					( attribute "PN" "AT30"
						( Origin gPackager )
					)
					( objectStatus "U7C1.AT30" )
				)
				( pin "vss(179)"
					( attribute "PN" "AT26"
						( Origin gPackager )
					)
					( objectStatus "U7C1.AT26" )
				)
				( pin "vss(180)"
					( attribute "PN" "AT22"
						( Origin gPackager )
					)
					( objectStatus "U7C1.AT22" )
				)
				( pin "vss(181)"
					( attribute "PN" "AT18"
						( Origin gPackager )
					)
					( objectStatus "U7C1.AT18" )
				)
				( pin "vss(182)"
					( attribute "PN" "AT15"
						( Origin gPackager )
					)
					( objectStatus "U7C1.AT15" )
				)
				( pin "vss(183)"
					( attribute "PN" "AT11"
						( Origin gPackager )
					)
					( objectStatus "U7C1.AT11" )
				)
				( pin "vss(184)"
					( attribute "PN" "AT7"
						( Origin gPackager )
					)
					( objectStatus "U7C1.AT7" )
				)
				( pin "vss(185)"
					( attribute "PN" "AR72"
						( Origin gPackager )
					)
					( objectStatus "U7C1.AR72" )
				)
				( pin "vss(186)"
					( attribute "PN" "AR70"
						( Origin gPackager )
					)
					( objectStatus "U7C1.AR70" )
				)
				( pin "vss(187)"
					( attribute "PN" "AR68"
						( Origin gPackager )
					)
					( objectStatus "U7C1.AR68" )
				)
				( pin "vss(188)"
					( attribute "PN" "AR65"
						( Origin gPackager )
					)
					( objectStatus "U7C1.AR65" )
				)
				( pin "vss(189)"
					( attribute "PN" "AR58"
						( Origin gPackager )
					)
					( objectStatus "U7C1.AR58" )
				)
				( pin "vss(190)"
					( attribute "PN" "AR50"
						( Origin gPackager )
					)
					( objectStatus "U7C1.AR50" )
				)
				( pin "vss(191)"
					( attribute "PN" "AR5"
						( Origin gPackager )
					)
					( objectStatus "U7C1.AR5" )
				)
				( pin "vss(192)"
					( attribute "PN" "AP66"
						( Origin gPackager )
					)
					( objectStatus "U7C1.AP66" )
				)
				( pin "vss(193)"
					( attribute "PN" "AP52"
						( Origin gPackager )
					)
					( objectStatus "U7C1.AP52" )
				)
				( pin "vss(194)"
					( attribute "PN" "AP46"
						( Origin gPackager )
					)
					( objectStatus "U7C1.AP46" )
				)
				( pin "vss(195)"
					( attribute "PN" "AP41"
						( Origin gPackager )
					)
					( objectStatus "U7C1.AP41" )
				)
				( pin "vss(196)"
					( attribute "PN" "AP4"
						( Origin gPackager )
					)
					( objectStatus "U7C1.AP4" )
				)
				( pin "vss(197)"
					( attribute "PN" "AP30"
						( Origin gPackager )
					)
					( objectStatus "U7C1.AP30" )
				)
				( pin "vss(198)"
					( attribute "PN" "AP26"
						( Origin gPackager )
					)
					( objectStatus "U7C1.AP26" )
				)
				( pin "vss(199)"
					( attribute "PN" "AP2"
						( Origin gPackager )
					)
					( objectStatus "U7C1.AP2" )
				)
				( pin "vss(200)"
					( attribute "PN" "AN9"
						( Origin gPackager )
					)
					( objectStatus "U7C1.AN9" )
				)
				( pin "vss(201)"
					( attribute "PN" "AN58"
						( Origin gPackager )
					)
					( objectStatus "U7C1.AN58" )
				)
				( pin "vss(202)"
					( attribute "PN" "AN5"
						( Origin gPackager )
					)
					( objectStatus "U7C1.AN5" )
				)
				( pin "vss(203)"
					( attribute "PN" "AN20"
						( Origin gPackager )
					)
					( objectStatus "U7C1.AN20" )
				)
				( pin "vss(204)"
					( attribute "PN" "AP22"
						( Origin gPackager )
					)
					( objectStatus "U7C1.AP22" )
				)
				( pin "vss(205)"
					( attribute "PN" "AN68"
						( Origin gPackager )
					)
					( objectStatus "U7C1.AN68" )
				)
				( pin "vss(206)"
					( attribute "PN" "AN17"
						( Origin gPackager )
					)
					( objectStatus "U7C1.AN17" )
				)
				( pin "vss(207)"
					( attribute "PN" "AN13"
						( Origin gPackager )
					)
					( objectStatus "U7C1.AN13" )
				)
				( pin "vss(208)"
					( attribute "PN" "AM46"
						( Origin gPackager )
					)
					( objectStatus "U7C1.AM46" )
				)
				( pin "vss(209)"
					( attribute "PN" "AM41"
						( Origin gPackager )
					)
					( objectStatus "U7C1.AM41" )
				)
				( pin "vss(210)"
					( attribute "PN" "AM30"
						( Origin gPackager )
					)
					( objectStatus "U7C1.AM30" )
				)
				( pin "vss(211)"
					( attribute "PN" "AM26"
						( Origin gPackager )
					)
					( objectStatus "U7C1.AM26" )
				)
				( pin "vss(212)"
					( attribute "PN" "AL72"
						( Origin gPackager )
					)
					( objectStatus "U7C1.AL72" )
				)
				( pin "vss(213)"
					( attribute "PN" "AL70"
						( Origin gPackager )
					)
					( objectStatus "U7C1.AL70" )
				)
				( pin "vss(214)"
					( attribute "PN" "AL68"
						( Origin gPackager )
					)
					( objectStatus "U7C1.AL68" )
				)
			)
			( gate "@baseboard_fab2_lib.baseboard_fab2(sch_1):page124_i17"
				( attribute "BOM_COST" "SB"
					( Origin gFrontEnd )
				)
				( attribute "CDS_LIB" "mstr_u_proc"
					( Origin gPackager )
				)
				( attribute "CDS_LOCATION" "U7C1"
					( Origin gPackager )
				)
				( attribute "CDS_SEC" "12"
					( Origin gPackager )
				)
				( attribute "LOCATION" "U7C1"
					( Origin gFrontEnd )
				)
				( attribute "MATERIAL" "IC"
					( Origin gFrontEnd )
				)
				( attribute "PACK_TYPE" "BGA1"
					( Origin gFrontEnd )
				)
				( attribute "PART_NUMBER" "H91415-002"
					( Origin gFrontEnd )
				)
				( attribute "PHYS_PAGE" "124"
					( Origin gFrontEnd )
				)
				( attribute "ROOM" "SB"
					( Origin gFrontEnd )
				)
				( attribute "ROT" "0"
					( Origin gFrontEnd )
				)
				( attribute "SEC" "12"
					( Origin gFrontEnd )
				)
				( attribute "SEC_TYPE" "BGA1"
					( Origin gFrontEnd )
				)
				( attribute "VER" "12"
					( Origin gFrontEnd )
				)
				( attribute "XY" "(-4000,2700)"
					( Origin gFrontEnd )
				)
				( attribute "CHIPS_PART_NAME" "LBG_CORE_QAT_EXT_D"
					( Origin gPackager )
				)
				( attribute "CDS_PART_NAME" "LBG_CORE_QAT_EXT_D_BGA1-IC,H91A"
					( Origin gPackager )
				)
				( objectStatus "U7C1" )
				( pin "vss(215)"
					( attribute "PN" "AL59"
						( Origin gPackager )
					)
					( objectStatus "U7C1.AL59" )
				)
				( pin "vss(216)"
					( attribute "PN" "AL52"
						( Origin gPackager )
					)
					( objectStatus "U7C1.AL52" )
				)
				( pin "vss(217)"
					( attribute "PN" "AL5"
						( Origin gPackager )
					)
					( objectStatus "U7C1.AL5" )
				)
				( pin "vss(218)"
					( attribute "PN" "AL22"
						( Origin gPackager )
					)
					( objectStatus "U7C1.AL22" )
				)
				( pin "vss(219)"
					( attribute "PN" "AK71"
						( Origin gPackager )
					)
					( objectStatus "U7C1.AK71" )
				)
				( pin "vss(220)"
					( attribute "PN" "AK69"
						( Origin gPackager )
					)
					( objectStatus "U7C1.AK69" )
				)
				( pin "vss(221)"
					( attribute "PN" "AK61"
						( Origin gPackager )
					)
					( objectStatus "U7C1.AK61" )
				)
				( pin "vss(222)"
					( attribute "PN" "AK58"
						( Origin gPackager )
					)
					( objectStatus "U7C1.AK58" )
				)
				( pin "vss(223)"
					( attribute "PN" "AK48"
						( Origin gPackager )
					)
					( objectStatus "U7C1.AK48" )
				)
				( pin "vss(224)"
					( attribute "PN" "AK46"
						( Origin gPackager )
					)
					( objectStatus "U7C1.AK46" )
				)
				( pin "vss(225)"
					( attribute "PN" "AK41"
						( Origin gPackager )
					)
					( objectStatus "U7C1.AK41" )
				)
				( pin "vss(226)"
					( attribute "PN" "AK26"
						( Origin gPackager )
					)
					( objectStatus "U7C1.AK26" )
				)
				( pin "vss(227)"
					( attribute "PN" "AJ7"
						( Origin gPackager )
					)
					( objectStatus "U7C1.AJ7" )
				)
				( pin "vss(228)"
					( attribute "PN" "AJ68"
						( Origin gPackager )
					)
					( objectStatus "U7C1.AJ68" )
				)
				( pin "vss(229)"
					( attribute "PN" "AJ66"
						( Origin gPackager )
					)
					( objectStatus "U7C1.AJ66" )
				)
				( pin "vss(230)"
					( attribute "PN" "AJ59"
						( Origin gPackager )
					)
					( objectStatus "U7C1.AJ59" )
				)
				( pin "vss(231)"
					( attribute "PN" "AJ52"
						( Origin gPackager )
					)
					( objectStatus "U7C1.AJ52" )
				)
				( pin "vss(232)"
					( attribute "PN" "AJ5"
						( Origin gPackager )
					)
					( objectStatus "U7C1.AJ5" )
				)
				( pin "vss(233)"
					( attribute "PN" "AJ41"
						( Origin gPackager )
					)
					( objectStatus "U7C1.AJ41" )
				)
				( pin "vss(234)"
					( attribute "PN" "AJ39"
						( Origin gPackager )
					)
					( objectStatus "U7C1.AJ39" )
				)
				( pin "vss(235)"
					( attribute "PN" "AJ37"
						( Origin gPackager )
					)
					( objectStatus "U7C1.AJ37" )
				)
				( pin "vss(236)"
					( attribute "PN" "AJ36"
						( Origin gPackager )
					)
					( objectStatus "U7C1.AJ36" )
				)
				( pin "vss(237)"
					( attribute "PN" "AJ34"
						( Origin gPackager )
					)
					( objectStatus "U7C1.AJ34" )
				)
				( pin "vss(238)"
					( attribute "PN" "AJ30"
						( Origin gPackager )
					)
					( objectStatus "U7C1.AJ30" )
				)
				( pin "vss(239)"
					( attribute "PN" "AJ26"
						( Origin gPackager )
					)
					( objectStatus "U7C1.AJ26" )
				)
				( pin "vss(240)"
					( attribute "PN" "AJ22"
						( Origin gPackager )
					)
					( objectStatus "U7C1.AJ22" )
				)
				( pin "vss(241)"
					( attribute "PN" "AJ18"
						( Origin gPackager )
					)
					( objectStatus "U7C1.AJ18" )
				)
				( pin "vss(242)"
					( attribute "PN" "AJ15"
						( Origin gPackager )
					)
					( objectStatus "U7C1.AJ15" )
				)
				( pin "vss(243)"
					( attribute "PN" "AK30"
						( Origin gPackager )
					)
					( objectStatus "U7C1.AK30" )
				)
				( pin "vss(244)"
					( attribute "PN" "AJ56"
						( Origin gPackager )
					)
					( objectStatus "U7C1.AJ56" )
				)
				( pin "vss(245)"
					( attribute "PN" "AJ32"
						( Origin gPackager )
					)
					( objectStatus "U7C1.AJ32" )
				)
				( pin "vss(246)"
					( attribute "PN" "AJ11"
						( Origin gPackager )
					)
					( objectStatus "U7C1.AJ11" )
				)
				( pin "vss(247)"
					( attribute "PN" "AH20"
						( Origin gPackager )
					)
					( objectStatus "U7C1.AH20" )
				)
				( pin "vss(248)"
					( attribute "PN" "AG66"
						( Origin gPackager )
					)
					( objectStatus "U7C1.AG66" )
				)
				( pin "vss(249)"
					( attribute "PN" "AG59"
						( Origin gPackager )
					)
					( objectStatus "U7C1.AG59" )
				)
				( pin "vss(250)"
					( attribute "PN" "AG56"
						( Origin gPackager )
					)
					( objectStatus "U7C1.AG56" )
				)
				( pin "vss(251)"
					( attribute "PN" "AG52"
						( Origin gPackager )
					)
					( objectStatus "U7C1.AG52" )
				)
				( pin "vss(252)"
					( attribute "PN" "AG43"
						( Origin gPackager )
					)
					( objectStatus "U7C1.AG43" )
				)
				( pin "vss(253)"
					( attribute "PN" "AG41"
						( Origin gPackager )
					)
					( objectStatus "U7C1.AG41" )
				)
				( pin "vss(254)"
					( attribute "PN" "AG30"
						( Origin gPackager )
					)
					( objectStatus "U7C1.AG30" )
				)
				( pin "vss(255)"
					( attribute "PN" "AG26"
						( Origin gPackager )
					)
					( objectStatus "U7C1.AG26" )
				)
				( pin "vss(256)"
					( attribute "PN" "AF68"
						( Origin gPackager )
					)
					( objectStatus "U7C1.AF68" )
				)
				( pin "vss(257)"
					( attribute "PN" "AF3"
						( Origin gPackager )
					)
					( objectStatus "U7C1.AF3" )
				)
				( pin "vss(258)"
					( attribute "PN" "AF24"
						( Origin gPackager )
					)
					( objectStatus "U7C1.AF24" )
				)
				( pin "vss(259)"
					( attribute "PN" "AF17"
						( Origin gPackager )
					)
					( objectStatus "U7C1.AF17" )
				)
				( pin "vss(260)"
					( attribute "PN" "AF9"
						( Origin gPackager )
					)
					( objectStatus "U7C1.AF9" )
				)
				( pin "vss(261)"
					( attribute "PN" "AF5"
						( Origin gPackager )
					)
					( objectStatus "U7C1.AF5" )
				)
				( pin "vss(262)"
					( attribute "PN" "AF13"
						( Origin gPackager )
					)
					( objectStatus "U7C1.AF13" )
				)
				( pin "vss(263)"
					( attribute "PN" "AF1"
						( Origin gPackager )
					)
					( objectStatus "U7C1.AF1" )
				)
				( pin "vss(264)"
					( attribute "PN" "AE66"
						( Origin gPackager )
					)
					( objectStatus "U7C1.AE66" )
				)
				( pin "vss(265)"
					( attribute "PN" "AE63"
						( Origin gPackager )
					)
					( objectStatus "U7C1.AE63" )
				)
				( pin "vss(266)"
					( attribute "PN" "AE59"
						( Origin gPackager )
					)
					( objectStatus "U7C1.AE59" )
				)
				( pin "vss(267)"
					( attribute "PN" "AE56"
						( Origin gPackager )
					)
					( objectStatus "U7C1.AE56" )
				)
				( pin "vss(268)"
					( attribute "PN" "AE52"
						( Origin gPackager )
					)
					( objectStatus "U7C1.AE52" )
				)
				( pin "vss(269)"
					( attribute "PN" "AE48"
						( Origin gPackager )
					)
					( objectStatus "U7C1.AE48" )
				)
				( pin "vss(270)"
					( attribute "PN" "J18"
						( Origin gPackager )
					)
					( objectStatus "U7C1.J18" )
				)
				( pin "vss(271)"
					( attribute "PN" "AE29"
						( Origin gPackager )
					)
					( objectStatus "U7C1.AE29" )
				)
				( pin "vss(272)"
					( attribute "PN" "AD68"
						( Origin gPackager )
					)
					( objectStatus "U7C1.AD68" )
				)
				( pin "vss(273)"
					( attribute "PN" "AD65"
						( Origin gPackager )
					)
					( objectStatus "U7C1.AD65" )
				)
				( pin "vss(274)"
					( attribute "PN" "AD5"
						( Origin gPackager )
					)
					( objectStatus "U7C1.AD5" )
				)
				( pin "vss(275)"
					( attribute "PN" "AC7"
						( Origin gPackager )
					)
					( objectStatus "U7C1.AC7" )
				)
				( pin "vss(276)"
					( attribute "PN" "AC66"
						( Origin gPackager )
					)
					( objectStatus "U7C1.AC66" )
				)
				( pin "vss(277)"
					( attribute "PN" "AC63"
						( Origin gPackager )
					)
					( objectStatus "U7C1.AC63" )
				)
				( pin "vss(278)"
					( attribute "PN" "AC59"
						( Origin gPackager )
					)
					( objectStatus "U7C1.AC59" )
				)
				( pin "vss(279)"
					( attribute "PN" "AC52"
						( Origin gPackager )
					)
					( objectStatus "U7C1.AC52" )
				)
				( pin "vss(280)"
					( attribute "PN" "AC48"
						( Origin gPackager )
					)
					( objectStatus "U7C1.AC48" )
				)
				( pin "vss(281)"
					( attribute "PN" "AC46"
						( Origin gPackager )
					)
					( objectStatus "U7C1.AC46" )
				)
				( pin "vss(282)"
					( attribute "PN" "AC43"
						( Origin gPackager )
					)
					( objectStatus "U7C1.AC43" )
				)
				( pin "vss(283)"
					( attribute "PN" "AC27"
						( Origin gPackager )
					)
					( objectStatus "U7C1.AC27" )
				)
				( pin "vss(284)"
					( attribute "PN" "AD58"
						( Origin gPackager )
					)
					( objectStatus "U7C1.AD58" )
				)
				( pin "vss(285)"
					( attribute "PN" "AC45"
						( Origin gPackager )
					)
					( objectStatus "U7C1.AC45" )
				)
				( pin "vss(286)"
					( attribute "PN" "AC22"
						( Origin gPackager )
					)
					( objectStatus "U7C1.AC22" )
				)
				( pin "vss(287)"
					( attribute "PN" "AC18"
						( Origin gPackager )
					)
					( objectStatus "U7C1.AC18" )
				)
				( pin "vss(288)"
					( attribute "PN" "AC15"
						( Origin gPackager )
					)
					( objectStatus "U7C1.AC15" )
				)
				( pin "vss(289)"
					( attribute "PN" "AC11"
						( Origin gPackager )
					)
					( objectStatus "U7C1.AC11" )
				)
				( pin "vss(290)"
					( attribute "PN" "AB72"
						( Origin gPackager )
					)
					( objectStatus "U7C1.AB72" )
				)
				( pin "vss(291)"
					( attribute "PN" "AB70"
						( Origin gPackager )
					)
					( objectStatus "U7C1.AB70" )
				)
				( pin "vss(292)"
					( attribute "PN" "AB68"
						( Origin gPackager )
					)
					( objectStatus "U7C1.AB68" )
				)
				( pin "vss(293)"
					( attribute "PN" "AB5"
						( Origin gPackager )
					)
					( objectStatus "U7C1.AB5" )
				)
				( pin "vss(294)"
					( attribute "PN" "AA48"
						( Origin gPackager )
					)
					( objectStatus "U7C1.AA48" )
				)
				( pin "vss(295)"
					( attribute "PN" "AA43"
						( Origin gPackager )
					)
					( objectStatus "U7C1.AA43" )
				)
				( pin "vss(296)"
					( attribute "PN" "AA27"
						( Origin gPackager )
					)
					( objectStatus "U7C1.AA27" )
				)
				( pin "vss(297)"
					( attribute "PN" "AA26"
						( Origin gPackager )
					)
					( objectStatus "U7C1.AA26" )
				)
				( pin "vss(298)"
					( attribute "PN" "Y68"
						( Origin gPackager )
					)
					( objectStatus "U7C1.Y68" )
				)
				( pin "vss(299)"
					( attribute "PN" "Y63"
						( Origin gPackager )
					)
					( objectStatus "U7C1.Y63" )
				)
				( pin "vss(300)"
					( attribute "PN" "Y59"
						( Origin gPackager )
					)
					( objectStatus "U7C1.Y59" )
				)
				( pin "vss(301)"
					( attribute "PN" "Y52"
						( Origin gPackager )
					)
					( objectStatus "U7C1.Y52" )
				)
				( pin "vss(302)"
					( attribute "PN" "Y5"
						( Origin gPackager )
					)
					( objectStatus "U7C1.Y5" )
				)
				( pin "vss(303)"
					( attribute "PN" "Y48"
						( Origin gPackager )
					)
					( objectStatus "U7C1.Y48" )
				)
				( pin "vss(304)"
					( attribute "PN" "Y27"
						( Origin gPackager )
					)
					( objectStatus "U7C1.Y27" )
				)
				( pin "vss(305)"
					( attribute "PN" "Y22"
						( Origin gPackager )
					)
					( objectStatus "U7C1.Y22" )
				)
				( pin "vss(306)"
					( attribute "PN" "W9"
						( Origin gPackager )
					)
					( objectStatus "U7C1.W9" )
				)
				( pin "vss(307)"
					( attribute "PN" "W61"
						( Origin gPackager )
					)
					( objectStatus "U7C1.W61" )
				)
				( pin "vss(308)"
					( attribute "PN" "Y43"
						( Origin gPackager )
					)
					( objectStatus "U7C1.Y43" )
				)
				( pin "vss(309)"
					( attribute "PN" "AA50"
						( Origin gPackager )
					)
					( objectStatus "U7C1.AA50" )
				)
				( pin "vss(310)"
					( attribute "PN" "W24"
						( Origin gPackager )
					)
					( objectStatus "U7C1.W24" )
				)
				( pin "vss(311)"
					( attribute "PN" "W20"
						( Origin gPackager )
					)
					( objectStatus "U7C1.W20" )
				)
				( pin "vss(312)"
					( attribute "PN" "W17"
						( Origin gPackager )
					)
					( objectStatus "U7C1.W17" )
				)
				( pin "vss(313)"
					( attribute "PN" "W13"
						( Origin gPackager )
					)
					( objectStatus "U7C1.W13" )
				)
				( pin "vss(314)"
					( attribute "PN" "V68"
						( Origin gPackager )
					)
					( objectStatus "U7C1.V68" )
				)
				( pin "vss(315)"
					( attribute "PN" "V66"
						( Origin gPackager )
					)
					( objectStatus "U7C1.V66" )
				)
				( pin "vss(316)"
					( attribute "PN" "W58"
						( Origin gPackager )
					)
					( objectStatus "U7C1.W58" )
				)
				( pin "vss(317)"
					( attribute "PN" "V52"
						( Origin gPackager )
					)
					( objectStatus "U7C1.V52" )
				)
				( pin "vss(318)"
					( attribute "PN" "V5"
						( Origin gPackager )
					)
					( objectStatus "U7C1.V5" )
				)
				( pin "vss(319)"
					( attribute "PN" "V48"
						( Origin gPackager )
					)
					( objectStatus "U7C1.V48" )
				)
				( pin "vss(320)"
					( attribute "PN" "V26"
						( Origin gPackager )
					)
					( objectStatus "U7C1.V26" )
				)
				( pin "vss(321)"
					( attribute "PN" "U58"
						( Origin gPackager )
					)
					( objectStatus "U7C1.U58" )
				)
				( pin "vss(322)"
					( attribute "PN" "AG46"
						( Origin gPackager )
					)
					( objectStatus "U7C1.AG46" )
				)
				( pin "vss(323)"
					( attribute "PN" "AF50"
						( Origin gPackager )
					)
					( objectStatus "U7C1.AF50" )
				)
				( pin "vss(324)"
					( attribute "PN" "T7"
						( Origin gPackager )
					)
					( objectStatus "U7C1.T7" )
				)
				( pin "vss(325)"
					( attribute "PN" "T66"
						( Origin gPackager )
					)
					( objectStatus "U7C1.T66" )
				)
				( pin "vss(326)"
					( attribute "PN" "T52"
						( Origin gPackager )
					)
					( objectStatus "U7C1.T52" )
				)
				( pin "vss(327)"
					( attribute "PN" "T48"
						( Origin gPackager )
					)
					( objectStatus "U7C1.T48" )
				)
				( pin "vss(328)"
					( attribute "PN" "AJ45"
						( Origin gPackager )
					)
					( objectStatus "U7C1.AJ45" )
				)
				( pin "vss(329)"
					( attribute "PN" "T40"
						( Origin gPackager )
					)
					( objectStatus "U7C1.T40" )
				)
				( pin "vss(330)"
					( attribute "PN" "T37"
						( Origin gPackager )
					)
					( objectStatus "U7C1.T37" )
				)
				( pin "vss(331)"
					( attribute "PN" "T33"
						( Origin gPackager )
					)
					( objectStatus "U7C1.T33" )
				)
				( pin "vss(332)"
					( attribute "PN" "T29"
						( Origin gPackager )
					)
					( objectStatus "U7C1.T29" )
				)
				( pin "vss(333)"
					( attribute "PN" "T26"
						( Origin gPackager )
					)
					( objectStatus "U7C1.T26" )
				)
				( pin "vss(334)"
					( attribute "PN" "T22"
						( Origin gPackager )
					)
					( objectStatus "U7C1.T22" )
				)
				( pin "vss(335)"
					( attribute "PN" "T18"
						( Origin gPackager )
					)
					( objectStatus "U7C1.T18" )
				)
				( pin "vss(336)"
					( attribute "PN" "T15"
						( Origin gPackager )
					)
					( objectStatus "U7C1.T15" )
				)
				( pin "vss(337)"
					( attribute "PN" "T11"
						( Origin gPackager )
					)
					( objectStatus "U7C1.T11" )
				)
				( pin "vss(338)"
					( attribute "PN" "R68"
						( Origin gPackager )
					)
					( objectStatus "U7C1.R68" )
				)
				( pin "vss(339)"
					( attribute "PN" "R58"
						( Origin gPackager )
					)
					( objectStatus "U7C1.R58" )
				)
				( pin "vss(340)"
					( attribute "PN" "T56"
						( Origin gPackager )
					)
					( objectStatus "U7C1.T56" )
				)
				( pin "vss(341)"
					( attribute "PN" "R54"
						( Origin gPackager )
					)
					( objectStatus "U7C1.R54" )
				)
				( pin "vss(342)"
					( attribute "PN" "R50"
						( Origin gPackager )
					)
					( objectStatus "U7C1.R50" )
				)
				( pin "vss(343)"
					( attribute "PN" "R5"
						( Origin gPackager )
					)
					( objectStatus "U7C1.R5" )
				)
				( pin "vss(344)"
					( attribute "PN" "U42"
						( Origin gPackager )
					)
					( objectStatus "U7C1.U42" )
				)
				( pin "vss(345)"
					( attribute "PN" "R27"
						( Origin gPackager )
					)
					( objectStatus "U7C1.R27" )
				)
				( pin "vss(346)"
					( attribute "PN" "P63"
						( Origin gPackager )
					)
					( objectStatus "U7C1.P63" )
				)
				( pin "vss(347)"
					( attribute "PN" "AE43"
						( Origin gPackager )
					)
					( objectStatus "U7C1.AE43" )
				)
				( pin "vss(348)"
					( attribute "PN" "N9"
						( Origin gPackager )
					)
					( objectStatus "U7C1.N9" )
				)
				( pin "vss(349)"
					( attribute "PN" "N68"
						( Origin gPackager )
					)
					( objectStatus "U7C1.N68" )
				)
				( pin "vss(350)"
					( attribute "PN" "R38"
						( Origin gPackager )
					)
					( objectStatus "U7C1.R38" )
				)
				( pin "vss(351)"
					( attribute "PN" "N5"
						( Origin gPackager )
					)
					( objectStatus "U7C1.N5" )
				)
				( pin "vss(352)"
					( attribute "PN" "N46"
						( Origin gPackager )
					)
					( objectStatus "U7C1.N46" )
				)
				( pin "vss(353)"
					( attribute "PN" "N38"
						( Origin gPackager )
					)
					( objectStatus "U7C1.N38" )
				)
				( pin "vss(354)"
					( attribute "PN" "N35"
						( Origin gPackager )
					)
					( objectStatus "U7C1.N35" )
				)
			)
			( gate "@baseboard_fab2_lib.baseboard_fab2(sch_1):page125_i11"
				( attribute "BOM_COST" "SB"
					( Origin gFrontEnd )
				)
				( attribute "CDS_LIB" "mstr_discrete"
					( Origin gPackager )
				)
				( attribute "CDS_LOCATION" "R2R11"
					( Origin gPackager )
				)
				( attribute "CDS_SEC" "1"
					( Origin gPackager )
				)
				( attribute "LOCATION" "R2R11"
					( Origin gFrontEnd )
				)
				( attribute "MATERIAL" "EMPTY"
					( Origin gFrontEnd )
				)
				( attribute "PACK_TYPE" "0402"
					( Origin gFrontEnd )
				)
				( attribute "PART_NUMBER" "G21796-026"
					( Origin gFrontEnd )
				)
				( attribute "PHYS_PAGE" "125"
					( Origin gFrontEnd )
				)
				( attribute "ROOM" "SB"
					( Origin gFrontEnd )
				)
				( attribute "ROT" "0"
					( Origin gFrontEnd )
				)
				( attribute "SEC" "1"
					( Origin gPackager )
				)
				( attribute "TOLERANCE" "1%"
					( Origin gFrontEnd )
				)
				( attribute "VALUE" "1.00K"
					( Origin gFrontEnd )
				)
				( attribute "VER" "2"
					( Origin gFrontEnd )
				)
				( attribute "WATTAGE" "1/16W"
					( Origin gFrontEnd )
				)
				( attribute "XY" "(1750,3050)"
					( Origin gFrontEnd )
				)
				( attribute "CHIPS_PART_NAME" "RES"
					( Origin gPackager )
				)
				( attribute "CDS_PART_NAME" "RES_0402-1.00K,1%,1/16W,EMPTY,A"
					( Origin gPackager )
				)
				( objectStatus "R2R11" )
				( pin "a"
					( attribute "PN" "1"
						( Origin gPackager )
					)
					( objectStatus "R2R11.1" )
				)
				( pin "b"
					( attribute "PN" "2"
						( Origin gPackager )
					)
					( objectStatus "R2R11.2" )
				)
			)
			( gate "@baseboard_fab2_lib.baseboard_fab2(sch_1):page125_i15"
				( attribute "BOM_COST" "SB"
					( Origin gFrontEnd )
				)
				( attribute "CDS_LIB" "mstr_discrete"
					( Origin gPackager )
				)
				( attribute "CDS_LOCATION" "R2T1"
					( Origin gPackager )
				)
				( attribute "CDS_SEC" "1"
					( Origin gPackager )
				)
				( attribute "LOCATION" "R2T1"
					( Origin gFrontEnd )
				)
				( attribute "MATERIAL" "CHIP"
					( Origin gFrontEnd )
				)
				( attribute "PACK_TYPE" "0402"
					( Origin gFrontEnd )
				)
				( attribute "PART_NUMBER" "G21796-026"
					( Origin gFrontEnd )
				)
				( attribute "PHYS_PAGE" "125"
					( Origin gFrontEnd )
				)
				( attribute "ROOM" "SB"
					( Origin gFrontEnd )
				)
				( attribute "ROT" "0"
					( Origin gFrontEnd )
				)
				( attribute "SEC" "1"
					( Origin gPackager )
				)
				( attribute "TOLERANCE" "1%"
					( Origin gFrontEnd )
				)
				( attribute "VALUE" "1.00K"
					( Origin gFrontEnd )
				)
				( attribute "VER" "2"
					( Origin gFrontEnd )
				)
				( attribute "WATTAGE" "1/16W"
					( Origin gFrontEnd )
				)
				( attribute "XY" "(1850,1475)"
					( Origin gFrontEnd )
				)
				( attribute "CHIPS_PART_NAME" "RES"
					( Origin gPackager )
				)
				( attribute "CDS_PART_NAME" "RES_0402-1.00K,1%,1/16W,CHIP,GA"
					( Origin gPackager )
				)
				( objectStatus "R2T1" )
				( pin "a"
					( attribute "PN" "1"
						( Origin gPackager )
					)
					( objectStatus "R2T1.1" )
				)
				( pin "b"
					( attribute "PN" "2"
						( Origin gPackager )
					)
					( objectStatus "R2T1.2" )
				)
			)
			( gate "@baseboard_fab2_lib.baseboard_fab2(sch_1):page125_i21"
				( attribute "BOM_COST" "SB"
					( Origin gFrontEnd )
				)
				( attribute "CDS_LIB" "mstr_discrete"
					( Origin gPackager )
				)
				( attribute "CDS_LOCATION" "R8E6"
					( Origin gPackager )
				)
				( attribute "CDS_SEC" "1"
					( Origin gPackager )
				)
				( attribute "LOCATION" "R8E6"
					( Origin gFrontEnd )
				)
				( attribute "MATERIAL" "EMPTY"
					( Origin gFrontEnd )
				)
				( attribute "PACK_TYPE" "0402"
					( Origin gFrontEnd )
				)
				( attribute "PART_NUMBER" "G21796-026"
					( Origin gFrontEnd )
				)
				( attribute "PHYS_PAGE" "125"
					( Origin gFrontEnd )
				)
				( attribute "ROOM" "SB"
					( Origin gFrontEnd )
				)
				( attribute "ROT" "0"
					( Origin gFrontEnd )
				)
				( attribute "SEC" "1"
					( Origin gFrontEnd )
				)
				( attribute "SEC_TYPE" "0402"
					( Origin gFrontEnd )
				)
				( attribute "TOLERANCE" "1%"
					( Origin gFrontEnd )
				)
				( attribute "VALUE" "1.00K"
					( Origin gFrontEnd )
				)
				( attribute "VER" "2"
					( Origin gFrontEnd )
				)
				( attribute "WATTAGE" "1/16W"
					( Origin gFrontEnd )
				)
				( attribute "XY" "(-950,3150)"
					( Origin gFrontEnd )
				)
				( attribute "CHIPS_PART_NAME" "RES"
					( Origin gPackager )
				)
				( attribute "CDS_PART_NAME" "RES_0402-1.00K,1%,1/16W,EMPTY,A"
					( Origin gPackager )
				)
				( objectStatus "R8E6" )
				( pin "a"
					( attribute "PN" "1"
						( Origin gPackager )
					)
					( objectStatus "R8E6.1" )
				)
				( pin "b"
					( attribute "PN" "2"
						( Origin gPackager )
					)
					( objectStatus "R8E6.2" )
				)
			)
			( gate "@baseboard_fab2_lib.baseboard_fab2(sch_1):page125_i24"
				( attribute "BOM_COST" "SB"
					( Origin gFrontEnd )
				)
				( attribute "CDS_LIB" "mstr_discrete"
					( Origin gPackager )
				)
				( attribute "CDS_LOCATION" "R8E4"
					( Origin gPackager )
				)
				( attribute "CDS_SEC" "1"
					( Origin gPackager )
				)
				( attribute "LOCATION" "R8E4"
					( Origin gFrontEnd )
				)
				( attribute "MATERIAL" "EMPTY"
					( Origin gFrontEnd )
				)
				( attribute "PACK_TYPE" "0402"
					( Origin gFrontEnd )
				)
				( attribute "PART_NUMBER" "G21796-026"
					( Origin gFrontEnd )
				)
				( attribute "PHYS_PAGE" "125"
					( Origin gFrontEnd )
				)
				( attribute "ROOM" "SB"
					( Origin gFrontEnd )
				)
				( attribute "ROT" "0"
					( Origin gFrontEnd )
				)
				( attribute "SEC" "1"
					( Origin gPackager )
				)
				( attribute "TOLERANCE" "1%"
					( Origin gFrontEnd )
				)
				( attribute "VALUE" "1.00K"
					( Origin gFrontEnd )
				)
				( attribute "VER" "2"
					( Origin gFrontEnd )
				)
				( attribute "WATTAGE" "1/16W"
					( Origin gFrontEnd )
				)
				( attribute "XY" "(-950,2750)"
					( Origin gFrontEnd )
				)
				( attribute "CHIPS_PART_NAME" "RES"
					( Origin gPackager )
				)
				( attribute "CDS_PART_NAME" "RES_0402-1.00K,1%,1/16W,EMPTY,A"
					( Origin gPackager )
				)
				( objectStatus "R8E4" )
				( pin "a"
					( attribute "PN" "1"
						( Origin gPackager )
					)
					( objectStatus "R8E4.1" )
				)
				( pin "b"
					( attribute "PN" "2"
						( Origin gPackager )
					)
					( objectStatus "R8E4.2" )
				)
			)
			( gate "@baseboard_fab2_lib.baseboard_fab2(sch_1):page125_i40"
				( attribute "BOM_COST" "SB"
					( Origin gFrontEnd )
				)
				( attribute "CDS_LIB" "mstr_discrete"
					( Origin gPackager )
				)
				( attribute "CDS_LOCATION" "R8C18"
					( Origin gPackager )
				)
				( attribute "CDS_SEC" "1"
					( Origin gPackager )
				)
				( attribute "LOCATION" "R8C18"
					( Origin gFrontEnd )
				)
				( attribute "MATERIAL" "CHIP"
					( Origin gFrontEnd )
				)
				( attribute "PACK_TYPE" "0402"
					( Origin gFrontEnd )
				)
				( attribute "PART_NUMBER" "G21796-026"
					( Origin gFrontEnd )
				)
				( attribute "PHYS_PAGE" "125"
					( Origin gFrontEnd )
				)
				( attribute "ROOM" "SB"
					( Origin gFrontEnd )
				)
				( attribute "ROT" "0"
					( Origin gFrontEnd )
				)
				( attribute "SEC" "1"
					( Origin gPackager )
				)
				( attribute "TOLERANCE" "1%"
					( Origin gFrontEnd )
				)
				( attribute "VALUE" "1.00K"
					( Origin gFrontEnd )
				)
				( attribute "VER" "2"
					( Origin gFrontEnd )
				)
				( attribute "WATTAGE" "1/16W"
					( Origin gFrontEnd )
				)
				( attribute "XY" "(-3225,2525)"
					( Origin gFrontEnd )
				)
				( attribute "CHIPS_PART_NAME" "RES"
					( Origin gPackager )
				)
				( attribute "CDS_PART_NAME" "RES_0402-1.00K,1%,1/16W,CHIP,GA"
					( Origin gPackager )
				)
				( objectStatus "R8C18" )
				( pin "a"
					( attribute "PN" "1"
						( Origin gPackager )
					)
					( objectStatus "R8C18.1" )
				)
				( pin "b"
					( attribute "PN" "2"
						( Origin gPackager )
					)
					( objectStatus "R8C18.2" )
				)
			)
			( gate "@baseboard_fab2_lib.baseboard_fab2(sch_1):page125_i41"
				( attribute "BOM_COST" "SB"
					( Origin gFrontEnd )
				)
				( attribute "CDS_LIB" "mstr_discrete"
					( Origin gPackager )
				)
				( attribute "CDS_LOCATION" "R8C17"
					( Origin gPackager )
				)
				( attribute "CDS_SEC" "1"
					( Origin gPackager )
				)
				( attribute "LOCATION" "R8C17"
					( Origin gFrontEnd )
				)
				( attribute "MATERIAL" "EMPTY"
					( Origin gFrontEnd )
				)
				( attribute "PACK_TYPE" "0402"
					( Origin gFrontEnd )
				)
				( attribute "PART_NUMBER" "G21796-026"
					( Origin gFrontEnd )
				)
				( attribute "PHYS_PAGE" "125"
					( Origin gFrontEnd )
				)
				( attribute "ROOM" "SB"
					( Origin gFrontEnd )
				)
				( attribute "ROT" "0"
					( Origin gFrontEnd )
				)
				( attribute "SEC" "1"
					( Origin gFrontEnd )
				)
				( attribute "SEC_TYPE" "0402"
					( Origin gFrontEnd )
				)
				( attribute "TOLERANCE" "1%"
					( Origin gFrontEnd )
				)
				( attribute "VALUE" "1.00K"
					( Origin gFrontEnd )
				)
				( attribute "VER" "2"
					( Origin gFrontEnd )
				)
				( attribute "WATTAGE" "1/16W"
					( Origin gFrontEnd )
				)
				( attribute "XY" "(-3225,2200)"
					( Origin gFrontEnd )
				)
				( attribute "CHIPS_PART_NAME" "RES"
					( Origin gPackager )
				)
				( attribute "CDS_PART_NAME" "RES_0402-1.00K,1%,1/16W,EMPTY,A"
					( Origin gPackager )
				)
				( objectStatus "R8C17" )
				( pin "a"
					( attribute "PN" "1"
						( Origin gPackager )
					)
					( objectStatus "R8C17.1" )
				)
				( pin "b"
					( attribute "PN" "2"
						( Origin gPackager )
					)
					( objectStatus "R8C17.2" )
				)
			)
			( gate "@baseboard_fab2_lib.baseboard_fab2(sch_1):page125_i50"
				( attribute "BOM_COST" "SB"
					( Origin gFrontEnd )
				)
				( attribute "CDS_LIB" "mstr_discrete"
					( Origin gPackager )
				)
				( attribute "CDS_LOCATION" "R8D5"
					( Origin gPackager )
				)
				( attribute "CDS_SEC" "1"
					( Origin gPackager )
				)
				( attribute "LOCATION" "R8D5"
					( Origin gFrontEnd )
				)
				( attribute "MATERIAL" "EMPTY"
					( Origin gFrontEnd )
				)
				( attribute "PACK_TYPE" "0402"
					( Origin gFrontEnd )
				)
				( attribute "PART_NUMBER" "G21796-026"
					( Origin gFrontEnd )
				)
				( attribute "PHYS_PAGE" "125"
					( Origin gFrontEnd )
				)
				( attribute "ROOM" "SB"
					( Origin gFrontEnd )
				)
				( attribute "ROT" "0"
					( Origin gFrontEnd )
				)
				( attribute "SEC" "1"
					( Origin gPackager )
				)
				( attribute "TOLERANCE" "1%"
					( Origin gFrontEnd )
				)
				( attribute "VALUE" "1.00K"
					( Origin gFrontEnd )
				)
				( attribute "VER" "2"
					( Origin gFrontEnd )
				)
				( attribute "WATTAGE" "1/16W"
					( Origin gFrontEnd )
				)
				( attribute "XY" "(-925,4450)"
					( Origin gFrontEnd )
				)
				( attribute "CHIPS_PART_NAME" "RES"
					( Origin gPackager )
				)
				( attribute "CDS_PART_NAME" "RES_0402-1.00K,1%,1/16W,EMPTY,A"
					( Origin gPackager )
				)
				( objectStatus "R8D5" )
				( pin "a"
					( attribute "PN" "1"
						( Origin gPackager )
					)
					( objectStatus "R8D5.1" )
				)
				( pin "b"
					( attribute "PN" "2"
						( Origin gPackager )
					)
					( objectStatus "R8D5.2" )
				)
			)
			( gate "@baseboard_fab2_lib.baseboard_fab2(sch_1):page125_i52"
				( attribute "BOM_COST" "SB"
					( Origin gFrontEnd )
				)
				( attribute "CDS_LIB" "mstr_discrete"
					( Origin gPackager )
				)
				( attribute "CDS_LOCATION" "R8D13"
					( Origin gPackager )
				)
				( attribute "CDS_SEC" "1"
					( Origin gPackager )
				)
				( attribute "LOCATION" "R8D13"
					( Origin gFrontEnd )
				)
				( attribute "MATERIAL" "CHIP"
					( Origin gFrontEnd )
				)
				( attribute "PACK_TYPE" "0402"
					( Origin gFrontEnd )
				)
				( attribute "PART_NUMBER" "G21796-016"
					( Origin gFrontEnd )
				)
				( attribute "PHYS_PAGE" "125"
					( Origin gFrontEnd )
				)
				( attribute "ROOM" "SB_HEADERS"
					( Origin gFrontEnd )
				)
				( attribute "ROT" "0"
					( Origin gFrontEnd )
				)
				( attribute "SEC" "1"
					( Origin gPackager )
				)
				( attribute "TOLERANCE" "1%"
					( Origin gFrontEnd )
				)
				( attribute "VALUE" "10.0K"
					( Origin gFrontEnd )
				)
				( attribute "VER" "2"
					( Origin gFrontEnd )
				)
				( attribute "WATTAGE" "1/16W"
					( Origin gFrontEnd )
				)
				( attribute "XY" "(-925,4925)"
					( Origin gFrontEnd )
				)
				( attribute "CHIPS_PART_NAME" "RES"
					( Origin gPackager )
				)
				( attribute "CDS_PART_NAME" "RES_0402-10.0K,1%,1/16W,CHIP,GA"
					( Origin gPackager )
				)
				( objectStatus "R8D13" )
				( pin "a"
					( attribute "PN" "1"
						( Origin gPackager )
					)
					( objectStatus "R8D13.1" )
				)
				( pin "b"
					( attribute "PN" "2"
						( Origin gPackager )
					)
					( objectStatus "R8D13.2" )
				)
			)
			( gate "@baseboard_fab2_lib.baseboard_fab2(sch_1):page125_i60"
				( attribute "BOM_COST" "SB"
					( Origin gFrontEnd )
				)
				( attribute "CDS_LIB" "mstr_discrete"
					( Origin gPackager )
				)
				( attribute "CDS_LOCATION" "R7D13"
					( Origin gPackager )
				)
				( attribute "CDS_SEC" "1"
					( Origin gPackager )
				)
				( attribute "LOCATION" "R7D13"
					( Origin gFrontEnd )
				)
				( attribute "MATERIAL" "EMPTY"
					( Origin gFrontEnd )
				)
				( attribute "PACK_TYPE" "0402"
					( Origin gFrontEnd )
				)
				( attribute "PART_NUMBER" "G21796-345"
					( Origin gFrontEnd )
				)
				( attribute "PHYS_PAGE" "125"
					( Origin gFrontEnd )
				)
				( attribute "ROOM" "SB"
					( Origin gFrontEnd )
				)
				( attribute "ROT" "0"
					( Origin gFrontEnd )
				)
				( attribute "SEC" "1"
					( Origin gPackager )
				)
				( attribute "TOLERANCE" "1%"
					( Origin gFrontEnd )
				)
				( attribute "VALUE" "8.2K"
					( Origin gFrontEnd )
				)
				( attribute "VER" "2"
					( Origin gFrontEnd )
				)
				( attribute "WATTAGE" "1/16W"
					( Origin gFrontEnd )
				)
				( attribute "XY" "(-3275,4975)"
					( Origin gFrontEnd )
				)
				( attribute "CHIPS_PART_NAME" "RES"
					( Origin gPackager )
				)
				( attribute "CDS_PART_NAME" "RES_0402-8.2K,1%,1/16W,EMPTY,GA"
					( Origin gPackager )
				)
				( objectStatus "R7D13" )
				( pin "a"
					( attribute "PN" "1"
						( Origin gPackager )
					)
					( objectStatus "R7D13.1" )
				)
				( pin "b"
					( attribute "PN" "2"
						( Origin gPackager )
					)
					( objectStatus "R7D13.2" )
				)
			)
			( gate "@baseboard_fab2_lib.baseboard_fab2(sch_1):page125_i70"
				( attribute "BOM_COST" "SB"
					( Origin gFrontEnd )
				)
				( attribute "CDS_LIB" "mstr_discrete"
					( Origin gPackager )
				)
				( attribute "CDS_LOCATION" "R7D1"
					( Origin gPackager )
				)
				( attribute "CDS_SEC" "1"
					( Origin gPackager )
				)
				( attribute "LOCATION" "R7D1"
					( Origin gFrontEnd )
				)
				( attribute "MATERIAL" "CHIP"
					( Origin gFrontEnd )
				)
				( attribute "PACK_TYPE" "0402"
					( Origin gFrontEnd )
				)
				( attribute "PART_NUMBER" "G21796-026"
					( Origin gFrontEnd )
				)
				( attribute "PHYS_PAGE" "125"
					( Origin gFrontEnd )
				)
				( attribute "ROOM" "SB"
					( Origin gFrontEnd )
				)
				( attribute "ROT" "0"
					( Origin gFrontEnd )
				)
				( attribute "SEC" "1"
					( Origin gFrontEnd )
				)
				( attribute "SEC_TYPE" "0402"
					( Origin gFrontEnd )
				)
				( attribute "TOLERANCE" "1%"
					( Origin gFrontEnd )
				)
				( attribute "VALUE" "1.00K"
					( Origin gFrontEnd )
				)
				( attribute "VER" "2"
					( Origin gFrontEnd )
				)
				( attribute "WATTAGE" "1/16W"
					( Origin gFrontEnd )
				)
				( attribute "XY" "(-5050,3375)"
					( Origin gFrontEnd )
				)
				( attribute "CHIPS_PART_NAME" "RES"
					( Origin gPackager )
				)
				( attribute "CDS_PART_NAME" "RES_0402-1.00K,1%,1/16W,CHIP,GA"
					( Origin gPackager )
				)
				( objectStatus "R7D1" )
				( pin "a"
					( attribute "PN" "1"
						( Origin gPackager )
					)
					( objectStatus "R7D1.1" )
				)
				( pin "b"
					( attribute "PN" "2"
						( Origin gPackager )
					)
					( objectStatus "R7D1.2" )
				)
			)
			( gate "@baseboard_fab2_lib.baseboard_fab2(sch_1):page125_i71"
				( attribute "BOM_COST" "SB"
					( Origin gFrontEnd )
				)
				( attribute "CDS_LIB" "mstr_discrete"
					( Origin gPackager )
				)
				( attribute "CDS_LOCATION" "R8D16"
					( Origin gPackager )
				)
				( attribute "CDS_SEC" "1"
					( Origin gPackager )
				)
				( attribute "LOCATION" "R8D16"
					( Origin gFrontEnd )
				)
				( attribute "MATERIAL" "EMPTY"
					( Origin gFrontEnd )
				)
				( attribute "PACK_TYPE" "0402"
					( Origin gFrontEnd )
				)
				( attribute "PART_NUMBER" "G21796-016"
					( Origin gFrontEnd )
				)
				( attribute "PHYS_PAGE" "125"
					( Origin gFrontEnd )
				)
				( attribute "ROOM" "SB"
					( Origin gFrontEnd )
				)
				( attribute "ROT" "0"
					( Origin gFrontEnd )
				)
				( attribute "SEC" "1"
					( Origin gFrontEnd )
				)
				( attribute "SEC_TYPE" "0402"
					( Origin gFrontEnd )
				)
				( attribute "TOLERANCE" "1%"
					( Origin gFrontEnd )
				)
				( attribute "VALUE" "10.0K"
					( Origin gFrontEnd )
				)
				( attribute "VER" "2"
					( Origin gFrontEnd )
				)
				( attribute "WATTAGE" "1/16W"
					( Origin gFrontEnd )
				)
				( attribute "XY" "(-5050,3750)"
					( Origin gFrontEnd )
				)
				( attribute "CHIPS_PART_NAME" "RES"
					( Origin gPackager )
				)
				( attribute "CDS_PART_NAME" "RES_0402-10.0K,1%,1/16W,EMPTY,A"
					( Origin gPackager )
				)
				( objectStatus "R8D16" )
				( pin "a"
					( attribute "PN" "1"
						( Origin gPackager )
					)
					( objectStatus "R8D16.1" )
				)
				( pin "b"
					( attribute "PN" "2"
						( Origin gPackager )
					)
					( objectStatus "R8D16.2" )
				)
			)
			( gate "@baseboard_fab2_lib.baseboard_fab2(sch_1):page125_i72"
				( attribute "BOM_COST" "SB"
					( Origin gFrontEnd )
				)
				( attribute "CDS_LIB" "mstr_discrete"
					( Origin gPackager )
				)
				( attribute "CDS_LOCATION" "R3N2"
					( Origin gPackager )
				)
				( attribute "CDS_SEC" "1"
					( Origin gPackager )
				)
				( attribute "LOCATION" "R3N2"
					( Origin gFrontEnd )
				)
				( attribute "MATERIAL" "EMPTY"
					( Origin gFrontEnd )
				)
				( attribute "PACK_TYPE" "0402"
					( Origin gFrontEnd )
				)
				( attribute "PART_NUMBER" "G21796-072"
					( Origin gFrontEnd )
				)
				( attribute "PHYS_PAGE" "125"
					( Origin gFrontEnd )
				)
				( attribute "ROOM" "BMC_MISC"
					( Origin gFrontEnd )
				)
				( attribute "ROT" "0"
					( Origin gFrontEnd )
				)
				( attribute "SEC" "1"
					( Origin gFrontEnd )
				)
				( attribute "SEC_TYPE" "0402"
					( Origin gFrontEnd )
				)
				( attribute "TOLERANCE" "1%"
					( Origin gFrontEnd )
				)
				( attribute "VALUE" "4.75K"
					( Origin gFrontEnd )
				)
				( attribute "VER" "2"
					( Origin gFrontEnd )
				)
				( attribute "WATTAGE" "1/16W"
					( Origin gFrontEnd )
				)
				( attribute "XY" "(400,4600)"
					( Origin gFrontEnd )
				)
				( attribute "CHIPS_PART_NAME" "RES"
					( Origin gPackager )
				)
				( attribute "CDS_PART_NAME" "RES_0402-4.75K,1%,1/16W,EMPTY,A"
					( Origin gPackager )
				)
				( objectStatus "R3N2" )
				( pin "a"
					( attribute "PN" "1"
						( Origin gPackager )
					)
					( objectStatus "R3N2.1" )
				)
				( pin "b"
					( attribute "PN" "2"
						( Origin gPackager )
					)
					( objectStatus "R3N2.2" )
				)
			)
			( gate "@baseboard_fab2_lib.baseboard_fab2(sch_1):page125_i76"
				( attribute "CDS_LIB" "mstr_discrete"
					( Origin gPackager )
				)
				( attribute "CDS_LOCATION" "R2U30"
					( Origin gPackager )
				)
				( attribute "CDS_SEC" "1"
					( Origin gPackager )
				)
				( attribute "LOCATION" "R2U30"
					( Origin gFrontEnd )
				)
				( attribute "MATERIAL" "CHIP"
					( Origin gFrontEnd )
				)
				( attribute "PACK_TYPE" "0402"
					( Origin gFrontEnd )
				)
				( attribute "PART_NUMBER" "G21796-072"
					( Origin gFrontEnd )
				)
				( attribute "PHYS_PAGE" "125"
					( Origin gFrontEnd )
				)
				( attribute "ROOM" "ADR"
					( Origin gFrontEnd )
				)
				( attribute "ROT" "0"
					( Origin gFrontEnd )
				)
				( attribute "SEC" "1"
					( Origin gPackager )
				)
				( attribute "TOLERANCE" "1%"
					( Origin gFrontEnd )
				)
				( attribute "VALUE" "4.75K"
					( Origin gFrontEnd )
				)
				( attribute "VER" "2"
					( Origin gFrontEnd )
				)
				( attribute "WATTAGE" "1/16W"
					( Origin gFrontEnd )
				)
				( attribute "XY" "(-3350,1375)"
					( Origin gFrontEnd )
				)
				( attribute "CHIPS_PART_NAME" "RES"
					( Origin gPackager )
				)
				( attribute "CDS_PART_NAME" "RES_0402-4.75K,1%,1/16W,CHIP,GA"
					( Origin gPackager )
				)
				( objectStatus "R2U30" )
				( pin "a"
					( attribute "PN" "1"
						( Origin gPackager )
					)
					( objectStatus "R2U30.1" )
				)
				( pin "b"
					( attribute "PN" "2"
						( Origin gPackager )
					)
					( objectStatus "R2U30.2" )
				)
			)
			( gate "@baseboard_fab2_lib.baseboard_fab2(sch_1):page125_i78"
				( attribute "BOM_COST" "SB"
					( Origin gFrontEnd )
				)
				( attribute "CDS_LIB" "mstr_discrete"
					( Origin gPackager )
				)
				( attribute "CDS_LOCATION" "R3N17"
					( Origin gPackager )
				)
				( attribute "CDS_SEC" "1"
					( Origin gPackager )
				)
				( attribute "LOCATION" "R3N17"
					( Origin gFrontEnd )
				)
				( attribute "MATERIAL" "EMPTY"
					( Origin gFrontEnd )
				)
				( attribute "PACK_TYPE" "0402"
					( Origin gFrontEnd )
				)
				( attribute "PART_NUMBER" "G21796-026"
					( Origin gFrontEnd )
				)
				( attribute "PHYS_PAGE" "125"
					( Origin gFrontEnd )
				)
				( attribute "ROOM" "SB"
					( Origin gFrontEnd )
				)
				( attribute "ROT" "0"
					( Origin gFrontEnd )
				)
				( attribute "SEC" "1"
					( Origin gFrontEnd )
				)
				( attribute "SEC_TYPE" "0402"
					( Origin gFrontEnd )
				)
				( attribute "TOLERANCE" "1%"
					( Origin gFrontEnd )
				)
				( attribute "VALUE" "1.00K"
					( Origin gFrontEnd )
				)
				( attribute "VER" "2"
					( Origin gFrontEnd )
				)
				( attribute "WATTAGE" "1/16W"
					( Origin gFrontEnd )
				)
				( attribute "XY" "(1850,1875)"
					( Origin gFrontEnd )
				)
				( attribute "CHIPS_PART_NAME" "RES"
					( Origin gPackager )
				)
				( attribute "CDS_PART_NAME" "RES_0402-1.00K,1%,1/16W,EMPTY,A"
					( Origin gPackager )
				)
				( objectStatus "R3N17" )
				( pin "a"
					( attribute "PN" "1"
						( Origin gPackager )
					)
					( objectStatus "R3N17.1" )
				)
				( pin "b"
					( attribute "PN" "2"
						( Origin gPackager )
					)
					( objectStatus "R3N17.2" )
				)
			)
			( gate "@baseboard_fab2_lib.baseboard_fab2(sch_1):page125_i83"
				( attribute "BOM_COST" "SB"
					( Origin gFrontEnd )
				)
				( attribute "CDS_LIB" "mstr_discrete"
					( Origin gPackager )
				)
				( attribute "CDS_LOCATION" "R2N14"
					( Origin gPackager )
				)
				( attribute "CDS_SEC" "1"
					( Origin gPackager )
				)
				( attribute "LOCATION" "R2N14"
					( Origin gFrontEnd )
				)
				( attribute "MATERIAL" "EMPTY"
					( Origin gFrontEnd )
				)
				( attribute "PACK_TYPE" "0402"
					( Origin gFrontEnd )
				)
				( attribute "PART_NUMBER" "G21796-026"
					( Origin gFrontEnd )
				)
				( attribute "PHYS_PAGE" "125"
					( Origin gFrontEnd )
				)
				( attribute "ROOM" "SB"
					( Origin gFrontEnd )
				)
				( attribute "ROT" "0"
					( Origin gFrontEnd )
				)
				( attribute "SEC" "1"
					( Origin gFrontEnd )
				)
				( attribute "SEC_TYPE" "0402"
					( Origin gFrontEnd )
				)
				( attribute "TOLERANCE" "1%"
					( Origin gFrontEnd )
				)
				( attribute "VALUE" "1.00K"
					( Origin gFrontEnd )
				)
				( attribute "VER" "2"
					( Origin gFrontEnd )
				)
				( attribute "WATTAGE" "1/16W"
					( Origin gFrontEnd )
				)
				( attribute "XY" "(-925,1525)"
					( Origin gFrontEnd )
				)
				( attribute "CHIPS_PART_NAME" "RES"
					( Origin gPackager )
				)
				( attribute "CDS_PART_NAME" "RES_0402-1.00K,1%,1/16W,EMPTY,A"
					( Origin gPackager )
				)
				( objectStatus "R2N14" )
				( pin "a"
					( attribute "PN" "1"
						( Origin gPackager )
					)
					( objectStatus "R2N14.1" )
				)
				( pin "b"
					( attribute "PN" "2"
						( Origin gPackager )
					)
					( objectStatus "R2N14.2" )
				)
			)
			( gate "@baseboard_fab2_lib.baseboard_fab2(sch_1):page126_i6"
				( attribute "BOM_COST" "SB"
					( Origin gFrontEnd )
				)
				( attribute "CDS_LIB" "mstr_discrete"
					( Origin gPackager )
				)
				( attribute "CDS_LOCATION" "R7D19"
					( Origin gPackager )
				)
				( attribute "CDS_SEC" "1"
					( Origin gPackager )
				)
				( attribute "LOCATION" "R7D19"
					( Origin gFrontEnd )
				)
				( attribute "MATERIAL" "EMPTY"
					( Origin gFrontEnd )
				)
				( attribute "PACK_TYPE" "0402"
					( Origin gFrontEnd )
				)
				( attribute "PART_NUMBER" "G21796-026"
					( Origin gFrontEnd )
				)
				( attribute "PHYS_PAGE" "126"
					( Origin gFrontEnd )
				)
				( attribute "ROOM" "SB"
					( Origin gFrontEnd )
				)
				( attribute "ROT" "0"
					( Origin gFrontEnd )
				)
				( attribute "SEC" "1"
					( Origin gFrontEnd )
				)
				( attribute "SEC_TYPE" "0402"
					( Origin gFrontEnd )
				)
				( attribute "TOLERANCE" "1%"
					( Origin gFrontEnd )
				)
				( attribute "VALUE" "1.00K"
					( Origin gFrontEnd )
				)
				( attribute "VER" "2"
					( Origin gFrontEnd )
				)
				( attribute "WATTAGE" "1/16W"
					( Origin gFrontEnd )
				)
				( attribute "XY" "(-6200,2350)"
					( Origin gFrontEnd )
				)
				( attribute "CHIPS_PART_NAME" "RES"
					( Origin gPackager )
				)
				( attribute "CDS_PART_NAME" "RES_0402-1.00K,1%,1/16W,EMPTY,A"
					( Origin gPackager )
				)
				( objectStatus "R7D19" )
				( pin "a"
					( attribute "PN" "1"
						( Origin gPackager )
					)
					( objectStatus "R7D19.1" )
				)
				( pin "b"
					( attribute "PN" "2"
						( Origin gPackager )
					)
					( objectStatus "R7D19.2" )
				)
			)
			( gate "@baseboard_fab2_lib.baseboard_fab2(sch_1):page126_i10"
				( attribute "BOM_COST" "SB"
					( Origin gFrontEnd )
				)
				( attribute "CDS_LIB" "mstr_discrete"
					( Origin gPackager )
				)
				( attribute "CDS_LOCATION" "R2N10"
					( Origin gPackager )
				)
				( attribute "CDS_SEC" "1"
					( Origin gPackager )
				)
				( attribute "LOCATION" "R2N10"
					( Origin gFrontEnd )
				)
				( attribute "MATERIAL" "CHIP"
					( Origin gFrontEnd )
				)
				( attribute "PACK_TYPE" "0402"
					( Origin gFrontEnd )
				)
				( attribute "PART_NUMBER" "G21796-072"
					( Origin gFrontEnd )
				)
				( attribute "PHYS_PAGE" "126"
					( Origin gFrontEnd )
				)
				( attribute "ROOM" "SB_HEADERS"
					( Origin gFrontEnd )
				)
				( attribute "ROT" "0"
					( Origin gFrontEnd )
				)
				( attribute "SEC" "1"
					( Origin gFrontEnd )
				)
				( attribute "SEC_TYPE" "0402"
					( Origin gFrontEnd )
				)
				( attribute "TOLERANCE" "1%"
					( Origin gFrontEnd )
				)
				( attribute "VALUE" "4.75K"
					( Origin gFrontEnd )
				)
				( attribute "VER" "2"
					( Origin gFrontEnd )
				)
				( attribute "WATTAGE" "1/16W"
					( Origin gFrontEnd )
				)
				( attribute "XY" "(-6325,4175)"
					( Origin gFrontEnd )
				)
				( attribute "CHIPS_PART_NAME" "RES"
					( Origin gPackager )
				)
				( attribute "CDS_PART_NAME" "RES_0402-4.75K,1%,1/16W,CHIP,GA"
					( Origin gPackager )
				)
				( objectStatus "R2N10" )
				( pin "a"
					( attribute "PN" "1"
						( Origin gPackager )
					)
					( objectStatus "R2N10.1" )
				)
				( pin "b"
					( attribute "PN" "2"
						( Origin gPackager )
					)
					( objectStatus "R2N10.2" )
				)
			)
			( gate "@baseboard_fab2_lib.baseboard_fab2(sch_1):page126_i12"
				( attribute "BOM_COST" "SM_CONTROLLER"
					( Origin gFrontEnd )
				)
				( attribute "CDS_LIB" "mstr_discrete"
					( Origin gPackager )
				)
				( attribute "CDS_LOCATION" "R1D35"
					( Origin gPackager )
				)
				( attribute "CDS_SEC" "1"
					( Origin gPackager )
				)
				( attribute "LOCATION" "R1D35"
					( Origin gFrontEnd )
				)
				( attribute "MATERIAL" "CHIP"
					( Origin gFrontEnd )
				)
				( attribute "PACK_TYPE" "0402"
					( Origin gFrontEnd )
				)
				( attribute "PART_NUMBER" "G21796-072"
					( Origin gFrontEnd )
				)
				( attribute "PHYS_PAGE" "126"
					( Origin gFrontEnd )
				)
				( attribute "ROOM" "BMC_MISC"
					( Origin gFrontEnd )
				)
				( attribute "ROT" "0"
					( Origin gFrontEnd )
				)
				( attribute "SEC" "1"
					( Origin gFrontEnd )
				)
				( attribute "SEC_TYPE" "0402"
					( Origin gFrontEnd )
				)
				( attribute "TOLERANCE" "1%"
					( Origin gFrontEnd )
				)
				( attribute "VALUE" "4.75K"
					( Origin gFrontEnd )
				)
				( attribute "VER" "2"
					( Origin gFrontEnd )
				)
				( attribute "WATTAGE" "1/16W"
					( Origin gFrontEnd )
				)
				( attribute "XY" "(-6200,2775)"
					( Origin gFrontEnd )
				)
				( attribute "CHIPS_PART_NAME" "RES"
					( Origin gPackager )
				)
				( attribute "CDS_PART_NAME" "RES_0402-4.75K,1%,1/16W,CHIP,GA"
					( Origin gPackager )
				)
				( objectStatus "R1D35" )
				( pin "a"
					( attribute "PN" "1"
						( Origin gPackager )
					)
					( objectStatus "R1D35.1" )
				)
				( pin "b"
					( attribute "PN" "2"
						( Origin gPackager )
					)
					( objectStatus "R1D35.2" )
				)
			)
			( gate "@baseboard_fab2_lib.baseboard_fab2(sch_1):page126_i13"
				( attribute "CDS_LIB" "mstr_discrete"
					( Origin gPackager )
				)
				( attribute "CDS_LOCATION" "Q8E2"
					( Origin gPackager )
				)
				( attribute "CDS_SEC" "1"
					( Origin gPackager )
				)
				( attribute "LOCATION" "Q8E2"
					( Origin gFrontEnd )
				)
				( attribute "MATERIAL" "FET"
					( Origin gFrontEnd )
				)
				( attribute "PACK_TYPE" "SOT23LF"
					( Origin gFrontEnd )
				)
				( attribute "PART_NUMBER" "C79254-001"
					( Origin gFrontEnd )
				)
				( attribute "PHYS_PAGE" "126"
					( Origin gFrontEnd )
				)
				( attribute "ROT" "0"
					( Origin gFrontEnd )
				)
				( attribute "SEC" "1"
					( Origin gFrontEnd )
				)
				( attribute "SEC_TYPE" "SOT23LF"
					( Origin gFrontEnd )
				)
				( attribute "VALUE" "2N7002"
					( Origin gFrontEnd )
				)
				( attribute "VER" "8"
					( Origin gFrontEnd )
				)
				( attribute "XY" "(-3625,3925)"
					( Origin gFrontEnd )
				)
				( attribute "CHIPS_PART_NAME" "FET_N"
					( Origin gPackager )
				)
				( attribute "CDS_PART_NAME" "FET_N_SOT23LF-2N7002,FET,C7925A"
					( Origin gPackager )
				)
				( objectStatus "Q8E2" )
				( pin "drn"
					( attribute "PN" "3"
						( Origin gPackager )
					)
					( objectStatus "Q8E2.3" )
				)
				( pin "gate"
					( attribute "PN" "1"
						( Origin gPackager )
					)
					( objectStatus "Q8E2.1" )
				)
				( pin "src"
					( attribute "PN" "2"
						( Origin gPackager )
					)
					( objectStatus "Q8E2.2" )
				)
			)
			( gate "@baseboard_fab2_lib.baseboard_fab2(sch_1):page126_i20"
				( attribute "BOM_COST" "SM_CONTROLLER"
					( Origin gFrontEnd )
				)
				( attribute "CDS_LIB" "mstr_discrete"
					( Origin gPackager )
				)
				( attribute "CDS_LOCATION" "R8C9"
					( Origin gPackager )
				)
				( attribute "CDS_SEC" "1"
					( Origin gPackager )
				)
				( attribute "LOCATION" "R8C9"
					( Origin gFrontEnd )
				)
				( attribute "MATERIAL" "CHIP"
					( Origin gFrontEnd )
				)
				( attribute "PACK_TYPE" "0402"
					( Origin gFrontEnd )
				)
				( attribute "PART_NUMBER" "G21796-072"
					( Origin gFrontEnd )
				)
				( attribute "PHYS_PAGE" "126"
					( Origin gFrontEnd )
				)
				( attribute "ROOM" "BMC_MISC"
					( Origin gFrontEnd )
				)
				( attribute "ROT" "0"
					( Origin gFrontEnd )
				)
				( attribute "SEC" "1"
					( Origin gFrontEnd )
				)
				( attribute "SEC_TYPE" "0402"
					( Origin gFrontEnd )
				)
				( attribute "TOLERANCE" "1%"
					( Origin gFrontEnd )
				)
				( attribute "VALUE" "4.75K"
					( Origin gFrontEnd )
				)
				( attribute "VER" "2"
					( Origin gFrontEnd )
				)
				( attribute "WATTAGE" "1/16W"
					( Origin gFrontEnd )
				)
				( attribute "XY" "(-3625,4425)"
					( Origin gFrontEnd )
				)
				( attribute "CHIPS_PART_NAME" "RES"
					( Origin gPackager )
				)
				( attribute "CDS_PART_NAME" "RES_0402-4.75K,1%,1/16W,CHIP,GA"
					( Origin gPackager )
				)
				( objectStatus "R8C9" )
				( pin "a"
					( attribute "PN" "1"
						( Origin gPackager )
					)
					( objectStatus "R8C9.1" )
				)
				( pin "b"
					( attribute "PN" "2"
						( Origin gPackager )
					)
					( objectStatus "R8C9.2" )
				)
			)
			( gate "@baseboard_fab2_lib.baseboard_fab2(sch_1):page126_i22"
				( attribute "CDS_LIB" "mstr_discrete"
					( Origin gPackager )
				)
				( attribute "CDS_LOCATION" "R3P62"
					( Origin gPackager )
				)
				( attribute "CDS_SEC" "1"
					( Origin gPackager )
				)
				( attribute "LOCATION" "R3P62"
					( Origin gFrontEnd )
				)
				( attribute "MATERIAL" "EMPTY"
					( Origin gFrontEnd )
				)
				( attribute "PACK_TYPE" "0402"
					( Origin gFrontEnd )
				)
				( attribute "PART_NUMBER" "G21796-072"
					( Origin gFrontEnd )
				)
				( attribute "PHYS_PAGE" "126"
					( Origin gFrontEnd )
				)
				( attribute "ROT" "0"
					( Origin gFrontEnd )
				)
				( attribute "SEC" "1"
					( Origin gFrontEnd )
				)
				( attribute "SEC_TYPE" "0402"
					( Origin gFrontEnd )
				)
				( attribute "TOLERANCE" "1%"
					( Origin gFrontEnd )
				)
				( attribute "VALUE" "4.75K"
					( Origin gFrontEnd )
				)
				( attribute "VER" "2"
					( Origin gFrontEnd )
				)
				( attribute "WATTAGE" "1/16W"
					( Origin gFrontEnd )
				)
				( attribute "XY" "(-4525,2725)"
					( Origin gFrontEnd )
				)
				( attribute "CHIPS_PART_NAME" "RES"
					( Origin gPackager )
				)
				( attribute "CDS_PART_NAME" "RES_0402-4.75K,1%,1/16W,EMPTY,A"
					( Origin gPackager )
				)
				( objectStatus "R3P62" )
				( pin "a"
					( attribute "PN" "1"
						( Origin gPackager )
					)
					( objectStatus "R3P62.1" )
				)
				( pin "b"
					( attribute "PN" "2"
						( Origin gPackager )
					)
					( objectStatus "R3P62.2" )
				)
			)
			( gate "@baseboard_fab2_lib.baseboard_fab2(sch_1):page126_i23"
				( attribute "CDS_LIB" "mstr_discrete"
					( Origin gPackager )
				)
				( attribute "CDS_LOCATION" "R3P64"
					( Origin gPackager )
				)
				( attribute "CDS_SEC" "1"
					( Origin gPackager )
				)
				( attribute "LOCATION" "R3P64"
					( Origin gFrontEnd )
				)
				( attribute "MATERIAL" "EMPTY"
					( Origin gFrontEnd )
				)
				( attribute "PACK_TYPE" "0402"
					( Origin gFrontEnd )
				)
				( attribute "PART_NUMBER" "G21796-026"
					( Origin gFrontEnd )
				)
				( attribute "PHYS_PAGE" "126"
					( Origin gFrontEnd )
				)
				( attribute "ROT" "0"
					( Origin gFrontEnd )
				)
				( attribute "SEC" "1"
					( Origin gFrontEnd )
				)
				( attribute "SEC_TYPE" "0402"
					( Origin gFrontEnd )
				)
				( attribute "TOLERANCE" "1%"
					( Origin gFrontEnd )
				)
				( attribute "VALUE" "1.00K"
					( Origin gFrontEnd )
				)
				( attribute "VER" "2"
					( Origin gFrontEnd )
				)
				( attribute "WATTAGE" "1/16W"
					( Origin gFrontEnd )
				)
				( attribute "XY" "(-4525,2275)"
					( Origin gFrontEnd )
				)
				( attribute "CHIPS_PART_NAME" "RES"
					( Origin gPackager )
				)
				( attribute "CDS_PART_NAME" "RES_0402-1.00K,1%,1/16W,EMPTY,A"
					( Origin gPackager )
				)
				( objectStatus "R3P64" )
				( pin "a"
					( attribute "PN" "1"
						( Origin gPackager )
					)
					( objectStatus "R3P64.1" )
				)
				( pin "b"
					( attribute "PN" "2"
						( Origin gPackager )
					)
					( objectStatus "R3P64.2" )
				)
			)
			( gate "@baseboard_fab2_lib.baseboard_fab2(sch_1):page127_i8"
				( attribute "BOM_COST" "SB"
					( Origin gFrontEnd )
				)
				( attribute "CDS_LIB" "mstr_discrete"
					( Origin gPackager )
				)
				( attribute "CDS_LOCATION" "FB3M1"
					( Origin gPackager )
				)
				( attribute "CDS_SEC" "1"
					( Origin gPackager )
				)
				( attribute "LOCATION" "FB3M1"
					( Origin gFrontEnd )
				)
				( attribute "MATERIAL" "FB"
					( Origin gFrontEnd )
				)
				( attribute "PACK_TYPE" "SM"
					( Origin gFrontEnd )
				)
				( attribute "PART_NUMBER" "693286-027"
					( Origin gFrontEnd )
				)
				( attribute "PHYS_PAGE" "127"
					( Origin gFrontEnd )
				)
				( attribute "ROOM" "SB_FILTER_PLL0"
					( Origin gFrontEnd )
				)
				( attribute "ROT" "0"
					( Origin gFrontEnd )
				)
				( attribute "SEC" "1"
					( Origin gFrontEnd )
				)
				( attribute "SEC_TYPE" "SM"
					( Origin gFrontEnd )
				)
				( attribute "VALUE" "120"
					( Origin gFrontEnd )
				)
				( attribute "VER" "1"
					( Origin gFrontEnd )
				)
				( attribute "XY" "(-4050,-850)"
					( Origin gFrontEnd )
				)
				( attribute "CHIPS_PART_NAME" "FERRITE"
					( Origin gPackager )
				)
				( attribute "CDS_PART_NAME" "FERRITE_SM-120,FB,693286-027"
					( Origin gPackager )
				)
				( objectStatus "FB3M1" )
				( pin "a"
					( attribute "PN" "1"
						( Origin gPackager )
					)
					( objectStatus "FB3M1.1" )
				)
				( pin "b"
					( attribute "PN" "2"
						( Origin gPackager )
					)
					( objectStatus "FB3M1.2" )
				)
			)
			( gate "@baseboard_fab2_lib.baseboard_fab2(sch_1):page127_i9"
				( attribute "BOM_COST" "SB"
					( Origin gFrontEnd )
				)
				( attribute "CDS_LIB" "dev_discrete"
					( Origin gPackager )
				)
				( attribute "CDS_LOCATION" "C3M21"
					( Origin gPackager )
				)
				( attribute "CDS_SEC" "1"
					( Origin gPackager )
				)
				( attribute "LOCATION" "C3M21"
					( Origin gFrontEnd )
				)
				( attribute "MATERIAL" "X6S"
					( Origin gFrontEnd )
				)
				( attribute "PACK_TYPE" "0402V"
					( Origin gFrontEnd )
				)
				( attribute "PART_NUMBER" "D97712-004"
					( Origin gFrontEnd )
				)
				( attribute "PHYS_PAGE" "127"
					( Origin gFrontEnd )
				)
				( attribute "ROOM" "SB_FILTER_PLL0"
					( Origin gFrontEnd )
				)
				( attribute "ROT" "2"
					( Origin gFrontEnd )
				)
				( attribute "SEC" "1"
					( Origin gFrontEnd )
				)
				( attribute "SEC_TYPE" "0402V"
					( Origin gFrontEnd )
				)
				( attribute "TOLERANCE" "10%"
					( Origin gFrontEnd )
				)
				( attribute "VALUE" "1.0UF"
					( Origin gFrontEnd )
				)
				( attribute "VER" "1"
					( Origin gFrontEnd )
				)
				( attribute "VOLTAGE" "6.3V"
					( Units "uVoltage" "V" 1.000000)
					( Origin gFrontEnd )
				)
				( attribute "XY" "(-4300,-1050)"
					( Origin gFrontEnd )
				)
				( attribute "CHIPS_PART_NAME" "CAP_A"
					( Origin gPackager )
				)
				( attribute "CDS_PART_NAME" "CAP_A_0402V-1.0UF,6.3V,10%,X6SA"
					( Origin gPackager )
				)
				( objectStatus "C3M21" )
				( pin "a"
					( attribute "PN" "1"
						( Origin gPackager )
					)
					( objectStatus "C3M21.1" )
				)
				( pin "b"
					( attribute "PN" "2"
						( Origin gPackager )
					)
					( objectStatus "C3M21.2" )
				)
			)
			( gate "@baseboard_fab2_lib.baseboard_fab2(sch_1):page127_i17"
				( attribute "BOM_COST" "SB"
					( Origin gFrontEnd )
				)
				( attribute "CDS_LIB" "mstr_discrete"
					( Origin gPackager )
				)
				( attribute "CDS_LOCATION" "FB3M2"
					( Origin gPackager )
				)
				( attribute "CDS_SEC" "1"
					( Origin gPackager )
				)
				( attribute "LOCATION" "FB3M2"
					( Origin gFrontEnd )
				)
				( attribute "MATERIAL" "FB"
					( Origin gFrontEnd )
				)
				( attribute "PACK_TYPE" "SM"
					( Origin gFrontEnd )
				)
				( attribute "PART_NUMBER" "693286-027"
					( Origin gFrontEnd )
				)
				( attribute "PHYS_PAGE" "127"
					( Origin gFrontEnd )
				)
				( attribute "ROOM" "SB_FILTER_PLL1"
					( Origin gFrontEnd )
				)
				( attribute "ROT" "0"
					( Origin gFrontEnd )
				)
				( attribute "SEC" "1"
					( Origin gFrontEnd )
				)
				( attribute "SEC_TYPE" "SM"
					( Origin gFrontEnd )
				)
				( attribute "VALUE" "120"
					( Origin gFrontEnd )
				)
				( attribute "VER" "1"
					( Origin gFrontEnd )
				)
				( attribute "XY" "(-4025,-2050)"
					( Origin gFrontEnd )
				)
				( attribute "CHIPS_PART_NAME" "FERRITE"
					( Origin gPackager )
				)
				( attribute "CDS_PART_NAME" "FERRITE_SM-120,FB,693286-027"
					( Origin gPackager )
				)
				( objectStatus "FB3M2" )
				( pin "a"
					( attribute "PN" "1"
						( Origin gPackager )
					)
					( objectStatus "FB3M2.1" )
				)
				( pin "b"
					( attribute "PN" "2"
						( Origin gPackager )
					)
					( objectStatus "FB3M2.2" )
				)
			)
			( gate "@baseboard_fab2_lib.baseboard_fab2(sch_1):page127_i18"
				( attribute "BOM_COST" "SB"
					( Origin gFrontEnd )
				)
				( attribute "CDS_LIB" "dev_discrete"
					( Origin gPackager )
				)
				( attribute "CDS_LOCATION" "C3M22"
					( Origin gPackager )
				)
				( attribute "CDS_SEC" "1"
					( Origin gPackager )
				)
				( attribute "LOCATION" "C3M22"
					( Origin gFrontEnd )
				)
				( attribute "MATERIAL" "X6S"
					( Origin gFrontEnd )
				)
				( attribute "PACK_TYPE" "0402V"
					( Origin gFrontEnd )
				)
				( attribute "PART_NUMBER" "D97712-004"
					( Origin gFrontEnd )
				)
				( attribute "PHYS_PAGE" "127"
					( Origin gFrontEnd )
				)
				( attribute "ROOM" "SB_FILTER_PLL1"
					( Origin gFrontEnd )
				)
				( attribute "ROT" "2"
					( Origin gFrontEnd )
				)
				( attribute "SEC" "1"
					( Origin gFrontEnd )
				)
				( attribute "SEC_TYPE" "0402V"
					( Origin gFrontEnd )
				)
				( attribute "TOLERANCE" "10%"
					( Origin gFrontEnd )
				)
				( attribute "VALUE" "1.0UF"
					( Origin gFrontEnd )
				)
				( attribute "VER" "1"
					( Origin gFrontEnd )
				)
				( attribute "VOLTAGE" "6.3V"
					( Units "uVoltage" "V" 1.000000)
					( Origin gFrontEnd )
				)
				( attribute "XY" "(-4275,-2250)"
					( Origin gFrontEnd )
				)
				( attribute "CHIPS_PART_NAME" "CAP_A"
					( Origin gPackager )
				)
				( attribute "CDS_PART_NAME" "CAP_A_0402V-1.0UF,6.3V,10%,X6SA"
					( Origin gPackager )
				)
				( objectStatus "C3M22" )
				( pin "a"
					( attribute "PN" "1"
						( Origin gPackager )
					)
					( objectStatus "C3M22.1" )
				)
				( pin "b"
					( attribute "PN" "2"
						( Origin gPackager )
					)
					( objectStatus "C3M22.2" )
				)
			)
			( gate "@baseboard_fab2_lib.baseboard_fab2(sch_1):page127_i26"
				( attribute "BOM_COST" "SB"
					( Origin gFrontEnd )
				)
				( attribute "CDS_LIB" "mstr_discrete"
					( Origin gPackager )
				)
				( attribute "CDS_LOCATION" "FB3M3"
					( Origin gPackager )
				)
				( attribute "CDS_SEC" "1"
					( Origin gPackager )
				)
				( attribute "LOCATION" "FB3M3"
					( Origin gFrontEnd )
				)
				( attribute "MATERIAL" "FB"
					( Origin gFrontEnd )
				)
				( attribute "PACK_TYPE" "SM"
					( Origin gFrontEnd )
				)
				( attribute "PART_NUMBER" "693286-027"
					( Origin gFrontEnd )
				)
				( attribute "PHYS_PAGE" "127"
					( Origin gFrontEnd )
				)
				( attribute "ROOM" "SB_FILTER_XTAL"
					( Origin gFrontEnd )
				)
				( attribute "ROT" "0"
					( Origin gFrontEnd )
				)
				( attribute "SEC" "1"
					( Origin gFrontEnd )
				)
				( attribute "SEC_TYPE" "SM"
					( Origin gFrontEnd )
				)
				( attribute "VALUE" "120"
					( Origin gFrontEnd )
				)
				( attribute "VER" "1"
					( Origin gFrontEnd )
				)
				( attribute "XY" "(-4000,-3350)"
					( Origin gFrontEnd )
				)
				( attribute "CHIPS_PART_NAME" "FERRITE"
					( Origin gPackager )
				)
				( attribute "CDS_PART_NAME" "FERRITE_SM-120,FB,693286-027"
					( Origin gPackager )
				)
				( objectStatus "FB3M3" )
				( pin "a"
					( attribute "PN" "1"
						( Origin gPackager )
					)
					( objectStatus "FB3M3.1" )
				)
				( pin "b"
					( attribute "PN" "2"
						( Origin gPackager )
					)
					( objectStatus "FB3M3.2" )
				)
			)
			( gate "@baseboard_fab2_lib.baseboard_fab2(sch_1):page127_i27"
				( attribute "BOM_COST" "SB"
					( Origin gFrontEnd )
				)
				( attribute "CDS_LIB" "dev_discrete"
					( Origin gPackager )
				)
				( attribute "CDS_LOCATION" "C3M30"
					( Origin gPackager )
				)
				( attribute "CDS_SEC" "1"
					( Origin gPackager )
				)
				( attribute "LOCATION" "C3M30"
					( Origin gFrontEnd )
				)
				( attribute "MATERIAL" "X6S"
					( Origin gFrontEnd )
				)
				( attribute "PACK_TYPE" "0402V"
					( Origin gFrontEnd )
				)
				( attribute "PART_NUMBER" "D97712-004"
					( Origin gFrontEnd )
				)
				( attribute "PHYS_PAGE" "127"
					( Origin gFrontEnd )
				)
				( attribute "ROOM" "SB_FILTER_XTAL"
					( Origin gFrontEnd )
				)
				( attribute "ROT" "2"
					( Origin gFrontEnd )
				)
				( attribute "SEC" "1"
					( Origin gFrontEnd )
				)
				( attribute "SEC_TYPE" "0402V"
					( Origin gFrontEnd )
				)
				( attribute "TOLERANCE" "10%"
					( Origin gFrontEnd )
				)
				( attribute "VALUE" "1.0UF"
					( Origin gFrontEnd )
				)
				( attribute "VER" "1"
					( Origin gFrontEnd )
				)
				( attribute "VOLTAGE" "6.3V"
					( Units "uVoltage" "V" 1.000000)
					( Origin gFrontEnd )
				)
				( attribute "XY" "(-4250,-3550)"
					( Origin gFrontEnd )
				)
				( attribute "CHIPS_PART_NAME" "CAP_A"
					( Origin gPackager )
				)
				( attribute "CDS_PART_NAME" "CAP_A_0402V-1.0UF,6.3V,10%,X6SA"
					( Origin gPackager )
				)
				( objectStatus "C3M30" )
				( pin "a"
					( attribute "PN" "1"
						( Origin gPackager )
					)
					( objectStatus "C3M30.1" )
				)
				( pin "b"
					( attribute "PN" "2"
						( Origin gPackager )
					)
					( objectStatus "C3M30.2" )
				)
			)
			( gate "@baseboard_fab2_lib.baseboard_fab2(sch_1):page127_i43"
				( attribute "BOM_COST" "SB"
					( Origin gFrontEnd )
				)
				( attribute "CDS_LIB" "mstr_discrete"
					( Origin gPackager )
				)
				( attribute "CDS_LOCATION" "C2M5"
					( Origin gPackager )
				)
				( attribute "CDS_SEC" "1"
					( Origin gPackager )
				)
				( attribute "LOCATION" "C2M5"
					( Origin gFrontEnd )
				)
				( attribute "MATERIAL" "X6S"
					( Origin gFrontEnd )
				)
				( attribute "PACK_TYPE" "0603LF"
					( Origin gFrontEnd )
				)
				( attribute "PART_NUMBER" "E15431-001"
					( Origin gFrontEnd )
				)
				( attribute "PHYS_PAGE" "127"
					( Origin gFrontEnd )
				)
				( attribute "ROOM" "SB_FILTER_VM20"
					( Origin gFrontEnd )
				)
				( attribute "ROT" "0"
					( Origin gFrontEnd )
				)
				( attribute "SEC" "1"
					( Origin gFrontEnd )
				)
				( attribute "SEC_TYPE" "0603LF"
					( Origin gFrontEnd )
				)
				( attribute "TOLERANCE" "20%"
					( Origin gFrontEnd )
				)
				( attribute "VALUE" "10UF"
					( Origin gFrontEnd )
				)
				( attribute "VER" "1"
					( Origin gFrontEnd )
				)
				( attribute "VOLTAGE" "4V"
					( Units "uVoltage" "V" 1.000000)
					( Origin gFrontEnd )
				)
				( attribute "XY" "(1850,-1375)"
					( Origin gFrontEnd )
				)
				( attribute "CHIPS_PART_NAME" "CAP"
					( Origin gPackager )
				)
				( attribute "CDS_PART_NAME" "CAP_0603LF-10UF,4V,20%,X6S,E15A"
					( Origin gPackager )
				)
				( objectStatus "C2M5" )
				( pin "a"
					( attribute "PN" "1"
						( Origin gPackager )
					)
					( objectStatus "C2M5.1" )
				)
				( pin "b"
					( attribute "PN" "2"
						( Origin gPackager )
					)
					( objectStatus "C2M5.2" )
				)
			)
			( gate "@baseboard_fab2_lib.baseboard_fab2(sch_1):page127_i44"
				( attribute "BOM_COST" "SB"
					( Origin gFrontEnd )
				)
				( attribute "CDS_LIB" "dev_discrete"
					( Origin gPackager )
				)
				( attribute "CDS_LOCATION" "C2M7"
					( Origin gPackager )
				)
				( attribute "CDS_SEC" "1"
					( Origin gPackager )
				)
				( attribute "LOCATION" "C2M7"
					( Origin gFrontEnd )
				)
				( attribute "MATERIAL" "X6S"
					( Origin gFrontEnd )
				)
				( attribute "PACK_TYPE" "0402V"
					( Origin gFrontEnd )
				)
				( attribute "PART_NUMBER" "D97712-004"
					( Origin gFrontEnd )
				)
				( attribute "PHYS_PAGE" "127"
					( Origin gFrontEnd )
				)
				( attribute "ROOM" "SB_FILTER_VM20"
					( Origin gFrontEnd )
				)
				( attribute "ROT" "0"
					( Origin gFrontEnd )
				)
				( attribute "SEC" "1"
					( Origin gFrontEnd )
				)
				( attribute "SEC_TYPE" "0402V"
					( Origin gFrontEnd )
				)
				( attribute "TOLERANCE" "10%"
					( Origin gFrontEnd )
				)
				( attribute "VALUE" "1.0UF"
					( Origin gFrontEnd )
				)
				( attribute "VER" "1"
					( Origin gFrontEnd )
				)
				( attribute "VOLTAGE" "6.3V"
					( Units "uVoltage" "V" 1.000000)
					( Origin gFrontEnd )
				)
				( attribute "XY" "(1400,-1375)"
					( Origin gFrontEnd )
				)
				( attribute "CHIPS_PART_NAME" "CAP_A"
					( Origin gPackager )
				)
				( attribute "CDS_PART_NAME" "CAP_A_0402V-1.0UF,6.3V,10%,X6SA"
					( Origin gPackager )
				)
				( objectStatus "C2M7" )
				( pin "a"
					( attribute "PN" "1"
						( Origin gPackager )
					)
					( objectStatus "C2M7.1" )
				)
				( pin "b"
					( attribute "PN" "2"
						( Origin gPackager )
					)
					( objectStatus "C2M7.2" )
				)
			)
			( gate "@baseboard_fab2_lib.baseboard_fab2(sch_1):page127_i46"
				( attribute "BOM_COST" "SB"
					( Origin gFrontEnd )
				)
				( attribute "CDS_LIB" "mstr_discrete"
					( Origin gPackager )
				)
				( attribute "CDS_LOCATION" "FB2M1"
					( Origin gPackager )
				)
				( attribute "CDS_SEC" "1"
					( Origin gPackager )
				)
				( attribute "LOCATION" "FB2M1"
					( Origin gFrontEnd )
				)
				( attribute "MATERIAL" "FB"
					( Origin gFrontEnd )
				)
				( attribute "PACK_TYPE" "SM"
					( Origin gFrontEnd )
				)
				( attribute "PART_NUMBER" "693286-027"
					( Origin gFrontEnd )
				)
				( attribute "PHYS_PAGE" "127"
					( Origin gFrontEnd )
				)
				( attribute "ROOM" "SB_FILTER_VM20"
					( Origin gFrontEnd )
				)
				( attribute "ROT" "0"
					( Origin gFrontEnd )
				)
				( attribute "SEC" "1"
					( Origin gFrontEnd )
				)
				( attribute "SEC_TYPE" "SM"
					( Origin gFrontEnd )
				)
				( attribute "VALUE" "120"
					( Origin gFrontEnd )
				)
				( attribute "VER" "1"
					( Origin gFrontEnd )
				)
				( attribute "XY" "(1150,-1175)"
					( Origin gFrontEnd )
				)
				( attribute "CHIPS_PART_NAME" "FERRITE"
					( Origin gPackager )
				)
				( attribute "CDS_PART_NAME" "FERRITE_SM-120,FB,693286-027"
					( Origin gPackager )
				)
				( objectStatus "FB2M1" )
				( pin "a"
					( attribute "PN" "1"
						( Origin gPackager )
					)
					( objectStatus "FB2M1.1" )
				)
				( pin "b"
					( attribute "PN" "2"
						( Origin gPackager )
					)
					( objectStatus "FB2M1.2" )
				)
			)
			( gate "@baseboard_fab2_lib.baseboard_fab2(sch_1):page127_i49"
				( attribute "BOM_COST" "SB"
					( Origin gFrontEnd )
				)
				( attribute "CDS_LIB" "mstr_discrete"
					( Origin gPackager )
				)
				( attribute "CDS_LOCATION" "C2M10"
					( Origin gPackager )
				)
				( attribute "CDS_SEC" "1"
					( Origin gPackager )
				)
				( attribute "LOCATION" "C2M10"
					( Origin gFrontEnd )
				)
				( attribute "MATERIAL" "X6S"
					( Origin gFrontEnd )
				)
				( attribute "PACK_TYPE" "0603LF"
					( Origin gFrontEnd )
				)
				( attribute "PART_NUMBER" "E15431-001"
					( Origin gFrontEnd )
				)
				( attribute "PHYS_PAGE" "127"
					( Origin gFrontEnd )
				)
				( attribute "ROOM" "SB_FILTER_VM26"
					( Origin gFrontEnd )
				)
				( attribute "ROT" "0"
					( Origin gFrontEnd )
				)
				( attribute "SEC" "1"
					( Origin gFrontEnd )
				)
				( attribute "SEC_TYPE" "0603LF"
					( Origin gFrontEnd )
				)
				( attribute "TOLERANCE" "20%"
					( Origin gFrontEnd )
				)
				( attribute "VALUE" "10UF"
					( Origin gFrontEnd )
				)
				( attribute "VER" "1"
					( Origin gFrontEnd )
				)
				( attribute "VOLTAGE" "4V"
					( Units "uVoltage" "V" 1.000000)
					( Origin gFrontEnd )
				)
				( attribute "XY" "(-500,-1400)"
					( Origin gFrontEnd )
				)
				( attribute "CHIPS_PART_NAME" "CAP"
					( Origin gPackager )
				)
				( attribute "CDS_PART_NAME" "CAP_0603LF-10UF,4V,20%,X6S,E15A"
					( Origin gPackager )
				)
				( objectStatus "C2M10" )
				( pin "a"
					( attribute "PN" "1"
						( Origin gPackager )
					)
					( objectStatus "C2M10.1" )
				)
				( pin "b"
					( attribute "PN" "2"
						( Origin gPackager )
					)
					( objectStatus "C2M10.2" )
				)
			)
			( gate "@baseboard_fab2_lib.baseboard_fab2(sch_1):page127_i50"
				( attribute "BOM_COST" "SB"
					( Origin gFrontEnd )
				)
				( attribute "CDS_LIB" "dev_discrete"
					( Origin gPackager )
				)
				( attribute "CDS_LOCATION" "C2M9"
					( Origin gPackager )
				)
				( attribute "CDS_SEC" "1"
					( Origin gPackager )
				)
				( attribute "LOCATION" "C2M9"
					( Origin gFrontEnd )
				)
				( attribute "MATERIAL" "X6S"
					( Origin gFrontEnd )
				)
				( attribute "PACK_TYPE" "0402V"
					( Origin gFrontEnd )
				)
				( attribute "PART_NUMBER" "D97712-004"
					( Origin gFrontEnd )
				)
				( attribute "PHYS_PAGE" "127"
					( Origin gFrontEnd )
				)
				( attribute "ROOM" "SB_FILTER_VM26"
					( Origin gFrontEnd )
				)
				( attribute "ROT" "0"
					( Origin gFrontEnd )
				)
				( attribute "SEC" "1"
					( Origin gFrontEnd )
				)
				( attribute "SEC_TYPE" "0402V"
					( Origin gFrontEnd )
				)
				( attribute "TOLERANCE" "10%"
					( Origin gFrontEnd )
				)
				( attribute "VALUE" "1.0UF"
					( Origin gFrontEnd )
				)
				( attribute "VER" "1"
					( Origin gFrontEnd )
				)
				( attribute "VOLTAGE" "6.3V"
					( Units "uVoltage" "V" 1.000000)
					( Origin gFrontEnd )
				)
				( attribute "XY" "(-1000,-1400)"
					( Origin gFrontEnd )
				)
				( attribute "CHIPS_PART_NAME" "CAP_A"
					( Origin gPackager )
				)
				( attribute "CDS_PART_NAME" "CAP_A_0402V-1.0UF,6.3V,10%,X6SA"
					( Origin gPackager )
				)
				( objectStatus "C2M9" )
				( pin "a"
					( attribute "PN" "1"
						( Origin gPackager )
					)
					( objectStatus "C2M9.1" )
				)
				( pin "b"
					( attribute "PN" "2"
						( Origin gPackager )
					)
					( objectStatus "C2M9.2" )
				)
			)
			( gate "@baseboard_fab2_lib.baseboard_fab2(sch_1):page127_i56"
				( attribute "BOM_COST" "SB"
					( Origin gFrontEnd )
				)
				( attribute "CDS_LIB" "mstr_discrete"
					( Origin gPackager )
				)
				( attribute "CDS_LOCATION" "FB3M4"
					( Origin gPackager )
				)
				( attribute "CDS_SEC" "1"
					( Origin gPackager )
				)
				( attribute "LOCATION" "FB3M4"
					( Origin gFrontEnd )
				)
				( attribute "MATERIAL" "FB"
					( Origin gFrontEnd )
				)
				( attribute "PACK_TYPE" "SM"
					( Origin gFrontEnd )
				)
				( attribute "PART_NUMBER" "693286-027"
					( Origin gFrontEnd )
				)
				( attribute "PHYS_PAGE" "127"
					( Origin gFrontEnd )
				)
				( attribute "ROOM" "SB_FILTER_ISCLK"
					( Origin gFrontEnd )
				)
				( attribute "ROT" "0"
					( Origin gFrontEnd )
				)
				( attribute "SEC" "1"
					( Origin gFrontEnd )
				)
				( attribute "SEC_TYPE" "SM"
					( Origin gFrontEnd )
				)
				( attribute "VALUE" "120"
					( Origin gFrontEnd )
				)
				( attribute "VER" "1"
					( Origin gFrontEnd )
				)
				( attribute "XY" "(1150,-3075)"
					( Origin gFrontEnd )
				)
				( attribute "CHIPS_PART_NAME" "FERRITE"
					( Origin gPackager )
				)
				( attribute "CDS_PART_NAME" "FERRITE_SM-120,FB,693286-027"
					( Origin gPackager )
				)
				( objectStatus "FB3M4" )
				( pin "a"
					( attribute "PN" "1"
						( Origin gPackager )
					)
					( objectStatus "FB3M4.1" )
				)
				( pin "b"
					( attribute "PN" "2"
						( Origin gPackager )
					)
					( objectStatus "FB3M4.2" )
				)
			)
			( gate "@baseboard_fab2_lib.baseboard_fab2(sch_1):page127_i57"
				( attribute "BOM_COST" "SB"
					( Origin gFrontEnd )
				)
				( attribute "CDS_LIB" "dev_discrete"
					( Origin gPackager )
				)
				( attribute "CDS_LOCATION" "C3M31"
					( Origin gPackager )
				)
				( attribute "CDS_SEC" "1"
					( Origin gPackager )
				)
				( attribute "LOCATION" "C3M31"
					( Origin gFrontEnd )
				)
				( attribute "MATERIAL" "X6S"
					( Origin gFrontEnd )
				)
				( attribute "PACK_TYPE" "0402V"
					( Origin gFrontEnd )
				)
				( attribute "PART_NUMBER" "D97712-004"
					( Origin gFrontEnd )
				)
				( attribute "PHYS_PAGE" "127"
					( Origin gFrontEnd )
				)
				( attribute "ROOM" "SB_FILTER_ISCLK"
					( Origin gFrontEnd )
				)
				( attribute "ROT" "2"
					( Origin gFrontEnd )
				)
				( attribute "SEC" "1"
					( Origin gFrontEnd )
				)
				( attribute "SEC_TYPE" "0402V"
					( Origin gFrontEnd )
				)
				( attribute "TOLERANCE" "10%"
					( Origin gFrontEnd )
				)
				( attribute "VALUE" "1.0UF"
					( Origin gFrontEnd )
				)
				( attribute "VER" "1"
					( Origin gFrontEnd )
				)
				( attribute "VOLTAGE" "6.3V"
					( Units "uVoltage" "V" 1.000000)
					( Origin gFrontEnd )
				)
				( attribute "XY" "(950,-3275)"
					( Origin gFrontEnd )
				)
				( attribute "CHIPS_PART_NAME" "CAP_A"
					( Origin gPackager )
				)
				( attribute "CDS_PART_NAME" "CAP_A_0402V-1.0UF,6.3V,10%,X6SA"
					( Origin gPackager )
				)
				( objectStatus "C3M31" )
				( pin "a"
					( attribute "PN" "1"
						( Origin gPackager )
					)
					( objectStatus "C3M31.1" )
				)
				( pin "b"
					( attribute "PN" "2"
						( Origin gPackager )
					)
					( objectStatus "C3M31.2" )
				)
			)
			( gate "@baseboard_fab2_lib.baseboard_fab2(sch_1):page127_i64"
				( attribute "BOM_COST" "SB"
					( Origin gFrontEnd )
				)
				( attribute "CDS_LIB" "mstr_discrete"
					( Origin gPackager )
				)
				( attribute "CDS_LOCATION" "C2N6"
					( Origin gPackager )
				)
				( attribute "CDS_SEC" "1"
					( Origin gPackager )
				)
				( attribute "LOCATION" "C2N6"
					( Origin gFrontEnd )
				)
				( attribute "MATERIAL" "X6S"
					( Origin gFrontEnd )
				)
				( attribute "PACK_TYPE" "0603LF"
					( Origin gFrontEnd )
				)
				( attribute "PART_NUMBER" "E15431-001"
					( Origin gFrontEnd )
				)
				( attribute "PHYS_PAGE" "127"
					( Origin gFrontEnd )
				)
				( attribute "ROOM" "SB_FILTER_KR_PLL"
					( Origin gFrontEnd )
				)
				( attribute "ROT" "0"
					( Origin gFrontEnd )
				)
				( attribute "SEC" "1"
					( Origin gFrontEnd )
				)
				( attribute "SEC_TYPE" "0603LF"
					( Origin gFrontEnd )
				)
				( attribute "TOLERANCE" "20%"
					( Origin gFrontEnd )
				)
				( attribute "VALUE" "10UF"
					( Origin gFrontEnd )
				)
				( attribute "VER" "1"
					( Origin gFrontEnd )
				)
				( attribute "VOLTAGE" "4V"
					( Units "uVoltage" "V" 1.000000)
					( Origin gFrontEnd )
				)
				( attribute "XY" "(-500,-3300)"
					( Origin gFrontEnd )
				)
				( attribute "CHIPS_PART_NAME" "CAP"
					( Origin gPackager )
				)
				( attribute "CDS_PART_NAME" "CAP_0603LF-10UF,4V,20%,X6S,E15A"
					( Origin gPackager )
				)
				( objectStatus "C2N6" )
				( pin "a"
					( attribute "PN" "1"
						( Origin gPackager )
					)
					( objectStatus "C2N6.1" )
				)
				( pin "b"
					( attribute "PN" "2"
						( Origin gPackager )
					)
					( objectStatus "C2N6.2" )
				)
			)
			( gate "@baseboard_fab2_lib.baseboard_fab2(sch_1):page127_i65"
				( attribute "BOM_COST" "SB"
					( Origin gFrontEnd )
				)
				( attribute "CDS_LIB" "dev_discrete"
					( Origin gPackager )
				)
				( attribute "CDS_LOCATION" "C2N5"
					( Origin gPackager )
				)
				( attribute "CDS_SEC" "1"
					( Origin gPackager )
				)
				( attribute "LOCATION" "C2N5"
					( Origin gFrontEnd )
				)
				( attribute "MATERIAL" "X6S"
					( Origin gFrontEnd )
				)
				( attribute "PACK_TYPE" "0402V"
					( Origin gFrontEnd )
				)
				( attribute "PART_NUMBER" "D97712-004"
					( Origin gFrontEnd )
				)
				( attribute "PHYS_PAGE" "127"
					( Origin gFrontEnd )
				)
				( attribute "ROOM" "SB_FILTER_KR_PLL"
					( Origin gFrontEnd )
				)
				( attribute "ROT" "0"
					( Origin gFrontEnd )
				)
				( attribute "SEC" "1"
					( Origin gFrontEnd )
				)
				( attribute "SEC_TYPE" "0402V"
					( Origin gFrontEnd )
				)
				( attribute "TOLERANCE" "10%"
					( Origin gFrontEnd )
				)
				( attribute "VALUE" "1.0UF"
					( Origin gFrontEnd )
				)
				( attribute "VER" "1"
					( Origin gFrontEnd )
				)
				( attribute "VOLTAGE" "6.3V"
					( Units "uVoltage" "V" 1.000000)
					( Origin gFrontEnd )
				)
				( attribute "XY" "(-1000,-3300)"
					( Origin gFrontEnd )
				)
				( attribute "CHIPS_PART_NAME" "CAP_A"
					( Origin gPackager )
				)
				( attribute "CDS_PART_NAME" "CAP_A_0402V-1.0UF,6.3V,10%,X6SA"
					( Origin gPackager )
				)
				( objectStatus "C2N5" )
				( pin "a"
					( attribute "PN" "1"
						( Origin gPackager )
					)
					( objectStatus "C2N5.1" )
				)
				( pin "b"
					( attribute "PN" "2"
						( Origin gPackager )
					)
					( objectStatus "C2N5.2" )
				)
			)
			( gate "@baseboard_fab2_lib.baseboard_fab2(sch_1):page127_i69"
				( attribute "BOM_COST" "SB"
					( Origin gFrontEnd )
				)
				( attribute "CDS_LIB" "mstr_discrete"
					( Origin gPackager )
				)
				( attribute "CDS_LOCATION" "FB2M2"
					( Origin gPackager )
				)
				( attribute "CDS_SEC" "1"
					( Origin gPackager )
				)
				( attribute "LOCATION" "FB2M2"
					( Origin gFrontEnd )
				)
				( attribute "MATERIAL" "FB"
					( Origin gFrontEnd )
				)
				( attribute "PACK_TYPE" "SM"
					( Origin gFrontEnd )
				)
				( attribute "PART_NUMBER" "693286-027"
					( Origin gFrontEnd )
				)
				( attribute "PHYS_PAGE" "127"
					( Origin gFrontEnd )
				)
				( attribute "ROOM" "SB_FILTER_VM26"
					( Origin gFrontEnd )
				)
				( attribute "ROT" "0"
					( Origin gFrontEnd )
				)
				( attribute "SEC" "1"
					( Origin gFrontEnd )
				)
				( attribute "SEC_TYPE" "SM"
					( Origin gFrontEnd )
				)
				( attribute "VALUE" "120"
					( Origin gFrontEnd )
				)
				( attribute "VER" "1"
					( Origin gFrontEnd )
				)
				( attribute "XY" "(-1225,-1200)"
					( Origin gFrontEnd )
				)
				( attribute "CHIPS_PART_NAME" "FERRITE"
					( Origin gPackager )
				)
				( attribute "CDS_PART_NAME" "FERRITE_SM-120,FB,693286-027"
					( Origin gPackager )
				)
				( objectStatus "FB2M2" )
				( pin "a"
					( attribute "PN" "1"
						( Origin gPackager )
					)
					( objectStatus "FB2M2.1" )
				)
				( pin "b"
					( attribute "PN" "2"
						( Origin gPackager )
					)
					( objectStatus "FB2M2.2" )
				)
			)
			( gate "@baseboard_fab2_lib.baseboard_fab2(sch_1):page127_i71"
				( attribute "BOM_COST" "SB"
					( Origin gFrontEnd )
				)
				( attribute "CDS_LIB" "mstr_discrete"
					( Origin gPackager )
				)
				( attribute "CDS_LOCATION" "L2M1"
					( Origin gPackager )
				)
				( attribute "CDS_SEC" "1"
					( Origin gPackager )
				)
				( attribute "LOCATION" "L2M1"
					( Origin gFrontEnd )
				)
				( attribute "MATERIAL" "IND"
					( Origin gFrontEnd )
				)
				( attribute "PACK_TYPE" "SMT"
					( Origin gFrontEnd )
				)
				( attribute "PART_NUMBER" "721891-082"
					( Origin gFrontEnd )
				)
				( attribute "PHYS_PAGE" "127"
					( Origin gFrontEnd )
				)
				( attribute "ROOM" "SB_FILTER_KR_PLL"
					( Origin gFrontEnd )
				)
				( attribute "ROT" "0"
					( Origin gFrontEnd )
				)
				( attribute "SEC" "1"
					( Origin gFrontEnd )
				)
				( attribute "SEC_TYPE" "SMT"
					( Origin gFrontEnd )
				)
				( attribute "VALUE" "0.022UH"
					( Origin gFrontEnd )
				)
				( attribute "VER" "1"
					( Origin gFrontEnd )
				)
				( attribute "XY" "(-1250,-3100)"
					( Origin gFrontEnd )
				)
				( attribute "CHIPS_PART_NAME" "INDUCTOR"
					( Origin gPackager )
				)
				( attribute "CDS_PART_NAME" "INDUCTOR_SMT-0.022UH,IND,72189A"
					( Origin gPackager )
				)
				( objectStatus "L2M1" )
				( pin "ina"
					( attribute "PN" "1"
						( Origin gPackager )
					)
					( objectStatus "L2M1.1" )
				)
				( pin "inb"
					( attribute "PN" "2"
						( Origin gPackager )
					)
					( objectStatus "L2M1.2" )
				)
			)
			( gate "@baseboard_fab2_lib.baseboard_fab2(sch_1):page127_i74"
				( attribute "BOM_COST" "SB"
					( Origin gFrontEnd )
				)
				( attribute "CDS_LIB" "dev_discrete"
					( Origin gPackager )
				)
				( attribute "CDS_LOCATION" "C2M8"
					( Origin gPackager )
				)
				( attribute "CDS_SEC" "1"
					( Origin gPackager )
				)
				( attribute "LOCATION" "C2M8"
					( Origin gFrontEnd )
				)
				( attribute "MATERIAL" "X6S"
					( Origin gFrontEnd )
				)
				( attribute "PACK_TYPE" "0402V"
					( Origin gFrontEnd )
				)
				( attribute "PART_NUMBER" "D97712-004"
					( Origin gFrontEnd )
				)
				( attribute "PHYS_PAGE" "127"
					( Origin gFrontEnd )
				)
				( attribute "ROOM" "SB_FILTER_VM26"
					( Origin gFrontEnd )
				)
				( attribute "ROT" "2"
					( Origin gFrontEnd )
				)
				( attribute "SEC" "1"
					( Origin gFrontEnd )
				)
				( attribute "SEC_TYPE" "0402V"
					( Origin gFrontEnd )
				)
				( attribute "TOLERANCE" "10%"
					( Origin gFrontEnd )
				)
				( attribute "VALUE" "1.0UF"
					( Origin gFrontEnd )
				)
				( attribute "VER" "1"
					( Origin gFrontEnd )
				)
				( attribute "VOLTAGE" "6.3V"
					( Units "uVoltage" "V" 1.000000)
					( Origin gFrontEnd )
				)
				( attribute "XY" "(-1450,-1400)"
					( Origin gFrontEnd )
				)
				( attribute "CHIPS_PART_NAME" "CAP_A"
					( Origin gPackager )
				)
				( attribute "CDS_PART_NAME" "CAP_A_0402V-1.0UF,6.3V,10%,X6SA"
					( Origin gPackager )
				)
				( objectStatus "C2M8" )
				( pin "a"
					( attribute "PN" "1"
						( Origin gPackager )
					)
					( objectStatus "C2M8.1" )
				)
				( pin "b"
					( attribute "PN" "2"
						( Origin gPackager )
					)
					( objectStatus "C2M8.2" )
				)
			)
			( gate "@baseboard_fab2_lib.baseboard_fab2(sch_1):page127_i76"
				( attribute "BOM_COST" "SB"
					( Origin gFrontEnd )
				)
				( attribute "CDS_LIB" "dev_discrete"
					( Origin gPackager )
				)
				( attribute "CDS_LOCATION" "C2M6"
					( Origin gPackager )
				)
				( attribute "CDS_SEC" "1"
					( Origin gPackager )
				)
				( attribute "LOCATION" "C2M6"
					( Origin gFrontEnd )
				)
				( attribute "MATERIAL" "X6S"
					( Origin gFrontEnd )
				)
				( attribute "PACK_TYPE" "0402V"
					( Origin gFrontEnd )
				)
				( attribute "PART_NUMBER" "D97712-004"
					( Origin gFrontEnd )
				)
				( attribute "PHYS_PAGE" "127"
					( Origin gFrontEnd )
				)
				( attribute "ROOM" "SB_FILTER_VM20"
					( Origin gFrontEnd )
				)
				( attribute "ROT" "2"
					( Origin gFrontEnd )
				)
				( attribute "SEC" "1"
					( Origin gFrontEnd )
				)
				( attribute "SEC_TYPE" "0402V"
					( Origin gFrontEnd )
				)
				( attribute "TOLERANCE" "10%"
					( Origin gFrontEnd )
				)
				( attribute "VALUE" "1.0UF"
					( Origin gFrontEnd )
				)
				( attribute "VER" "1"
					( Origin gFrontEnd )
				)
				( attribute "VOLTAGE" "6.3V"
					( Units "uVoltage" "V" 1.000000)
					( Origin gFrontEnd )
				)
				( attribute "XY" "(950,-1375)"
					( Origin gFrontEnd )
				)
				( attribute "CHIPS_PART_NAME" "CAP_A"
					( Origin gPackager )
				)
				( attribute "CDS_PART_NAME" "CAP_A_0402V-1.0UF,6.3V,10%,X6SA"
					( Origin gPackager )
				)
				( objectStatus "C2M6" )
				( pin "a"
					( attribute "PN" "1"
						( Origin gPackager )
					)
					( objectStatus "C2M6.1" )
				)
				( pin "b"
					( attribute "PN" "2"
						( Origin gPackager )
					)
					( objectStatus "C2M6.2" )
				)
			)
			( gate "@baseboard_fab2_lib.baseboard_fab2(sch_1):page127_i78"
				( attribute "BOM_COST" "SB"
					( Origin gFrontEnd )
				)
				( attribute "CDS_LIB" "dev_discrete"
					( Origin gPackager )
				)
				( attribute "CDS_LOCATION" "C2M25"
					( Origin gPackager )
				)
				( attribute "CDS_SEC" "1"
					( Origin gPackager )
				)
				( attribute "LOCATION" "C2M25"
					( Origin gFrontEnd )
				)
				( attribute "MATERIAL" "X6S"
					( Origin gFrontEnd )
				)
				( attribute "PACK_TYPE" "0402V"
					( Origin gFrontEnd )
				)
				( attribute "PART_NUMBER" "D97712-004"
					( Origin gFrontEnd )
				)
				( attribute "PHYS_PAGE" "127"
					( Origin gFrontEnd )
				)
				( attribute "ROOM" "SB_FILTER_KR_PLL"
					( Origin gFrontEnd )
				)
				( attribute "ROT" "2"
					( Origin gFrontEnd )
				)
				( attribute "SEC" "1"
					( Origin gFrontEnd )
				)
				( attribute "SEC_TYPE" "0402V"
					( Origin gFrontEnd )
				)
				( attribute "TOLERANCE" "10%"
					( Origin gFrontEnd )
				)
				( attribute "VALUE" "1.0UF"
					( Origin gFrontEnd )
				)
				( attribute "VER" "1"
					( Origin gFrontEnd )
				)
				( attribute "VOLTAGE" "6.3V"
					( Units "uVoltage" "V" 1.000000)
					( Origin gFrontEnd )
				)
				( attribute "XY" "(-1450,-3300)"
					( Origin gFrontEnd )
				)
				( attribute "CHIPS_PART_NAME" "CAP_A"
					( Origin gPackager )
				)
				( attribute "CDS_PART_NAME" "CAP_A_0402V-1.0UF,6.3V,10%,X6SA"
					( Origin gPackager )
				)
				( objectStatus "C2M25" )
				( pin "a"
					( attribute "PN" "1"
						( Origin gPackager )
					)
					( objectStatus "C2M25.1" )
				)
				( pin "b"
					( attribute "PN" "2"
						( Origin gPackager )
					)
					( objectStatus "C2M25.2" )
				)
			)
			( gate "@baseboard_fab2_lib.baseboard_fab2(sch_1):page127_i80"
				( attribute "BOM_COST" "SB"
					( Origin gFrontEnd )
				)
				( attribute "CDS_LIB" "dev_discrete"
					( Origin gPackager )
				)
				( attribute "CDS_LOCATION" "C3M29"
					( Origin gPackager )
				)
				( attribute "CDS_SEC" "1"
					( Origin gPackager )
				)
				( attribute "LOCATION" "C3M29"
					( Origin gFrontEnd )
				)
				( attribute "MATERIAL" "X6S"
					( Origin gFrontEnd )
				)
				( attribute "PACK_TYPE" "0402V"
					( Origin gFrontEnd )
				)
				( attribute "PART_NUMBER" "D97712-004"
					( Origin gFrontEnd )
				)
				( attribute "PHYS_PAGE" "127"
					( Origin gFrontEnd )
				)
				( attribute "ROOM" "SB_FILTER_ISCLK"
					( Origin gFrontEnd )
				)
				( attribute "ROT" "0"
					( Origin gFrontEnd )
				)
				( attribute "SEC" "1"
					( Origin gFrontEnd )
				)
				( attribute "SEC_TYPE" "0402V"
					( Origin gFrontEnd )
				)
				( attribute "TOLERANCE" "10%"
					( Origin gFrontEnd )
				)
				( attribute "VALUE" "1.0UF"
					( Origin gFrontEnd )
				)
				( attribute "VER" "1"
					( Origin gFrontEnd )
				)
				( attribute "VOLTAGE" "6.3V"
					( Units "uVoltage" "V" 1.000000)
					( Origin gFrontEnd )
				)
				( attribute "XY" "(1400,-3275)"
					( Origin gFrontEnd )
				)
				( attribute "CHIPS_PART_NAME" "CAP_A"
					( Origin gPackager )
				)
				( attribute "CDS_PART_NAME" "CAP_A_0402V-1.0UF,6.3V,10%,X6SA"
					( Origin gPackager )
				)
				( objectStatus "C3M29" )
				( pin "a"
					( attribute "PN" "1"
						( Origin gPackager )
					)
					( objectStatus "C3M29.1" )
				)
				( pin "b"
					( attribute "PN" "2"
						( Origin gPackager )
					)
					( objectStatus "C3M29.2" )
				)
			)
			( gate "@baseboard_fab2_lib.baseboard_fab2(sch_1):page127_i81"
				( attribute "BOM_COST" "SB"
					( Origin gFrontEnd )
				)
				( attribute "CDS_LIB" "mstr_discrete"
					( Origin gPackager )
				)
				( attribute "CDS_LOCATION" "C3M24"
					( Origin gPackager )
				)
				( attribute "CDS_SEC" "1"
					( Origin gPackager )
				)
				( attribute "LOCATION" "C3M24"
					( Origin gFrontEnd )
				)
				( attribute "MATERIAL" "X6S"
					( Origin gFrontEnd )
				)
				( attribute "PACK_TYPE" "0603LF"
					( Origin gFrontEnd )
				)
				( attribute "PART_NUMBER" "E15431-001"
					( Origin gFrontEnd )
				)
				( attribute "PHYS_PAGE" "127"
					( Origin gFrontEnd )
				)
				( attribute "ROOM" "SB_FILTER_ISCLK"
					( Origin gFrontEnd )
				)
				( attribute "ROT" "0"
					( Origin gFrontEnd )
				)
				( attribute "SEC" "1"
					( Origin gFrontEnd )
				)
				( attribute "SEC_TYPE" "0603LF"
					( Origin gFrontEnd )
				)
				( attribute "TOLERANCE" "20%"
					( Origin gFrontEnd )
				)
				( attribute "VALUE" "10UF"
					( Origin gFrontEnd )
				)
				( attribute "VER" "1"
					( Origin gFrontEnd )
				)
				( attribute "VOLTAGE" "4V"
					( Units "uVoltage" "V" 1.000000)
					( Origin gFrontEnd )
				)
				( attribute "XY" "(1700,-3275)"
					( Origin gFrontEnd )
				)
				( attribute "CHIPS_PART_NAME" "CAP"
					( Origin gPackager )
				)
				( attribute "CDS_PART_NAME" "CAP_0603LF-10UF,4V,20%,X6S,E15A"
					( Origin gPackager )
				)
				( objectStatus "C3M24" )
				( pin "a"
					( attribute "PN" "1"
						( Origin gPackager )
					)
					( objectStatus "C3M24.1" )
				)
				( pin "b"
					( attribute "PN" "2"
						( Origin gPackager )
					)
					( objectStatus "C3M24.2" )
				)
			)
			( gate "@baseboard_fab2_lib.baseboard_fab2(sch_1):page127_i82"
				( attribute "BOM_COST" "SB"
					( Origin gFrontEnd )
				)
				( attribute "CDS_LIB" "mstr_discrete"
					( Origin gPackager )
				)
				( attribute "CDS_LOCATION" "C3M23"
					( Origin gPackager )
				)
				( attribute "CDS_SEC" "1"
					( Origin gPackager )
				)
				( attribute "LOCATION" "C3M23"
					( Origin gFrontEnd )
				)
				( attribute "MATERIAL" "X6S"
					( Origin gFrontEnd )
				)
				( attribute "PACK_TYPE" "0603LF"
					( Origin gFrontEnd )
				)
				( attribute "PART_NUMBER" "E15431-001"
					( Origin gFrontEnd )
				)
				( attribute "PHYS_PAGE" "127"
					( Origin gFrontEnd )
				)
				( attribute "ROOM" "SB_FILTER_XTAL"
					( Origin gFrontEnd )
				)
				( attribute "ROT" "0"
					( Origin gFrontEnd )
				)
				( attribute "SEC" "1"
					( Origin gFrontEnd )
				)
				( attribute "SEC_TYPE" "0603LF"
					( Origin gFrontEnd )
				)
				( attribute "TOLERANCE" "20%"
					( Origin gFrontEnd )
				)
				( attribute "VALUE" "10UF"
					( Origin gFrontEnd )
				)
				( attribute "VER" "1"
					( Origin gFrontEnd )
				)
				( attribute "VOLTAGE" "4V"
					( Units "uVoltage" "V" 1.000000)
					( Origin gFrontEnd )
				)
				( attribute "XY" "(-2550,-3600)"
					( Origin gFrontEnd )
				)
				( attribute "CHIPS_PART_NAME" "CAP"
					( Origin gPackager )
				)
				( attribute "CDS_PART_NAME" "CAP_0603LF-10UF,4V,20%,X6S,E15A"
					( Origin gPackager )
				)
				( objectStatus "C3M23" )
				( pin "a"
					( attribute "PN" "1"
						( Origin gPackager )
					)
					( objectStatus "C3M23.1" )
				)
				( pin "b"
					( attribute "PN" "2"
						( Origin gPackager )
					)
					( objectStatus "C3M23.2" )
				)
			)
			( gate "@baseboard_fab2_lib.baseboard_fab2(sch_1):page127_i83"
				( attribute "BOM_COST" "SB"
					( Origin gFrontEnd )
				)
				( attribute "CDS_LIB" "dev_discrete"
					( Origin gPackager )
				)
				( attribute "CDS_LOCATION" "C3M27"
					( Origin gPackager )
				)
				( attribute "CDS_SEC" "1"
					( Origin gPackager )
				)
				( attribute "LOCATION" "C3M27"
					( Origin gFrontEnd )
				)
				( attribute "MATERIAL" "X6S"
					( Origin gFrontEnd )
				)
				( attribute "PACK_TYPE" "0402V"
					( Origin gFrontEnd )
				)
				( attribute "PART_NUMBER" "D97712-004"
					( Origin gFrontEnd )
				)
				( attribute "PHYS_PAGE" "127"
					( Origin gFrontEnd )
				)
				( attribute "ROOM" "SB_FILTER_XTAL"
					( Origin gFrontEnd )
				)
				( attribute "ROT" "0"
					( Origin gFrontEnd )
				)
				( attribute "SEC" "1"
					( Origin gFrontEnd )
				)
				( attribute "SEC_TYPE" "0402V"
					( Origin gFrontEnd )
				)
				( attribute "TOLERANCE" "10%"
					( Origin gFrontEnd )
				)
				( attribute "VALUE" "1.0UF"
					( Origin gFrontEnd )
				)
				( attribute "VER" "1"
					( Origin gFrontEnd )
				)
				( attribute "VOLTAGE" "6.3V"
					( Units "uVoltage" "V" 1.000000)
					( Origin gFrontEnd )
				)
				( attribute "XY" "(-3400,-3550)"
					( Origin gFrontEnd )
				)
				( attribute "CHIPS_PART_NAME" "CAP_A"
					( Origin gPackager )
				)
				( attribute "CDS_PART_NAME" "CAP_A_0402V-1.0UF,6.3V,10%,X6SA"
					( Origin gPackager )
				)
				( objectStatus "C3M27" )
				( pin "a"
					( attribute "PN" "1"
						( Origin gPackager )
					)
					( objectStatus "C3M27.1" )
				)
				( pin "b"
					( attribute "PN" "2"
						( Origin gPackager )
					)
					( objectStatus "C3M27.2" )
				)
			)
			( gate "@baseboard_fab2_lib.baseboard_fab2(sch_1):page127_i84"
				( attribute "BOM_COST" "SB"
					( Origin gFrontEnd )
				)
				( attribute "CDS_LIB" "dev_discrete"
					( Origin gPackager )
				)
				( attribute "CDS_LOCATION" "C3M20"
					( Origin gPackager )
				)
				( attribute "CDS_SEC" "1"
					( Origin gPackager )
				)
				( attribute "LOCATION" "C3M20"
					( Origin gFrontEnd )
				)
				( attribute "MATERIAL" "X6S"
					( Origin gFrontEnd )
				)
				( attribute "PACK_TYPE" "0402V"
					( Origin gFrontEnd )
				)
				( attribute "PART_NUMBER" "D97712-004"
					( Origin gFrontEnd )
				)
				( attribute "PHYS_PAGE" "127"
					( Origin gFrontEnd )
				)
				( attribute "ROOM" "SB_FILTER_PLL1"
					( Origin gFrontEnd )
				)
				( attribute "ROT" "0"
					( Origin gFrontEnd )
				)
				( attribute "SEC" "1"
					( Origin gFrontEnd )
				)
				( attribute "SEC_TYPE" "0402V"
					( Origin gFrontEnd )
				)
				( attribute "TOLERANCE" "10%"
					( Origin gFrontEnd )
				)
				( attribute "VALUE" "1.0UF"
					( Origin gFrontEnd )
				)
				( attribute "VER" "1"
					( Origin gFrontEnd )
				)
				( attribute "VOLTAGE" "6.3V"
					( Units "uVoltage" "V" 1.000000)
					( Origin gFrontEnd )
				)
				( attribute "XY" "(-3425,-2250)"
					( Origin gFrontEnd )
				)
				( attribute "CHIPS_PART_NAME" "CAP_A"
					( Origin gPackager )
				)
				( attribute "CDS_PART_NAME" "CAP_A_0402V-1.0UF,6.3V,10%,X6SA"
					( Origin gPackager )
				)
				( objectStatus "C3M20" )
				( pin "a"
					( attribute "PN" "1"
						( Origin gPackager )
					)
					( objectStatus "C3M20.1" )
				)
				( pin "b"
					( attribute "PN" "2"
						( Origin gPackager )
					)
					( objectStatus "C3M20.2" )
				)
			)
			( gate "@baseboard_fab2_lib.baseboard_fab2(sch_1):page127_i85"
				( attribute "BOM_COST" "SB"
					( Origin gFrontEnd )
				)
				( attribute "CDS_LIB" "mstr_discrete"
					( Origin gPackager )
				)
				( attribute "CDS_LOCATION" "C3M18"
					( Origin gPackager )
				)
				( attribute "CDS_SEC" "1"
					( Origin gPackager )
				)
				( attribute "LOCATION" "C3M18"
					( Origin gFrontEnd )
				)
				( attribute "MATERIAL" "X6S"
					( Origin gFrontEnd )
				)
				( attribute "PACK_TYPE" "0603LF"
					( Origin gFrontEnd )
				)
				( attribute "PART_NUMBER" "E15431-001"
					( Origin gFrontEnd )
				)
				( attribute "PHYS_PAGE" "127"
					( Origin gFrontEnd )
				)
				( attribute "ROOM" "SB_FILTER_PLL1"
					( Origin gFrontEnd )
				)
				( attribute "ROT" "0"
					( Origin gFrontEnd )
				)
				( attribute "SEC" "1"
					( Origin gFrontEnd )
				)
				( attribute "SEC_TYPE" "0603LF"
					( Origin gFrontEnd )
				)
				( attribute "TOLERANCE" "20%"
					( Origin gFrontEnd )
				)
				( attribute "VALUE" "10UF"
					( Origin gFrontEnd )
				)
				( attribute "VER" "1"
					( Origin gFrontEnd )
				)
				( attribute "VOLTAGE" "4V"
					( Units "uVoltage" "V" 1.000000)
					( Origin gFrontEnd )
				)
				( attribute "XY" "(-2575,-2325)"
					( Origin gFrontEnd )
				)
				( attribute "CHIPS_PART_NAME" "CAP"
					( Origin gPackager )
				)
				( attribute "CDS_PART_NAME" "CAP_0603LF-10UF,4V,20%,X6S,E15A"
					( Origin gPackager )
				)
				( objectStatus "C3M18" )
				( pin "a"
					( attribute "PN" "1"
						( Origin gPackager )
					)
					( objectStatus "C3M18.1" )
				)
				( pin "b"
					( attribute "PN" "2"
						( Origin gPackager )
					)
					( objectStatus "C3M18.2" )
				)
			)
			( gate "@baseboard_fab2_lib.baseboard_fab2(sch_1):page127_i86"
				( attribute "BOM_COST" "SB"
					( Origin gFrontEnd )
				)
				( attribute "CDS_LIB" "mstr_discrete"
					( Origin gPackager )
				)
				( attribute "CDS_LOCATION" "C3M17"
					( Origin gPackager )
				)
				( attribute "CDS_SEC" "1"
					( Origin gPackager )
				)
				( attribute "LOCATION" "C3M17"
					( Origin gFrontEnd )
				)
				( attribute "MATERIAL" "X6S"
					( Origin gFrontEnd )
				)
				( attribute "PACK_TYPE" "0603LF"
					( Origin gFrontEnd )
				)
				( attribute "PART_NUMBER" "E15431-001"
					( Origin gFrontEnd )
				)
				( attribute "PHYS_PAGE" "127"
					( Origin gFrontEnd )
				)
				( attribute "ROOM" "SB_FILTER_PLL0"
					( Origin gFrontEnd )
				)
				( attribute "ROT" "0"
					( Origin gFrontEnd )
				)
				( attribute "SEC" "1"
					( Origin gFrontEnd )
				)
				( attribute "SEC_TYPE" "0603LF"
					( Origin gFrontEnd )
				)
				( attribute "TOLERANCE" "20%"
					( Origin gFrontEnd )
				)
				( attribute "VALUE" "10UF"
					( Origin gFrontEnd )
				)
				( attribute "VER" "1"
					( Origin gFrontEnd )
				)
				( attribute "VOLTAGE" "4V"
					( Units "uVoltage" "V" 1.000000)
					( Origin gFrontEnd )
				)
				( attribute "XY" "(-2575,-1075)"
					( Origin gFrontEnd )
				)
				( attribute "CHIPS_PART_NAME" "CAP"
					( Origin gPackager )
				)
				( attribute "CDS_PART_NAME" "CAP_0603LF-10UF,4V,20%,X6S,E15A"
					( Origin gPackager )
				)
				( objectStatus "C3M17" )
				( pin "a"
					( attribute "PN" "1"
						( Origin gPackager )
					)
					( objectStatus "C3M17.1" )
				)
				( pin "b"
					( attribute "PN" "2"
						( Origin gPackager )
					)
					( objectStatus "C3M17.2" )
				)
			)
			( gate "@baseboard_fab2_lib.baseboard_fab2(sch_1):page127_i87"
				( attribute "BOM_COST" "SB"
					( Origin gFrontEnd )
				)
				( attribute "CDS_LIB" "dev_discrete"
					( Origin gPackager )
				)
				( attribute "CDS_LOCATION" "C3M19"
					( Origin gPackager )
				)
				( attribute "CDS_SEC" "1"
					( Origin gPackager )
				)
				( attribute "LOCATION" "C3M19"
					( Origin gFrontEnd )
				)
				( attribute "MATERIAL" "X6S"
					( Origin gFrontEnd )
				)
				( attribute "PACK_TYPE" "0402V"
					( Origin gFrontEnd )
				)
				( attribute "PART_NUMBER" "D97712-004"
					( Origin gFrontEnd )
				)
				( attribute "PHYS_PAGE" "127"
					( Origin gFrontEnd )
				)
				( attribute "ROOM" "SB_FILTER_PLL0"
					( Origin gFrontEnd )
				)
				( attribute "ROT" "0"
					( Origin gFrontEnd )
				)
				( attribute "SEC" "1"
					( Origin gFrontEnd )
				)
				( attribute "SEC_TYPE" "0402V"
					( Origin gFrontEnd )
				)
				( attribute "TOLERANCE" "10%"
					( Origin gFrontEnd )
				)
				( attribute "VALUE" "1.0UF"
					( Origin gFrontEnd )
				)
				( attribute "VER" "1"
					( Origin gFrontEnd )
				)
				( attribute "VOLTAGE" "6.3V"
					( Units "uVoltage" "V" 1.000000)
					( Origin gFrontEnd )
				)
				( attribute "XY" "(-3450,-1050)"
					( Origin gFrontEnd )
				)
				( attribute "CHIPS_PART_NAME" "CAP_A"
					( Origin gPackager )
				)
				( attribute "CDS_PART_NAME" "CAP_A_0402V-1.0UF,6.3V,10%,X6SA"
					( Origin gPackager )
				)
				( objectStatus "C3M19" )
				( pin "a"
					( attribute "PN" "1"
						( Origin gPackager )
					)
					( objectStatus "C3M19.1" )
				)
				( pin "b"
					( attribute "PN" "2"
						( Origin gPackager )
					)
					( objectStatus "C3M19.2" )
				)
			)
			( gate "@baseboard_fab2_lib.baseboard_fab2(sch_1):page129_i35"
				( attribute "BOM_COST" "SB"
					( Origin gFrontEnd )
				)
				( attribute "CDS_LIB" "mstr_discrete"
					( Origin gPackager )
				)
				( attribute "CDS_LOCATION" "C7B25"
					( Origin gPackager )
				)
				( attribute "CDS_SEC" "1"
					( Origin gPackager )
				)
				( attribute "LOCATION" "C7B25"
					( Origin gFrontEnd )
				)
				( attribute "MATERIAL" "X7R"
					( Origin gFrontEnd )
				)
				( attribute "PACK_TYPE" "0402"
					( Origin gFrontEnd )
				)
				( attribute "PART_NUMBER" "A36096-155"
					( Origin gFrontEnd )
				)
				( attribute "PHYS_PAGE" "129"
					( Origin gFrontEnd )
				)
				( attribute "ROOM" "DMI"
					( Origin gFrontEnd )
				)
				( attribute "ROT" "1"
					( Origin gFrontEnd )
				)
				( attribute "SEC" "1"
					( Origin gPackager )
				)
				( attribute "TOLERANCE" "10%"
					( Origin gFrontEnd )
				)
				( attribute "VALUE" "0.22UF"
					( Origin gFrontEnd )
				)
				( attribute "VER" "1"
					( Origin gFrontEnd )
				)
				( attribute "VOLTAGE" "16V"
					( Units "uVoltage" "V" 1.000000)
					( Origin gFrontEnd )
				)
				( attribute "XY" "(-3650,4925)"
					( Origin gFrontEnd )
				)
				( attribute "CHIPS_PART_NAME" "CAP"
					( Origin gPackager )
				)
				( attribute "CDS_PART_NAME" "CAP_0402-0.22UF,16V,10%,X7R,A3A"
					( Origin gPackager )
				)
				( objectStatus "C7B25" )
				( pin "a"
					( attribute "PN" "1"
						( Origin gPackager )
					)
					( objectStatus "C7B25.1" )
				)
				( pin "b"
					( attribute "PN" "2"
						( Origin gPackager )
					)
					( objectStatus "C7B25.2" )
				)
			)
			( gate "@baseboard_fab2_lib.baseboard_fab2(sch_1):page129_i69"
				( attribute "BOM_COST" "SB"
					( Origin gFrontEnd )
				)
				( attribute "CDS_LIB" "mstr_discrete"
					( Origin gPackager )
				)
				( attribute "CDS_LOCATION" "C7B27"
					( Origin gPackager )
				)
				( attribute "CDS_SEC" "1"
					( Origin gPackager )
				)
				( attribute "LOCATION" "C7B27"
					( Origin gFrontEnd )
				)
				( attribute "MATERIAL" "X7R"
					( Origin gFrontEnd )
				)
				( attribute "PACK_TYPE" "0402"
					( Origin gFrontEnd )
				)
				( attribute "PART_NUMBER" "A36096-155"
					( Origin gFrontEnd )
				)
				( attribute "PHYS_PAGE" "129"
					( Origin gFrontEnd )
				)
				( attribute "ROOM" "DMI"
					( Origin gFrontEnd )
				)
				( attribute "ROT" "1"
					( Origin gFrontEnd )
				)
				( attribute "SEC" "1"
					( Origin gPackager )
				)
				( attribute "TOLERANCE" "10%"
					( Origin gFrontEnd )
				)
				( attribute "VALUE" "0.22UF"
					( Origin gFrontEnd )
				)
				( attribute "VER" "1"
					( Origin gFrontEnd )
				)
				( attribute "VOLTAGE" "16V"
					( Units "uVoltage" "V" 1.000000)
					( Origin gFrontEnd )
				)
				( attribute "XY" "(-3300,4725)"
					( Origin gFrontEnd )
				)
				( attribute "CHIPS_PART_NAME" "CAP"
					( Origin gPackager )
				)
				( attribute "CDS_PART_NAME" "CAP_0402-0.22UF,16V,10%,X7R,A3A"
					( Origin gPackager )
				)
				( objectStatus "C7B27" )
				( pin "a"
					( attribute "PN" "1"
						( Origin gPackager )
					)
					( objectStatus "C7B27.1" )
				)
				( pin "b"
					( attribute "PN" "2"
						( Origin gPackager )
					)
					( objectStatus "C7B27.2" )
				)
			)
			( gate "@baseboard_fab2_lib.baseboard_fab2(sch_1):page129_i70"
				( attribute "BOM_COST" "SB"
					( Origin gFrontEnd )
				)
				( attribute "CDS_LIB" "mstr_discrete"
					( Origin gPackager )
				)
				( attribute "CDS_LOCATION" "C7B28"
					( Origin gPackager )
				)
				( attribute "CDS_SEC" "1"
					( Origin gPackager )
				)
				( attribute "LOCATION" "C7B28"
					( Origin gFrontEnd )
				)
				( attribute "MATERIAL" "X7R"
					( Origin gFrontEnd )
				)
				( attribute "PACK_TYPE" "0402"
					( Origin gFrontEnd )
				)
				( attribute "PART_NUMBER" "A36096-155"
					( Origin gFrontEnd )
				)
				( attribute "PHYS_PAGE" "129"
					( Origin gFrontEnd )
				)
				( attribute "ROOM" "DMI"
					( Origin gFrontEnd )
				)
				( attribute "ROT" "1"
					( Origin gFrontEnd )
				)
				( attribute "SEC" "1"
					( Origin gPackager )
				)
				( attribute "TOLERANCE" "10%"
					( Origin gFrontEnd )
				)
				( attribute "VALUE" "0.22UF"
					( Origin gFrontEnd )
				)
				( attribute "VER" "1"
					( Origin gFrontEnd )
				)
				( attribute "VOLTAGE" "16V"
					( Units "uVoltage" "V" 1.000000)
					( Origin gFrontEnd )
				)
				( attribute "XY" "(-3650,4525)"
					( Origin gFrontEnd )
				)
				( attribute "CHIPS_PART_NAME" "CAP"
					( Origin gPackager )
				)
				( attribute "CDS_PART_NAME" "CAP_0402-0.22UF,16V,10%,X7R,A3A"
					( Origin gPackager )
				)
				( objectStatus "C7B28" )
				( pin "a"
					( attribute "PN" "1"
						( Origin gPackager )
					)
					( objectStatus "C7B28.1" )
				)
				( pin "b"
					( attribute "PN" "2"
						( Origin gPackager )
					)
					( objectStatus "C7B28.2" )
				)
			)
			( gate "@baseboard_fab2_lib.baseboard_fab2(sch_1):page129_i71"
				( attribute "BOM_COST" "SB"
					( Origin gFrontEnd )
				)
				( attribute "CDS_LIB" "mstr_discrete"
					( Origin gPackager )
				)
				( attribute "CDS_LOCATION" "C7C2"
					( Origin gPackager )
				)
				( attribute "CDS_SEC" "1"
					( Origin gPackager )
				)
				( attribute "LOCATION" "C7C2"
					( Origin gFrontEnd )
				)
				( attribute "MATERIAL" "X7R"
					( Origin gFrontEnd )
				)
				( attribute "PACK_TYPE" "0402"
					( Origin gFrontEnd )
				)
				( attribute "PART_NUMBER" "A36096-155"
					( Origin gFrontEnd )
				)
				( attribute "PHYS_PAGE" "129"
					( Origin gFrontEnd )
				)
				( attribute "ROOM" "DMI"
					( Origin gFrontEnd )
				)
				( attribute "ROT" "1"
					( Origin gFrontEnd )
				)
				( attribute "SEC" "1"
					( Origin gPackager )
				)
				( attribute "TOLERANCE" "10%"
					( Origin gFrontEnd )
				)
				( attribute "VALUE" "0.22UF"
					( Origin gFrontEnd )
				)
				( attribute "VER" "1"
					( Origin gFrontEnd )
				)
				( attribute "VOLTAGE" "16V"
					( Units "uVoltage" "V" 1.000000)
					( Origin gFrontEnd )
				)
				( attribute "XY" "(-3300,4325)"
					( Origin gFrontEnd )
				)
				( attribute "CHIPS_PART_NAME" "CAP"
					( Origin gPackager )
				)
				( attribute "CDS_PART_NAME" "CAP_0402-0.22UF,16V,10%,X7R,A3A"
					( Origin gPackager )
				)
				( objectStatus "C7C2" )
				( pin "a"
					( attribute "PN" "1"
						( Origin gPackager )
					)
					( objectStatus "C7C2.1" )
				)
				( pin "b"
					( attribute "PN" "2"
						( Origin gPackager )
					)
					( objectStatus "C7C2.2" )
				)
			)
			( gate "@baseboard_fab2_lib.baseboard_fab2(sch_1):page129_i72"
				( attribute "BOM_COST" "SB"
					( Origin gFrontEnd )
				)
				( attribute "CDS_LIB" "mstr_discrete"
					( Origin gPackager )
				)
				( attribute "CDS_LOCATION" "C3M40"
					( Origin gPackager )
				)
				( attribute "CDS_SEC" "1"
					( Origin gPackager )
				)
				( attribute "LOCATION" "C3M40"
					( Origin gFrontEnd )
				)
				( attribute "MATERIAL" "X7R"
					( Origin gFrontEnd )
				)
				( attribute "PACK_TYPE" "0402"
					( Origin gFrontEnd )
				)
				( attribute "PART_NUMBER" "A36096-155"
					( Origin gFrontEnd )
				)
				( attribute "PHYS_PAGE" "129"
					( Origin gFrontEnd )
				)
				( attribute "ROOM" "DMI"
					( Origin gFrontEnd )
				)
				( attribute "ROT" "1"
					( Origin gFrontEnd )
				)
				( attribute "SEC" "1"
					( Origin gPackager )
				)
				( attribute "TOLERANCE" "10%"
					( Origin gFrontEnd )
				)
				( attribute "VALUE" "0.22UF"
					( Origin gFrontEnd )
				)
				( attribute "VER" "1"
					( Origin gFrontEnd )
				)
				( attribute "VOLTAGE" "16V"
					( Units "uVoltage" "V" 1.000000)
					( Origin gFrontEnd )
				)
				( attribute "XY" "(-3300,3375)"
					( Origin gFrontEnd )
				)
				( attribute "CHIPS_PART_NAME" "CAP"
					( Origin gPackager )
				)
				( attribute "CDS_PART_NAME" "CAP_0402-0.22UF,16V,10%,X7R,A3A"
					( Origin gPackager )
				)
				( objectStatus "C3M40" )
				( pin "a"
					( attribute "PN" "1"
						( Origin gPackager )
					)
					( objectStatus "C3M40.1" )
				)
				( pin "b"
					( attribute "PN" "2"
						( Origin gPackager )
					)
					( objectStatus "C3M40.2" )
				)
			)
			( gate "@baseboard_fab2_lib.baseboard_fab2(sch_1):page129_i73"
				( attribute "BOM_COST" "SB"
					( Origin gFrontEnd )
				)
				( attribute "CDS_LIB" "mstr_discrete"
					( Origin gPackager )
				)
				( attribute "CDS_LOCATION" "C3M37"
					( Origin gPackager )
				)
				( attribute "CDS_SEC" "1"
					( Origin gPackager )
				)
				( attribute "LOCATION" "C3M37"
					( Origin gFrontEnd )
				)
				( attribute "MATERIAL" "X7R"
					( Origin gFrontEnd )
				)
				( attribute "PACK_TYPE" "0402"
					( Origin gFrontEnd )
				)
				( attribute "PART_NUMBER" "A36096-155"
					( Origin gFrontEnd )
				)
				( attribute "PHYS_PAGE" "129"
					( Origin gFrontEnd )
				)
				( attribute "ROOM" "DMI"
					( Origin gFrontEnd )
				)
				( attribute "ROT" "1"
					( Origin gFrontEnd )
				)
				( attribute "SEC" "1"
					( Origin gPackager )
				)
				( attribute "TOLERANCE" "10%"
					( Origin gFrontEnd )
				)
				( attribute "VALUE" "0.22UF"
					( Origin gFrontEnd )
				)
				( attribute "VER" "1"
					( Origin gFrontEnd )
				)
				( attribute "VOLTAGE" "16V"
					( Units "uVoltage" "V" 1.000000)
					( Origin gFrontEnd )
				)
				( attribute "XY" "(-3650,3575)"
					( Origin gFrontEnd )
				)
				( attribute "CHIPS_PART_NAME" "CAP"
					( Origin gPackager )
				)
				( attribute "CDS_PART_NAME" "CAP_0402-0.22UF,16V,10%,X7R,A3A"
					( Origin gPackager )
				)
				( objectStatus "C3M37" )
				( pin "a"
					( attribute "PN" "1"
						( Origin gPackager )
					)
					( objectStatus "C3M37.1" )
				)
				( pin "b"
					( attribute "PN" "2"
						( Origin gPackager )
					)
					( objectStatus "C3M37.2" )
				)
			)
			( gate "@baseboard_fab2_lib.baseboard_fab2(sch_1):page129_i74"
				( attribute "BOM_COST" "SB"
					( Origin gFrontEnd )
				)
				( attribute "CDS_LIB" "mstr_discrete"
					( Origin gPackager )
				)
				( attribute "CDS_LOCATION" "C3N9"
					( Origin gPackager )
				)
				( attribute "CDS_SEC" "1"
					( Origin gPackager )
				)
				( attribute "LOCATION" "C3N9"
					( Origin gFrontEnd )
				)
				( attribute "MATERIAL" "X7R"
					( Origin gFrontEnd )
				)
				( attribute "PACK_TYPE" "0402"
					( Origin gFrontEnd )
				)
				( attribute "PART_NUMBER" "A36096-155"
					( Origin gFrontEnd )
				)
				( attribute "PHYS_PAGE" "129"
					( Origin gFrontEnd )
				)
				( attribute "ROOM" "DMI"
					( Origin gFrontEnd )
				)
				( attribute "ROT" "1"
					( Origin gFrontEnd )
				)
				( attribute "SEC" "1"
					( Origin gPackager )
				)
				( attribute "TOLERANCE" "10%"
					( Origin gFrontEnd )
				)
				( attribute "VALUE" "0.22UF"
					( Origin gFrontEnd )
				)
				( attribute "VER" "1"
					( Origin gFrontEnd )
				)
				( attribute "VOLTAGE" "16V"
					( Units "uVoltage" "V" 1.000000)
					( Origin gFrontEnd )
				)
				( attribute "XY" "(-3300,3775)"
					( Origin gFrontEnd )
				)
				( attribute "CHIPS_PART_NAME" "CAP"
					( Origin gPackager )
				)
				( attribute "CDS_PART_NAME" "CAP_0402-0.22UF,16V,10%,X7R,A3A"
					( Origin gPackager )
				)
				( objectStatus "C3N9" )
				( pin "a"
					( attribute "PN" "1"
						( Origin gPackager )
					)
					( objectStatus "C3N9.1" )
				)
				( pin "b"
					( attribute "PN" "2"
						( Origin gPackager )
					)
					( objectStatus "C3N9.2" )
				)
			)
			( gate "@baseboard_fab2_lib.baseboard_fab2(sch_1):page129_i75"
				( attribute "BOM_COST" "SB"
					( Origin gFrontEnd )
				)
				( attribute "CDS_LIB" "mstr_discrete"
					( Origin gPackager )
				)
				( attribute "CDS_LOCATION" "C3N8"
					( Origin gPackager )
				)
				( attribute "CDS_SEC" "1"
					( Origin gPackager )
				)
				( attribute "LOCATION" "C3N8"
					( Origin gFrontEnd )
				)
				( attribute "MATERIAL" "X7R"
					( Origin gFrontEnd )
				)
				( attribute "PACK_TYPE" "0402"
					( Origin gFrontEnd )
				)
				( attribute "PART_NUMBER" "A36096-155"
					( Origin gFrontEnd )
				)
				( attribute "PHYS_PAGE" "129"
					( Origin gFrontEnd )
				)
				( attribute "ROOM" "DMI"
					( Origin gFrontEnd )
				)
				( attribute "ROT" "1"
					( Origin gFrontEnd )
				)
				( attribute "SEC" "1"
					( Origin gPackager )
				)
				( attribute "TOLERANCE" "10%"
					( Origin gFrontEnd )
				)
				( attribute "VALUE" "0.22UF"
					( Origin gFrontEnd )
				)
				( attribute "VER" "1"
					( Origin gFrontEnd )
				)
				( attribute "VOLTAGE" "16V"
					( Units "uVoltage" "V" 1.000000)
					( Origin gFrontEnd )
				)
				( attribute "XY" "(-3650,3975)"
					( Origin gFrontEnd )
				)
				( attribute "CHIPS_PART_NAME" "CAP"
					( Origin gPackager )
				)
				( attribute "CDS_PART_NAME" "CAP_0402-0.22UF,16V,10%,X7R,A3A"
					( Origin gPackager )
				)
				( objectStatus "C3N8" )
				( pin "a"
					( attribute "PN" "1"
						( Origin gPackager )
					)
					( objectStatus "C3N8.1" )
				)
				( pin "b"
					( attribute "PN" "2"
						( Origin gPackager )
					)
					( objectStatus "C3N8.2" )
				)
			)
			( gate "@baseboard_fab2_lib.baseboard_fab2(sch_1):page129_i76"
				( attribute "BOM_COST" "SB"
					( Origin gFrontEnd )
				)
				( attribute "CDS_LIB" "mstr_discrete"
					( Origin gPackager )
				)
				( attribute "CDS_LOCATION" "C7C3"
					( Origin gPackager )
				)
				( attribute "CDS_SEC" "1"
					( Origin gPackager )
				)
				( attribute "LOCATION" "C7C3"
					( Origin gFrontEnd )
				)
				( attribute "MATERIAL" "X7R"
					( Origin gFrontEnd )
				)
				( attribute "PACK_TYPE" "0402"
					( Origin gFrontEnd )
				)
				( attribute "PART_NUMBER" "A36096-155"
					( Origin gFrontEnd )
				)
				( attribute "PHYS_PAGE" "129"
					( Origin gFrontEnd )
				)
				( attribute "ROOM" "DMI"
					( Origin gFrontEnd )
				)
				( attribute "ROT" "1"
					( Origin gFrontEnd )
				)
				( attribute "SEC" "1"
					( Origin gPackager )
				)
				( attribute "TOLERANCE" "10%"
					( Origin gFrontEnd )
				)
				( attribute "VALUE" "0.22UF"
					( Origin gFrontEnd )
				)
				( attribute "VER" "1"
					( Origin gFrontEnd )
				)
				( attribute "VOLTAGE" "16V"
					( Units "uVoltage" "V" 1.000000)
					( Origin gFrontEnd )
				)
				( attribute "XY" "(750,4325)"
					( Origin gFrontEnd )
				)
				( attribute "CHIPS_PART_NAME" "CAP"
					( Origin gPackager )
				)
				( attribute "CDS_PART_NAME" "CAP_0402-0.22UF,16V,10%,X7R,A3A"
					( Origin gPackager )
				)
				( objectStatus "C7C3" )
				( pin "a"
					( attribute "PN" "1"
						( Origin gPackager )
					)
					( objectStatus "C7C3.1" )
				)
				( pin "b"
					( attribute "PN" "2"
						( Origin gPackager )
					)
					( objectStatus "C7C3.2" )
				)
			)
			( gate "@baseboard_fab2_lib.baseboard_fab2(sch_1):page129_i77"
				( attribute "BOM_COST" "SB"
					( Origin gFrontEnd )
				)
				( attribute "CDS_LIB" "mstr_discrete"
					( Origin gPackager )
				)
				( attribute "CDS_LOCATION" "C7C1"
					( Origin gPackager )
				)
				( attribute "CDS_SEC" "1"
					( Origin gPackager )
				)
				( attribute "LOCATION" "C7C1"
					( Origin gFrontEnd )
				)
				( attribute "MATERIAL" "X7R"
					( Origin gFrontEnd )
				)
				( attribute "PACK_TYPE" "0402"
					( Origin gFrontEnd )
				)
				( attribute "PART_NUMBER" "A36096-155"
					( Origin gFrontEnd )
				)
				( attribute "PHYS_PAGE" "129"
					( Origin gFrontEnd )
				)
				( attribute "ROOM" "DMI"
					( Origin gFrontEnd )
				)
				( attribute "ROT" "1"
					( Origin gFrontEnd )
				)
				( attribute "SEC" "1"
					( Origin gPackager )
				)
				( attribute "TOLERANCE" "10%"
					( Origin gFrontEnd )
				)
				( attribute "VALUE" "0.22UF"
					( Origin gFrontEnd )
				)
				( attribute "VER" "1"
					( Origin gFrontEnd )
				)
				( attribute "VOLTAGE" "16V"
					( Units "uVoltage" "V" 1.000000)
					( Origin gFrontEnd )
				)
				( attribute "XY" "(400,4525)"
					( Origin gFrontEnd )
				)
				( attribute "CHIPS_PART_NAME" "CAP"
					( Origin gPackager )
				)
				( attribute "CDS_PART_NAME" "CAP_0402-0.22UF,16V,10%,X7R,A3A"
					( Origin gPackager )
				)
				( objectStatus "C7C1" )
				( pin "a"
					( attribute "PN" "1"
						( Origin gPackager )
					)
					( objectStatus "C7C1.1" )
				)
				( pin "b"
					( attribute "PN" "2"
						( Origin gPackager )
					)
					( objectStatus "C7C1.2" )
				)
			)
			( gate "@baseboard_fab2_lib.baseboard_fab2(sch_1):page129_i78"
				( attribute "BOM_COST" "SB"
					( Origin gFrontEnd )
				)
				( attribute "CDS_LIB" "mstr_discrete"
					( Origin gPackager )
				)
				( attribute "CDS_LOCATION" "C7B29"
					( Origin gPackager )
				)
				( attribute "CDS_SEC" "1"
					( Origin gPackager )
				)
				( attribute "LOCATION" "C7B29"
					( Origin gFrontEnd )
				)
				( attribute "MATERIAL" "X7R"
					( Origin gFrontEnd )
				)
				( attribute "PACK_TYPE" "0402"
					( Origin gFrontEnd )
				)
				( attribute "PART_NUMBER" "A36096-155"
					( Origin gFrontEnd )
				)
				( attribute "PHYS_PAGE" "129"
					( Origin gFrontEnd )
				)
				( attribute "ROOM" "DMI"
					( Origin gFrontEnd )
				)
				( attribute "ROT" "1"
					( Origin gFrontEnd )
				)
				( attribute "SEC" "1"
					( Origin gPackager )
				)
				( attribute "TOLERANCE" "10%"
					( Origin gFrontEnd )
				)
				( attribute "VALUE" "0.22UF"
					( Origin gFrontEnd )
				)
				( attribute "VER" "1"
					( Origin gFrontEnd )
				)
				( attribute "VOLTAGE" "16V"
					( Units "uVoltage" "V" 1.000000)
					( Origin gFrontEnd )
				)
				( attribute "XY" "(750,4725)"
					( Origin gFrontEnd )
				)
				( attribute "CHIPS_PART_NAME" "CAP"
					( Origin gPackager )
				)
				( attribute "CDS_PART_NAME" "CAP_0402-0.22UF,16V,10%,X7R,A3A"
					( Origin gPackager )
				)
				( objectStatus "C7B29" )
				( pin "a"
					( attribute "PN" "1"
						( Origin gPackager )
					)
					( objectStatus "C7B29.1" )
				)
				( pin "b"
					( attribute "PN" "2"
						( Origin gPackager )
					)
					( objectStatus "C7B29.2" )
				)
			)
			( gate "@baseboard_fab2_lib.baseboard_fab2(sch_1):page129_i79"
				( attribute "BOM_COST" "SB"
					( Origin gFrontEnd )
				)
				( attribute "CDS_LIB" "mstr_discrete"
					( Origin gPackager )
				)
				( attribute "CDS_LOCATION" "C7B26"
					( Origin gPackager )
				)
				( attribute "CDS_SEC" "1"
					( Origin gPackager )
				)
				( attribute "LOCATION" "C7B26"
					( Origin gFrontEnd )
				)
				( attribute "MATERIAL" "X7R"
					( Origin gFrontEnd )
				)
				( attribute "PACK_TYPE" "0402"
					( Origin gFrontEnd )
				)
				( attribute "PART_NUMBER" "A36096-155"
					( Origin gFrontEnd )
				)
				( attribute "PHYS_PAGE" "129"
					( Origin gFrontEnd )
				)
				( attribute "ROOM" "DMI"
					( Origin gFrontEnd )
				)
				( attribute "ROT" "1"
					( Origin gFrontEnd )
				)
				( attribute "SEC" "1"
					( Origin gPackager )
				)
				( attribute "TOLERANCE" "10%"
					( Origin gFrontEnd )
				)
				( attribute "VALUE" "0.22UF"
					( Origin gFrontEnd )
				)
				( attribute "VER" "1"
					( Origin gFrontEnd )
				)
				( attribute "VOLTAGE" "16V"
					( Units "uVoltage" "V" 1.000000)
					( Origin gFrontEnd )
				)
				( attribute "XY" "(400,4925)"
					( Origin gFrontEnd )
				)
				( attribute "CHIPS_PART_NAME" "CAP"
					( Origin gPackager )
				)
				( attribute "CDS_PART_NAME" "CAP_0402-0.22UF,16V,10%,X7R,A3A"
					( Origin gPackager )
				)
				( objectStatus "C7B26" )
				( pin "a"
					( attribute "PN" "1"
						( Origin gPackager )
					)
					( objectStatus "C7B26.1" )
				)
				( pin "b"
					( attribute "PN" "2"
						( Origin gPackager )
					)
					( objectStatus "C7B26.2" )
				)
			)
			( gate "@baseboard_fab2_lib.baseboard_fab2(sch_1):page129_i80"
				( attribute "BOM_COST" "SB"
					( Origin gFrontEnd )
				)
				( attribute "CDS_LIB" "mstr_discrete"
					( Origin gPackager )
				)
				( attribute "CDS_LOCATION" "C3M44"
					( Origin gPackager )
				)
				( attribute "CDS_SEC" "1"
					( Origin gPackager )
				)
				( attribute "LOCATION" "C3M44"
					( Origin gFrontEnd )
				)
				( attribute "MATERIAL" "X7R"
					( Origin gFrontEnd )
				)
				( attribute "PACK_TYPE" "0402"
					( Origin gFrontEnd )
				)
				( attribute "PART_NUMBER" "A36096-155"
					( Origin gFrontEnd )
				)
				( attribute "PHYS_PAGE" "129"
					( Origin gFrontEnd )
				)
				( attribute "ROOM" "DMI"
					( Origin gFrontEnd )
				)
				( attribute "ROT" "1"
					( Origin gFrontEnd )
				)
				( attribute "SEC" "1"
					( Origin gPackager )
				)
				( attribute "TOLERANCE" "10%"
					( Origin gFrontEnd )
				)
				( attribute "VALUE" "0.22UF"
					( Origin gFrontEnd )
				)
				( attribute "VER" "1"
					( Origin gFrontEnd )
				)
				( attribute "VOLTAGE" "16V"
					( Units "uVoltage" "V" 1.000000)
					( Origin gFrontEnd )
				)
				( attribute "XY" "(750,3375)"
					( Origin gFrontEnd )
				)
				( attribute "CHIPS_PART_NAME" "CAP"
					( Origin gPackager )
				)
				( attribute "CDS_PART_NAME" "CAP_0402-0.22UF,16V,10%,X7R,A3A"
					( Origin gPackager )
				)
				( objectStatus "C3M44" )
				( pin "a"
					( attribute "PN" "1"
						( Origin gPackager )
					)
					( objectStatus "C3M44.1" )
				)
				( pin "b"
					( attribute "PN" "2"
						( Origin gPackager )
					)
					( objectStatus "C3M44.2" )
				)
			)
			( gate "@baseboard_fab2_lib.baseboard_fab2(sch_1):page129_i81"
				( attribute "BOM_COST" "SB"
					( Origin gFrontEnd )
				)
				( attribute "CDS_LIB" "mstr_discrete"
					( Origin gPackager )
				)
				( attribute "CDS_LOCATION" "C3M41"
					( Origin gPackager )
				)
				( attribute "CDS_SEC" "1"
					( Origin gPackager )
				)
				( attribute "LOCATION" "C3M41"
					( Origin gFrontEnd )
				)
				( attribute "MATERIAL" "X7R"
					( Origin gFrontEnd )
				)
				( attribute "PACK_TYPE" "0402"
					( Origin gFrontEnd )
				)
				( attribute "PART_NUMBER" "A36096-155"
					( Origin gFrontEnd )
				)
				( attribute "PHYS_PAGE" "129"
					( Origin gFrontEnd )
				)
				( attribute "ROOM" "DMI"
					( Origin gFrontEnd )
				)
				( attribute "ROT" "1"
					( Origin gFrontEnd )
				)
				( attribute "SEC" "1"
					( Origin gPackager )
				)
				( attribute "TOLERANCE" "10%"
					( Origin gFrontEnd )
				)
				( attribute "VALUE" "0.22UF"
					( Origin gFrontEnd )
				)
				( attribute "VER" "1"
					( Origin gFrontEnd )
				)
				( attribute "VOLTAGE" "16V"
					( Units "uVoltage" "V" 1.000000)
					( Origin gFrontEnd )
				)
				( attribute "XY" "(400,3575)"
					( Origin gFrontEnd )
				)
				( attribute "CHIPS_PART_NAME" "CAP"
					( Origin gPackager )
				)
				( attribute "CDS_PART_NAME" "CAP_0402-0.22UF,16V,10%,X7R,A3A"
					( Origin gPackager )
				)
				( objectStatus "C3M41" )
				( pin "a"
					( attribute "PN" "1"
						( Origin gPackager )
					)
					( objectStatus "C3M41.1" )
				)
				( pin "b"
					( attribute "PN" "2"
						( Origin gPackager )
					)
					( objectStatus "C3M41.2" )
				)
			)
			( gate "@baseboard_fab2_lib.baseboard_fab2(sch_1):page129_i82"
				( attribute "BOM_COST" "SB"
					( Origin gFrontEnd )
				)
				( attribute "CDS_LIB" "mstr_discrete"
					( Origin gPackager )
				)
				( attribute "CDS_LOCATION" "C3M45"
					( Origin gPackager )
				)
				( attribute "CDS_SEC" "1"
					( Origin gPackager )
				)
				( attribute "LOCATION" "C3M45"
					( Origin gFrontEnd )
				)
				( attribute "MATERIAL" "X7R"
					( Origin gFrontEnd )
				)
				( attribute "PACK_TYPE" "0402"
					( Origin gFrontEnd )
				)
				( attribute "PART_NUMBER" "A36096-155"
					( Origin gFrontEnd )
				)
				( attribute "PHYS_PAGE" "129"
					( Origin gFrontEnd )
				)
				( attribute "ROOM" "DMI"
					( Origin gFrontEnd )
				)
				( attribute "ROT" "1"
					( Origin gFrontEnd )
				)
				( attribute "SEC" "1"
					( Origin gPackager )
				)
				( attribute "TOLERANCE" "10%"
					( Origin gFrontEnd )
				)
				( attribute "VALUE" "0.22UF"
					( Origin gFrontEnd )
				)
				( attribute "VER" "1"
					( Origin gFrontEnd )
				)
				( attribute "VOLTAGE" "16V"
					( Units "uVoltage" "V" 1.000000)
					( Origin gFrontEnd )
				)
				( attribute "XY" "(750,3775)"
					( Origin gFrontEnd )
				)
				( attribute "CHIPS_PART_NAME" "CAP"
					( Origin gPackager )
				)
				( attribute "CDS_PART_NAME" "CAP_0402-0.22UF,16V,10%,X7R,A3A"
					( Origin gPackager )
				)
				( objectStatus "C3M45" )
				( pin "a"
					( attribute "PN" "1"
						( Origin gPackager )
					)
					( objectStatus "C3M45.1" )
				)
				( pin "b"
					( attribute "PN" "2"
						( Origin gPackager )
					)
					( objectStatus "C3M45.2" )
				)
			)
			( gate "@baseboard_fab2_lib.baseboard_fab2(sch_1):page129_i83"
				( attribute "BOM_COST" "SB"
					( Origin gFrontEnd )
				)
				( attribute "CDS_LIB" "mstr_discrete"
					( Origin gPackager )
				)
				( attribute "CDS_LOCATION" "C3N13"
					( Origin gPackager )
				)
				( attribute "CDS_SEC" "1"
					( Origin gPackager )
				)
				( attribute "LOCATION" "C3N13"
					( Origin gFrontEnd )
				)
				( attribute "MATERIAL" "X7R"
					( Origin gFrontEnd )
				)
				( attribute "PACK_TYPE" "0402"
					( Origin gFrontEnd )
				)
				( attribute "PART_NUMBER" "A36096-155"
					( Origin gFrontEnd )
				)
				( attribute "PHYS_PAGE" "129"
					( Origin gFrontEnd )
				)
				( attribute "ROOM" "DMI"
					( Origin gFrontEnd )
				)
				( attribute "ROT" "1"
					( Origin gFrontEnd )
				)
				( attribute "SEC" "1"
					( Origin gPackager )
				)
				( attribute "TOLERANCE" "10%"
					( Origin gFrontEnd )
				)
				( attribute "VALUE" "0.22UF"
					( Origin gFrontEnd )
				)
				( attribute "VER" "1"
					( Origin gFrontEnd )
				)
				( attribute "VOLTAGE" "16V"
					( Units "uVoltage" "V" 1.000000)
					( Origin gFrontEnd )
				)
				( attribute "XY" "(400,3975)"
					( Origin gFrontEnd )
				)
				( attribute "CHIPS_PART_NAME" "CAP"
					( Origin gPackager )
				)
				( attribute "CDS_PART_NAME" "CAP_0402-0.22UF,16V,10%,X7R,A3A"
					( Origin gPackager )
				)
				( objectStatus "C3N13" )
				( pin "a"
					( attribute "PN" "1"
						( Origin gPackager )
					)
					( objectStatus "C3N13.1" )
				)
				( pin "b"
					( attribute "PN" "2"
						( Origin gPackager )
					)
					( objectStatus "C3N13.2" )
				)
			)
			( gate "@baseboard_fab2_lib.baseboard_fab2(sch_1):page130_i2"
				( attribute "BOM_COST" "SB"
					( Origin gFrontEnd )
				)
				( attribute "CDS_LIB" "mstr_discrete"
					( Origin gPackager )
				)
				( attribute "CDS_LOCATION" "C7D2"
					( Origin gPackager )
				)
				( attribute "CDS_SEC" "1"
					( Origin gPackager )
				)
				( attribute "LOCATION" "C7D2"
					( Origin gFrontEnd )
				)
				( attribute "MATERIAL" "X6S"
					( Origin gFrontEnd )
				)
				( attribute "PACK_TYPE" "0603"
					( Origin gFrontEnd )
				)
				( attribute "PART_NUMBER" "E15431-002"
					( Origin gFrontEnd )
				)
				( attribute "PHYS_PAGE" "130"
					( Origin gFrontEnd )
				)
				( attribute "ROOM" "SB_DECOUPLING"
					( Origin gFrontEnd )
				)
				( attribute "ROT" "0"
					( Origin gFrontEnd )
				)
				( attribute "SEC" "1"
					( Origin gFrontEnd )
				)
				( attribute "SEC_TYPE" "0603"
					( Origin gFrontEnd )
				)
				( attribute "TOLERANCE" "20%"
					( Origin gFrontEnd )
				)
				( attribute "VALUE" "10UF"
					( Origin gFrontEnd )
				)
				( attribute "VER" "1"
					( Origin gFrontEnd )
				)
				( attribute "VOLTAGE" "6.3V"
					( Units "uVoltage" "V" 1.000000)
					( Origin gFrontEnd )
				)
				( attribute "XY" "(1125,5003)"
					( Origin gFrontEnd )
				)
				( attribute "CHIPS_PART_NAME" "CAP"
					( Origin gPackager )
				)
				( attribute "CDS_PART_NAME" "CAP_0603-10UF,6.3V,20%,X6S,E15A"
					( Origin gPackager )
				)
				( objectStatus "C7D2" )
				( pin "a"
					( attribute "PN" "1"
						( Origin gPackager )
					)
					( objectStatus "C7D2.1" )
				)
				( pin "b"
					( attribute "PN" "2"
						( Origin gPackager )
					)
					( objectStatus "C7D2.2" )
				)
			)
			( gate "@baseboard_fab2_lib.baseboard_fab2(sch_1):page130_i4"
				( attribute "BOM_COST" "SB"
					( Origin gFrontEnd )
				)
				( attribute "CDS_LIB" "dev_discrete"
					( Origin gPackager )
				)
				( attribute "CDS_LOCATION" "C2N26"
					( Origin gPackager )
				)
				( attribute "CDS_SEC" "1"
					( Origin gPackager )
				)
				( attribute "LOCATION" "C2N26"
					( Origin gFrontEnd )
				)
				( attribute "MATERIAL" "X6S"
					( Origin gFrontEnd )
				)
				( attribute "PACK_TYPE" "0402V"
					( Origin gFrontEnd )
				)
				( attribute "PART_NUMBER" "D97712-004"
					( Origin gFrontEnd )
				)
				( attribute "PHYS_PAGE" "130"
					( Origin gFrontEnd )
				)
				( attribute "ROOM" "SB_DECOUPLING"
					( Origin gFrontEnd )
				)
				( attribute "ROT" "0"
					( Origin gFrontEnd )
				)
				( attribute "SEC" "1"
					( Origin gPackager )
				)
				( attribute "TOLERANCE" "10%"
					( Origin gFrontEnd )
				)
				( attribute "VALUE" "1.0UF"
					( Origin gFrontEnd )
				)
				( attribute "VER" "1"
					( Origin gFrontEnd )
				)
				( attribute "VOLTAGE" "6.3V"
					( Units "uVoltage" "V" 1.000000)
					( Origin gFrontEnd )
				)
				( attribute "XY" "(1725,2650)"
					( Origin gFrontEnd )
				)
				( attribute "CHIPS_PART_NAME" "CAP_A"
					( Origin gPackager )
				)
				( attribute "CDS_PART_NAME" "CAP_A_0402V-1.0UF,6.3V,10%,X6SA"
					( Origin gPackager )
				)
				( objectStatus "C2N26" )
				( pin "a"
					( attribute "PN" "1"
						( Origin gPackager )
					)
					( objectStatus "C2N26.1" )
				)
				( pin "b"
					( attribute "PN" "2"
						( Origin gPackager )
					)
					( objectStatus "C2N26.2" )
				)
			)
			( gate "@baseboard_fab2_lib.baseboard_fab2(sch_1):page130_i7"
				( attribute "BOM_COST" "SB"
					( Origin gFrontEnd )
				)
				( attribute "CDS_LIB" "dev_discrete"
					( Origin gPackager )
				)
				( attribute "CDS_LOCATION" "C2N19"
					( Origin gPackager )
				)
				( attribute "CDS_SEC" "1"
					( Origin gPackager )
				)
				( attribute "LOCATION" "C2N19"
					( Origin gFrontEnd )
				)
				( attribute "MATERIAL" "X6S"
					( Origin gFrontEnd )
				)
				( attribute "PACK_TYPE" "0402V"
					( Origin gFrontEnd )
				)
				( attribute "PART_NUMBER" "D97712-004"
					( Origin gFrontEnd )
				)
				( attribute "PHYS_PAGE" "130"
					( Origin gFrontEnd )
				)
				( attribute "ROOM" "SB_DECOUPLING"
					( Origin gFrontEnd )
				)
				( attribute "ROT" "0"
					( Origin gFrontEnd )
				)
				( attribute "SEC" "1"
					( Origin gPackager )
				)
				( attribute "TOLERANCE" "10%"
					( Origin gFrontEnd )
				)
				( attribute "VALUE" "1.0UF"
					( Origin gFrontEnd )
				)
				( attribute "VER" "1"
					( Origin gFrontEnd )
				)
				( attribute "VOLTAGE" "6.3V"
					( Units "uVoltage" "V" 1.000000)
					( Origin gFrontEnd )
				)
				( attribute "XY" "(1175,3900)"
					( Origin gFrontEnd )
				)
				( attribute "CHIPS_PART_NAME" "CAP_A"
					( Origin gPackager )
				)
				( attribute "CDS_PART_NAME" "CAP_A_0402V-1.0UF,6.3V,10%,X6SA"
					( Origin gPackager )
				)
				( objectStatus "C2N19" )
				( pin "a"
					( attribute "PN" "1"
						( Origin gPackager )
					)
					( objectStatus "C2N19.1" )
				)
				( pin "b"
					( attribute "PN" "2"
						( Origin gPackager )
					)
					( objectStatus "C2N19.2" )
				)
			)
			( gate "@baseboard_fab2_lib.baseboard_fab2(sch_1):page130_i8"
				( attribute "BOM_COST" "SB"
					( Origin gFrontEnd )
				)
				( attribute "CDS_LIB" "mstr_discrete"
					( Origin gPackager )
				)
				( attribute "CDS_LOCATION" "C2N24"
					( Origin gPackager )
				)
				( attribute "CDS_SEC" "1"
					( Origin gPackager )
				)
				( attribute "LOCATION" "C2N24"
					( Origin gFrontEnd )
				)
				( attribute "MATERIAL" "X6S"
					( Origin gFrontEnd )
				)
				( attribute "PACK_TYPE" "0603"
					( Origin gFrontEnd )
				)
				( attribute "PART_NUMBER" "E15431-002"
					( Origin gFrontEnd )
				)
				( attribute "PHYS_PAGE" "130"
					( Origin gFrontEnd )
				)
				( attribute "ROOM" "SB_DECOUPLING"
					( Origin gFrontEnd )
				)
				( attribute "ROT" "0"
					( Origin gFrontEnd )
				)
				( attribute "SEC" "1"
					( Origin gPackager )
				)
				( attribute "TOLERANCE" "20%"
					( Origin gFrontEnd )
				)
				( attribute "VALUE" "10UF"
					( Origin gFrontEnd )
				)
				( attribute "VER" "1"
					( Origin gFrontEnd )
				)
				( attribute "VOLTAGE" "6.3V"
					( Units "uVoltage" "V" 1.000000)
					( Origin gFrontEnd )
				)
				( attribute "XY" "(1300,2650)"
					( Origin gFrontEnd )
				)
				( attribute "CHIPS_PART_NAME" "CAP"
					( Origin gPackager )
				)
				( attribute "CDS_PART_NAME" "CAP_0603-10UF,6.3V,20%,X6S,E15A"
					( Origin gPackager )
				)
				( objectStatus "C2N24" )
				( pin "a"
					( attribute "PN" "1"
						( Origin gPackager )
					)
					( objectStatus "C2N24.1" )
				)
				( pin "b"
					( attribute "PN" "2"
						( Origin gPackager )
					)
					( objectStatus "C2N24.2" )
				)
			)
			( gate "@baseboard_fab2_lib.baseboard_fab2(sch_1):page130_i9"
				( attribute "BOM_COST" "SB"
					( Origin gFrontEnd )
				)
				( attribute "CDS_LIB" "mstr_discrete"
					( Origin gPackager )
				)
				( attribute "CDS_LOCATION" "C2N22"
					( Origin gPackager )
				)
				( attribute "CDS_SEC" "1"
					( Origin gPackager )
				)
				( attribute "LOCATION" "C2N22"
					( Origin gFrontEnd )
				)
				( attribute "MATERIAL" "X6S"
					( Origin gFrontEnd )
				)
				( attribute "PACK_TYPE" "0603"
					( Origin gFrontEnd )
				)
				( attribute "PART_NUMBER" "E15431-002"
					( Origin gFrontEnd )
				)
				( attribute "PHYS_PAGE" "130"
					( Origin gFrontEnd )
				)
				( attribute "ROOM" "SB_DECOUPLING"
					( Origin gFrontEnd )
				)
				( attribute "ROT" "0"
					( Origin gFrontEnd )
				)
				( attribute "SEC" "1"
					( Origin gPackager )
				)
				( attribute "TOLERANCE" "20%"
					( Origin gFrontEnd )
				)
				( attribute "VALUE" "10UF"
					( Origin gFrontEnd )
				)
				( attribute "VER" "1"
					( Origin gFrontEnd )
				)
				( attribute "VOLTAGE" "6.3V"
					( Units "uVoltage" "V" 1.000000)
					( Origin gFrontEnd )
				)
				( attribute "XY" "(875,2650)"
					( Origin gFrontEnd )
				)
				( attribute "CHIPS_PART_NAME" "CAP"
					( Origin gPackager )
				)
				( attribute "CDS_PART_NAME" "CAP_0603-10UF,6.3V,20%,X6S,E15A"
					( Origin gPackager )
				)
				( objectStatus "C2N22" )
				( pin "a"
					( attribute "PN" "1"
						( Origin gPackager )
					)
					( objectStatus "C2N22.1" )
				)
				( pin "b"
					( attribute "PN" "2"
						( Origin gPackager )
					)
					( objectStatus "C2N22.2" )
				)
			)
			( gate "@baseboard_fab2_lib.baseboard_fab2(sch_1):page130_i12"
				( attribute "BOM_COST" "SB"
					( Origin gFrontEnd )
				)
				( attribute "CDS_LIB" "dev_discrete"
					( Origin gPackager )
				)
				( attribute "CDS_LOCATION" "C2N20"
					( Origin gPackager )
				)
				( attribute "CDS_SEC" "1"
					( Origin gPackager )
				)
				( attribute "LOCATION" "C2N20"
					( Origin gFrontEnd )
				)
				( attribute "MATERIAL" "X6S"
					( Origin gFrontEnd )
				)
				( attribute "PACK_TYPE" "0402V"
					( Origin gFrontEnd )
				)
				( attribute "PART_NUMBER" "D97712-004"
					( Origin gFrontEnd )
				)
				( attribute "PHYS_PAGE" "130"
					( Origin gFrontEnd )
				)
				( attribute "ROOM" "SB_DECOUPLING"
					( Origin gFrontEnd )
				)
				( attribute "ROT" "0"
					( Origin gFrontEnd )
				)
				( attribute "SEC" "1"
					( Origin gPackager )
				)
				( attribute "TOLERANCE" "10%"
					( Origin gFrontEnd )
				)
				( attribute "VALUE" "1.0UF"
					( Origin gFrontEnd )
				)
				( attribute "VER" "1"
					( Origin gFrontEnd )
				)
				( attribute "VOLTAGE" "6.3V"
					( Units "uVoltage" "V" 1.000000)
					( Origin gFrontEnd )
				)
				( attribute "XY" "(1925,1600)"
					( Origin gFrontEnd )
				)
				( attribute "CHIPS_PART_NAME" "CAP_A"
					( Origin gPackager )
				)
				( attribute "CDS_PART_NAME" "CAP_A_0402V-1.0UF,6.3V,10%,X6SA"
					( Origin gPackager )
				)
				( objectStatus "C2N20" )
				( pin "a"
					( attribute "PN" "1"
						( Origin gPackager )
					)
					( objectStatus "C2N20.1" )
				)
				( pin "b"
					( attribute "PN" "2"
						( Origin gPackager )
					)
					( objectStatus "C2N20.2" )
				)
			)
			( gate "@baseboard_fab2_lib.baseboard_fab2(sch_1):page130_i15"
				( attribute "BOM_COST" "SB"
					( Origin gFrontEnd )
				)
				( attribute "CDS_LIB" "mstr_discrete"
					( Origin gPackager )
				)
				( attribute "CDS_LOCATION" "C2N21"
					( Origin gPackager )
				)
				( attribute "CDS_SEC" "1"
					( Origin gPackager )
				)
				( attribute "LOCATION" "C2N21"
					( Origin gFrontEnd )
				)
				( attribute "MATERIAL" "X6S"
					( Origin gFrontEnd )
				)
				( attribute "PACK_TYPE" "0603"
					( Origin gFrontEnd )
				)
				( attribute "PART_NUMBER" "E15431-002"
					( Origin gFrontEnd )
				)
				( attribute "PHYS_PAGE" "130"
					( Origin gFrontEnd )
				)
				( attribute "ROOM" "SB_DECOUPLING"
					( Origin gFrontEnd )
				)
				( attribute "ROT" "0"
					( Origin gFrontEnd )
				)
				( attribute "SEC" "1"
					( Origin gPackager )
				)
				( attribute "TOLERANCE" "20%"
					( Origin gFrontEnd )
				)
				( attribute "VALUE" "10UF"
					( Origin gFrontEnd )
				)
				( attribute "VER" "1"
					( Origin gFrontEnd )
				)
				( attribute "VOLTAGE" "6.3V"
					( Units "uVoltage" "V" 1.000000)
					( Origin gFrontEnd )
				)
				( attribute "XY" "(425,2650)"
					( Origin gFrontEnd )
				)
				( attribute "CHIPS_PART_NAME" "CAP"
					( Origin gPackager )
				)
				( attribute "CDS_PART_NAME" "CAP_0603-10UF,6.3V,20%,X6S,E15A"
					( Origin gPackager )
				)
				( objectStatus "C2N21" )
				( pin "a"
					( attribute "PN" "1"
						( Origin gPackager )
					)
					( objectStatus "C2N21.1" )
				)
				( pin "b"
					( attribute "PN" "2"
						( Origin gPackager )
					)
					( objectStatus "C2N21.2" )
				)
			)
			( gate "@baseboard_fab2_lib.baseboard_fab2(sch_1):page130_i16"
				( attribute "BOM_COST" "SB"
					( Origin gFrontEnd )
				)
				( attribute "CDS_LIB" "dev_discrete"
					( Origin gPackager )
				)
				( attribute "CDS_LOCATION" "C3N29"
					( Origin gPackager )
				)
				( attribute "CDS_SEC" "1"
					( Origin gPackager )
				)
				( attribute "LOCATION" "C3N29"
					( Origin gFrontEnd )
				)
				( attribute "MATERIAL" "X7R"
					( Origin gFrontEnd )
				)
				( attribute "PACK_TYPE" "0402V"
					( Origin gFrontEnd )
				)
				( attribute "PART_NUMBER" "A36096-030"
					( Origin gFrontEnd )
				)
				( attribute "PHYS_PAGE" "130"
					( Origin gFrontEnd )
				)
				( attribute "ROOM" "SB_DECOUPLING"
					( Origin gFrontEnd )
				)
				( attribute "ROT" "2"
					( Origin gFrontEnd )
				)
				( attribute "SEC" "1"
					( Origin gPackager )
				)
				( attribute "TOLERANCE" "10%"
					( Origin gFrontEnd )
				)
				( attribute "VALUE" "0.1UF"
					( Origin gFrontEnd )
				)
				( attribute "VER" "1"
					( Origin gFrontEnd )
				)
				( attribute "VOLTAGE" "16V"
					( Units "uVoltage" "V" 1.000000)
					( Origin gFrontEnd )
				)
				( attribute "XY" "(0,2025)"
					( Origin gFrontEnd )
				)
				( attribute "CHIPS_PART_NAME" "CAP_A"
					( Origin gPackager )
				)
				( attribute "CDS_PART_NAME" "CAP_A_0402V-0.1UF,16V,10%,X7R,A"
					( Origin gPackager )
				)
				( objectStatus "C3N29" )
				( pin "a"
					( attribute "PN" "1"
						( Origin gPackager )
					)
					( objectStatus "C3N29.1" )
				)
				( pin "b"
					( attribute "PN" "2"
						( Origin gPackager )
					)
					( objectStatus "C3N29.2" )
				)
			)
			( gate "@baseboard_fab2_lib.baseboard_fab2(sch_1):page130_i19"
				( attribute "BOM_COST" "SB"
					( Origin gFrontEnd )
				)
				( attribute "CDS_LIB" "mstr_discrete"
					( Origin gPackager )
				)
				( attribute "CDS_LOCATION" "C8C3"
					( Origin gPackager )
				)
				( attribute "CDS_SEC" "1"
					( Origin gPackager )
				)
				( attribute "LOCATION" "C8C3"
					( Origin gFrontEnd )
				)
				( attribute "MATERIAL" "X6S"
					( Origin gFrontEnd )
				)
				( attribute "PACK_TYPE" "0603"
					( Origin gFrontEnd )
				)
				( attribute "PART_NUMBER" "E15431-002"
					( Origin gFrontEnd )
				)
				( attribute "PHYS_PAGE" "130"
					( Origin gFrontEnd )
				)
				( attribute "ROOM" "SB_DECOUPLING"
					( Origin gFrontEnd )
				)
				( attribute "ROT" "0"
					( Origin gFrontEnd )
				)
				( attribute "SEC" "1"
					( Origin gPackager )
				)
				( attribute "TOLERANCE" "20%"
					( Origin gFrontEnd )
				)
				( attribute "VALUE" "10UF"
					( Origin gFrontEnd )
				)
				( attribute "VER" "1"
					( Origin gFrontEnd )
				)
				( attribute "VOLTAGE" "6.3V"
					( Units "uVoltage" "V" 1.000000)
					( Origin gFrontEnd )
				)
				( attribute "XY" "(-2550,4925)"
					( Origin gFrontEnd )
				)
				( attribute "CHIPS_PART_NAME" "CAP"
					( Origin gPackager )
				)
				( attribute "CDS_PART_NAME" "CAP_0603-10UF,6.3V,20%,X6S,E15A"
					( Origin gPackager )
				)
				( objectStatus "C8C3" )
				( pin "a"
					( attribute "PN" "1"
						( Origin gPackager )
					)
					( objectStatus "C8C3.1" )
				)
				( pin "b"
					( attribute "PN" "2"
						( Origin gPackager )
					)
					( objectStatus "C8C3.2" )
				)
			)
			( gate "@baseboard_fab2_lib.baseboard_fab2(sch_1):page130_i20"
				( attribute "BOM_COST" "SB"
					( Origin gFrontEnd )
				)
				( attribute "CDS_LIB" "mstr_discrete"
					( Origin gPackager )
				)
				( attribute "CDS_LOCATION" "C8C4"
					( Origin gPackager )
				)
				( attribute "CDS_SEC" "1"
					( Origin gPackager )
				)
				( attribute "LOCATION" "C8C4"
					( Origin gFrontEnd )
				)
				( attribute "MATERIAL" "X6S"
					( Origin gFrontEnd )
				)
				( attribute "PACK_TYPE" "0603"
					( Origin gFrontEnd )
				)
				( attribute "PART_NUMBER" "E15431-002"
					( Origin gFrontEnd )
				)
				( attribute "PHYS_PAGE" "130"
					( Origin gFrontEnd )
				)
				( attribute "ROOM" "SB_DECOUPLING"
					( Origin gFrontEnd )
				)
				( attribute "ROT" "0"
					( Origin gFrontEnd )
				)
				( attribute "SEC" "1"
					( Origin gPackager )
				)
				( attribute "TOLERANCE" "20%"
					( Origin gFrontEnd )
				)
				( attribute "VALUE" "10UF"
					( Origin gFrontEnd )
				)
				( attribute "VER" "1"
					( Origin gFrontEnd )
				)
				( attribute "VOLTAGE" "6.3V"
					( Units "uVoltage" "V" 1.000000)
					( Origin gFrontEnd )
				)
				( attribute "XY" "(-2975,4925)"
					( Origin gFrontEnd )
				)
				( attribute "CHIPS_PART_NAME" "CAP"
					( Origin gPackager )
				)
				( attribute "CDS_PART_NAME" "CAP_0603-10UF,6.3V,20%,X6S,E15A"
					( Origin gPackager )
				)
				( objectStatus "C8C4" )
				( pin "a"
					( attribute "PN" "1"
						( Origin gPackager )
					)
					( objectStatus "C8C4.1" )
				)
				( pin "b"
					( attribute "PN" "2"
						( Origin gPackager )
					)
					( objectStatus "C8C4.2" )
				)
			)
			( gate "@baseboard_fab2_lib.baseboard_fab2(sch_1):page130_i21"
				( attribute "BOM_COST" "SB"
					( Origin gFrontEnd )
				)
				( attribute "CDS_LIB" "mstr_discrete"
					( Origin gPackager )
				)
				( attribute "CDS_LOCATION" "C8C5"
					( Origin gPackager )
				)
				( attribute "CDS_SEC" "1"
					( Origin gPackager )
				)
				( attribute "LOCATION" "C8C5"
					( Origin gFrontEnd )
				)
				( attribute "MATERIAL" "X6S"
					( Origin gFrontEnd )
				)
				( attribute "PACK_TYPE" "0603"
					( Origin gFrontEnd )
				)
				( attribute "PART_NUMBER" "E15431-002"
					( Origin gFrontEnd )
				)
				( attribute "PHYS_PAGE" "130"
					( Origin gFrontEnd )
				)
				( attribute "ROOM" "SB_DECOUPLING"
					( Origin gFrontEnd )
				)
				( attribute "ROT" "0"
					( Origin gFrontEnd )
				)
				( attribute "SEC" "1"
					( Origin gPackager )
				)
				( attribute "TOLERANCE" "20%"
					( Origin gFrontEnd )
				)
				( attribute "VALUE" "10UF"
					( Origin gFrontEnd )
				)
				( attribute "VER" "1"
					( Origin gFrontEnd )
				)
				( attribute "VOLTAGE" "6.3V"
					( Units "uVoltage" "V" 1.000000)
					( Origin gFrontEnd )
				)
				( attribute "XY" "(-3375,4925)"
					( Origin gFrontEnd )
				)
				( attribute "CHIPS_PART_NAME" "CAP"
					( Origin gPackager )
				)
				( attribute "CDS_PART_NAME" "CAP_0603-10UF,6.3V,20%,X6S,E15A"
					( Origin gPackager )
				)
				( objectStatus "C8C5" )
				( pin "a"
					( attribute "PN" "1"
						( Origin gPackager )
					)
					( objectStatus "C8C5.1" )
				)
				( pin "b"
					( attribute "PN" "2"
						( Origin gPackager )
					)
					( objectStatus "C8C5.2" )
				)
			)
			( gate "@baseboard_fab2_lib.baseboard_fab2(sch_1):page130_i22"
				( attribute "BOM_COST" "SB"
					( Origin gFrontEnd )
				)
				( attribute "CDS_LIB" "mstr_discrete"
					( Origin gPackager )
				)
				( attribute "CDS_LOCATION" "C8C6"
					( Origin gPackager )
				)
				( attribute "CDS_SEC" "1"
					( Origin gPackager )
				)
				( attribute "LOCATION" "C8C6"
					( Origin gFrontEnd )
				)
				( attribute "MATERIAL" "X6S"
					( Origin gFrontEnd )
				)
				( attribute "PACK_TYPE" "0603"
					( Origin gFrontEnd )
				)
				( attribute "PART_NUMBER" "E15431-002"
					( Origin gFrontEnd )
				)
				( attribute "PHYS_PAGE" "130"
					( Origin gFrontEnd )
				)
				( attribute "ROOM" "SB_DECOUPLING"
					( Origin gFrontEnd )
				)
				( attribute "ROT" "0"
					( Origin gFrontEnd )
				)
				( attribute "SEC" "1"
					( Origin gPackager )
				)
				( attribute "TOLERANCE" "20%"
					( Origin gFrontEnd )
				)
				( attribute "VALUE" "10UF"
					( Origin gFrontEnd )
				)
				( attribute "VER" "1"
					( Origin gFrontEnd )
				)
				( attribute "VOLTAGE" "6.3V"
					( Units "uVoltage" "V" 1.000000)
					( Origin gFrontEnd )
				)
				( attribute "XY" "(-3775,4925)"
					( Origin gFrontEnd )
				)
				( attribute "CHIPS_PART_NAME" "CAP"
					( Origin gPackager )
				)
				( attribute "CDS_PART_NAME" "CAP_0603-10UF,6.3V,20%,X6S,E15A"
					( Origin gPackager )
				)
				( objectStatus "C8C6" )
				( pin "a"
					( attribute "PN" "1"
						( Origin gPackager )
					)
					( objectStatus "C8C6.1" )
				)
				( pin "b"
					( attribute "PN" "2"
						( Origin gPackager )
					)
					( objectStatus "C8C6.2" )
				)
			)
			( gate "@baseboard_fab2_lib.baseboard_fab2(sch_1):page130_i24"
				( attribute "BOM_COST" "SB"
					( Origin gFrontEnd )
				)
				( attribute "CDS_LIB" "mstr_discrete"
					( Origin gPackager )
				)
				( attribute "CDS_LOCATION" "C2N23"
					( Origin gPackager )
				)
				( attribute "CDS_SEC" "1"
					( Origin gPackager )
				)
				( attribute "LOCATION" "C2N23"
					( Origin gFrontEnd )
				)
				( attribute "MATERIAL" "X6S"
					( Origin gFrontEnd )
				)
				( attribute "PACK_TYPE" "0603"
					( Origin gFrontEnd )
				)
				( attribute "PART_NUMBER" "E15431-002"
					( Origin gFrontEnd )
				)
				( attribute "PHYS_PAGE" "130"
					( Origin gFrontEnd )
				)
				( attribute "ROOM" "SB_DECOUPLING"
					( Origin gFrontEnd )
				)
				( attribute "ROT" "0"
					( Origin gFrontEnd )
				)
				( attribute "SEC" "1"
					( Origin gPackager )
				)
				( attribute "TOLERANCE" "20%"
					( Origin gFrontEnd )
				)
				( attribute "VALUE" "10UF"
					( Origin gFrontEnd )
				)
				( attribute "VER" "1"
					( Origin gFrontEnd )
				)
				( attribute "VOLTAGE" "6.3V"
					( Units "uVoltage" "V" 1.000000)
					( Origin gFrontEnd )
				)
				( attribute "XY" "(-4175,4925)"
					( Origin gFrontEnd )
				)
				( attribute "CHIPS_PART_NAME" "CAP"
					( Origin gPackager )
				)
				( attribute "CDS_PART_NAME" "CAP_0603-10UF,6.3V,20%,X6S,E15A"
					( Origin gPackager )
				)
				( objectStatus "C2N23" )
				( pin "a"
					( attribute "PN" "1"
						( Origin gPackager )
					)
					( objectStatus "C2N23.1" )
				)
				( pin "b"
					( attribute "PN" "2"
						( Origin gPackager )
					)
					( objectStatus "C2N23.2" )
				)
			)
			( gate "@baseboard_fab2_lib.baseboard_fab2(sch_1):page130_i25"
				( attribute "BOM_COST" "SB"
					( Origin gFrontEnd )
				)
				( attribute "CDS_LIB" "mstr_discrete"
					( Origin gPackager )
				)
				( attribute "CDS_LOCATION" "C2N14"
					( Origin gPackager )
				)
				( attribute "CDS_SEC" "1"
					( Origin gPackager )
				)
				( attribute "LOCATION" "C2N14"
					( Origin gFrontEnd )
				)
				( attribute "MATERIAL" "X6S"
					( Origin gFrontEnd )
				)
				( attribute "PACK_TYPE" "0603"
					( Origin gFrontEnd )
				)
				( attribute "PART_NUMBER" "E15431-002"
					( Origin gFrontEnd )
				)
				( attribute "PHYS_PAGE" "130"
					( Origin gFrontEnd )
				)
				( attribute "ROOM" "SB_DECOUPLING"
					( Origin gFrontEnd )
				)
				( attribute "ROT" "0"
					( Origin gFrontEnd )
				)
				( attribute "SEC" "1"
					( Origin gPackager )
				)
				( attribute "TOLERANCE" "20%"
					( Origin gFrontEnd )
				)
				( attribute "VALUE" "10UF"
					( Origin gFrontEnd )
				)
				( attribute "VER" "1"
					( Origin gFrontEnd )
				)
				( attribute "VOLTAGE" "6.3V"
					( Units "uVoltage" "V" 1.000000)
					( Origin gFrontEnd )
				)
				( attribute "XY" "(-4575,4925)"
					( Origin gFrontEnd )
				)
				( attribute "CHIPS_PART_NAME" "CAP"
					( Origin gPackager )
				)
				( attribute "CDS_PART_NAME" "CAP_0603-10UF,6.3V,20%,X6S,E15A"
					( Origin gPackager )
				)
				( objectStatus "C2N14" )
				( pin "a"
					( attribute "PN" "1"
						( Origin gPackager )
					)
					( objectStatus "C2N14.1" )
				)
				( pin "b"
					( attribute "PN" "2"
						( Origin gPackager )
					)
					( objectStatus "C2N14.2" )
				)
			)
			( gate "@baseboard_fab2_lib.baseboard_fab2(sch_1):page130_i28"
				( attribute "BOM_COST" "SB"
					( Origin gFrontEnd )
				)
				( attribute "CDS_LIB" "mstr_discrete"
					( Origin gPackager )
				)
				( attribute "CDS_LOCATION" "C2N17"
					( Origin gPackager )
				)
				( attribute "CDS_SEC" "1"
					( Origin gPackager )
				)
				( attribute "LOCATION" "C2N17"
					( Origin gFrontEnd )
				)
				( attribute "MATERIAL" "X6S"
					( Origin gFrontEnd )
				)
				( attribute "PACK_TYPE" "0603"
					( Origin gFrontEnd )
				)
				( attribute "PART_NUMBER" "E15431-002"
					( Origin gFrontEnd )
				)
				( attribute "PHYS_PAGE" "130"
					( Origin gFrontEnd )
				)
				( attribute "ROOM" "SB_DECOUPLING"
					( Origin gFrontEnd )
				)
				( attribute "ROT" "0"
					( Origin gFrontEnd )
				)
				( attribute "SEC" "1"
					( Origin gPackager )
				)
				( attribute "TOLERANCE" "20%"
					( Origin gFrontEnd )
				)
				( attribute "VALUE" "10UF"
					( Origin gFrontEnd )
				)
				( attribute "VER" "1"
					( Origin gFrontEnd )
				)
				( attribute "VOLTAGE" "6.3V"
					( Units "uVoltage" "V" 1.000000)
					( Origin gFrontEnd )
				)
				( attribute "XY" "(-1475,3925)"
					( Origin gFrontEnd )
				)
				( attribute "CHIPS_PART_NAME" "CAP"
					( Origin gPackager )
				)
				( attribute "CDS_PART_NAME" "CAP_0603-10UF,6.3V,20%,X6S,E15A"
					( Origin gPackager )
				)
				( objectStatus "C2N17" )
				( pin "a"
					( attribute "PN" "1"
						( Origin gPackager )
					)
					( objectStatus "C2N17.1" )
				)
				( pin "b"
					( attribute "PN" "2"
						( Origin gPackager )
					)
					( objectStatus "C2N17.2" )
				)
			)
			( gate "@baseboard_fab2_lib.baseboard_fab2(sch_1):page130_i29"
				( attribute "BOM_COST" "SB"
					( Origin gFrontEnd )
				)
				( attribute "CDS_LIB" "dev_discrete"
					( Origin gPackager )
				)
				( attribute "CDS_LOCATION" "C2N18"
					( Origin gPackager )
				)
				( attribute "CDS_SEC" "1"
					( Origin gPackager )
				)
				( attribute "LOCATION" "C2N18"
					( Origin gFrontEnd )
				)
				( attribute "MATERIAL" "X6S"
					( Origin gFrontEnd )
				)
				( attribute "PACK_TYPE" "0402V"
					( Origin gFrontEnd )
				)
				( attribute "PART_NUMBER" "D97712-004"
					( Origin gFrontEnd )
				)
				( attribute "PHYS_PAGE" "130"
					( Origin gFrontEnd )
				)
				( attribute "ROOM" "SB_DECOUPLING"
					( Origin gFrontEnd )
				)
				( attribute "ROT" "0"
					( Origin gFrontEnd )
				)
				( attribute "SEC" "1"
					( Origin gPackager )
				)
				( attribute "TOLERANCE" "10%"
					( Origin gFrontEnd )
				)
				( attribute "VALUE" "1.0UF"
					( Origin gFrontEnd )
				)
				( attribute "VER" "1"
					( Origin gFrontEnd )
				)
				( attribute "VOLTAGE" "6.3V"
					( Units "uVoltage" "V" 1.000000)
					( Origin gFrontEnd )
				)
				( attribute "XY" "(-3450,3925)"
					( Origin gFrontEnd )
				)
				( attribute "CHIPS_PART_NAME" "CAP_A"
					( Origin gPackager )
				)
				( attribute "CDS_PART_NAME" "CAP_A_0402V-1.0UF,6.3V,10%,X6SA"
					( Origin gPackager )
				)
				( objectStatus "C2N18" )
				( pin "a"
					( attribute "PN" "1"
						( Origin gPackager )
					)
					( objectStatus "C2N18.1" )
				)
				( pin "b"
					( attribute "PN" "2"
						( Origin gPackager )
					)
					( objectStatus "C2N18.2" )
				)
			)
			( gate "@baseboard_fab2_lib.baseboard_fab2(sch_1):page130_i30"
				( attribute "BOM_COST" "SB"
					( Origin gFrontEnd )
				)
				( attribute "CDS_LIB" "dev_discrete"
					( Origin gPackager )
				)
				( attribute "CDS_LOCATION" "C8B2"
					( Origin gPackager )
				)
				( attribute "CDS_SEC" "1"
					( Origin gPackager )
				)
				( attribute "LOCATION" "C8B2"
					( Origin gFrontEnd )
				)
				( attribute "MATERIAL" "X6S"
					( Origin gFrontEnd )
				)
				( attribute "PACK_TYPE" "0603V"
					( Origin gFrontEnd )
				)
				( attribute "PART_NUMBER" "E15431-004"
					( Origin gFrontEnd )
				)
				( attribute "PHYS_PAGE" "130"
					( Origin gFrontEnd )
				)
				( attribute "ROOM" "SB_DECOUPLING"
					( Origin gFrontEnd )
				)
				( attribute "ROT" "0"
					( Origin gFrontEnd )
				)
				( attribute "SEC" "1"
					( Origin gPackager )
				)
				( attribute "TOLERANCE" "20%"
					( Origin gFrontEnd )
				)
				( attribute "VALUE" "22.0UF"
					( Origin gFrontEnd )
				)
				( attribute "VER" "1"
					( Origin gFrontEnd )
				)
				( attribute "VOLTAGE" "4V"
					( Units "uVoltage" "V" 1.000000)
					( Origin gFrontEnd )
				)
				( attribute "XY" "(-3100,2750)"
					( Origin gFrontEnd )
				)
				( attribute "CHIPS_PART_NAME" "CAP_A"
					( Origin gPackager )
				)
				( attribute "CDS_PART_NAME" "CAP_A_0603V-22.0UF,4V,20%,X6S,A"
					( Origin gPackager )
				)
				( objectStatus "C8B2" )
				( pin "a"
					( attribute "PN" "1"
						( Origin gPackager )
					)
					( objectStatus "C8B2.1" )
				)
				( pin "b"
					( attribute "PN" "2"
						( Origin gPackager )
					)
					( objectStatus "C8B2.2" )
				)
			)
			( gate "@baseboard_fab2_lib.baseboard_fab2(sch_1):page130_i32"
				( attribute "BOM_COST" "SB"
					( Origin gFrontEnd )
				)
				( attribute "CDS_LIB" "dev_discrete"
					( Origin gPackager )
				)
				( attribute "CDS_LOCATION" "C8B3"
					( Origin gPackager )
				)
				( attribute "CDS_SEC" "1"
					( Origin gPackager )
				)
				( attribute "LOCATION" "C8B3"
					( Origin gFrontEnd )
				)
				( attribute "MATERIAL" "X6S"
					( Origin gFrontEnd )
				)
				( attribute "PACK_TYPE" "0603V"
					( Origin gFrontEnd )
				)
				( attribute "PART_NUMBER" "E15431-004"
					( Origin gFrontEnd )
				)
				( attribute "PHYS_PAGE" "130"
					( Origin gFrontEnd )
				)
				( attribute "ROOM" "SB_DECOUPLING"
					( Origin gFrontEnd )
				)
				( attribute "ROT" "0"
					( Origin gFrontEnd )
				)
				( attribute "SEC" "1"
					( Origin gPackager )
				)
				( attribute "TOLERANCE" "20%"
					( Origin gFrontEnd )
				)
				( attribute "VALUE" "22.0UF"
					( Origin gFrontEnd )
				)
				( attribute "VER" "1"
					( Origin gFrontEnd )
				)
				( attribute "VOLTAGE" "4V"
					( Units "uVoltage" "V" 1.000000)
					( Origin gFrontEnd )
				)
				( attribute "XY" "(-1975,1900)"
					( Origin gFrontEnd )
				)
				( attribute "CHIPS_PART_NAME" "CAP_A"
					( Origin gPackager )
				)
				( attribute "CDS_PART_NAME" "CAP_A_0603V-22.0UF,4V,20%,X6S,A"
					( Origin gPackager )
				)
				( objectStatus "C8B3" )
				( pin "a"
					( attribute "PN" "1"
						( Origin gPackager )
					)
					( objectStatus "C8B3.1" )
				)
				( pin "b"
					( attribute "PN" "2"
						( Origin gPackager )
					)
					( objectStatus "C8B3.2" )
				)
			)
			( gate "@baseboard_fab2_lib.baseboard_fab2(sch_1):page130_i34"
				( attribute "BOM_COST" "SB"
					( Origin gFrontEnd )
				)
				( attribute "CDS_LIB" "dev_discrete"
					( Origin gPackager )
				)
				( attribute "CDS_LOCATION" "C2N25"
					( Origin gPackager )
				)
				( attribute "CDS_SEC" "1"
					( Origin gPackager )
				)
				( attribute "LOCATION" "C2N25"
					( Origin gFrontEnd )
				)
				( attribute "MATERIAL" "X6S"
					( Origin gFrontEnd )
				)
				( attribute "PACK_TYPE" "0402V"
					( Origin gFrontEnd )
				)
				( attribute "PART_NUMBER" "D97712-004"
					( Origin gFrontEnd )
				)
				( attribute "PHYS_PAGE" "130"
					( Origin gFrontEnd )
				)
				( attribute "ROOM" "SB_DECOUPLING"
					( Origin gFrontEnd )
				)
				( attribute "ROT" "0"
					( Origin gFrontEnd )
				)
				( attribute "SEC" "1"
					( Origin gPackager )
				)
				( attribute "TOLERANCE" "10%"
					( Origin gFrontEnd )
				)
				( attribute "VALUE" "1.0UF"
					( Origin gFrontEnd )
				)
				( attribute "VER" "1"
					( Origin gFrontEnd )
				)
				( attribute "VOLTAGE" "6.3V"
					( Units "uVoltage" "V" 1.000000)
					( Origin gFrontEnd )
				)
				( attribute "XY" "(-3825,3925)"
					( Origin gFrontEnd )
				)
				( attribute "CHIPS_PART_NAME" "CAP_A"
					( Origin gPackager )
				)
				( attribute "CDS_PART_NAME" "CAP_A_0402V-1.0UF,6.3V,10%,X6SA"
					( Origin gPackager )
				)
				( objectStatus "C2N25" )
				( pin "a"
					( attribute "PN" "1"
						( Origin gPackager )
					)
					( objectStatus "C2N25.1" )
				)
				( pin "b"
					( attribute "PN" "2"
						( Origin gPackager )
					)
					( objectStatus "C2N25.2" )
				)
			)
			( gate "@baseboard_fab2_lib.baseboard_fab2(sch_1):page130_i37"
				( attribute "BOM_COST" "SB"
					( Origin gFrontEnd )
				)
				( attribute "CDS_LIB" "dev_discrete"
					( Origin gPackager )
				)
				( attribute "CDS_LOCATION" "C2M16"
					( Origin gPackager )
				)
				( attribute "CDS_SEC" "1"
					( Origin gPackager )
				)
				( attribute "LOCATION" "C2M16"
					( Origin gFrontEnd )
				)
				( attribute "MATERIAL" "X6S"
					( Origin gFrontEnd )
				)
				( attribute "PACK_TYPE" "0402V"
					( Origin gFrontEnd )
				)
				( attribute "PART_NUMBER" "D97712-004"
					( Origin gFrontEnd )
				)
				( attribute "PHYS_PAGE" "130"
					( Origin gFrontEnd )
				)
				( attribute "ROOM" "SB_DECOUPLING"
					( Origin gFrontEnd )
				)
				( attribute "ROT" "0"
					( Origin gFrontEnd )
				)
				( attribute "SEC" "1"
					( Origin gPackager )
				)
				( attribute "TOLERANCE" "10%"
					( Origin gFrontEnd )
				)
				( attribute "VALUE" "1.0UF"
					( Origin gFrontEnd )
				)
				( attribute "VER" "1"
					( Origin gFrontEnd )
				)
				( attribute "VOLTAGE" "6.3V"
					( Units "uVoltage" "V" 1.000000)
					( Origin gFrontEnd )
				)
				( attribute "XY" "(-4200,3925)"
					( Origin gFrontEnd )
				)
				( attribute "CHIPS_PART_NAME" "CAP_A"
					( Origin gPackager )
				)
				( attribute "CDS_PART_NAME" "CAP_A_0402V-1.0UF,6.3V,10%,X6SA"
					( Origin gPackager )
				)
				( objectStatus "C2M16" )
				( pin "a"
					( attribute "PN" "1"
						( Origin gPackager )
					)
					( objectStatus "C2M16.1" )
				)
				( pin "b"
					( attribute "PN" "2"
						( Origin gPackager )
					)
					( objectStatus "C2M16.2" )
				)
			)
			( gate "@baseboard_fab2_lib.baseboard_fab2(sch_1):page130_i38"
				( attribute "BOM_COST" "SB"
					( Origin gFrontEnd )
				)
				( attribute "CDS_LIB" "dev_discrete"
					( Origin gPackager )
				)
				( attribute "CDS_LOCATION" "C7D3"
					( Origin gPackager )
				)
				( attribute "CDS_SEC" "1"
					( Origin gPackager )
				)
				( attribute "LOCATION" "C7D3"
					( Origin gFrontEnd )
				)
				( attribute "MATERIAL" "X6S"
					( Origin gFrontEnd )
				)
				( attribute "PACK_TYPE" "0603V"
					( Origin gFrontEnd )
				)
				( attribute "PART_NUMBER" "E15431-004"
					( Origin gFrontEnd )
				)
				( attribute "PHYS_PAGE" "130"
					( Origin gFrontEnd )
				)
				( attribute "ROOM" "SB_DECOUPLING"
					( Origin gFrontEnd )
				)
				( attribute "ROT" "0"
					( Origin gFrontEnd )
				)
				( attribute "SEC" "1"
					( Origin gPackager )
				)
				( attribute "TOLERANCE" "20%"
					( Origin gFrontEnd )
				)
				( attribute "VALUE" "22.0UF"
					( Origin gFrontEnd )
				)
				( attribute "VER" "1"
					( Origin gFrontEnd )
				)
				( attribute "VOLTAGE" "4V"
					( Units "uVoltage" "V" 1.000000)
					( Origin gFrontEnd )
				)
				( attribute "XY" "(-3525,2750)"
					( Origin gFrontEnd )
				)
				( attribute "CHIPS_PART_NAME" "CAP_A"
					( Origin gPackager )
				)
				( attribute "CDS_PART_NAME" "CAP_A_0603V-22.0UF,4V,20%,X6S,A"
					( Origin gPackager )
				)
				( objectStatus "C7D3" )
				( pin "a"
					( attribute "PN" "1"
						( Origin gPackager )
					)
					( objectStatus "C7D3.1" )
				)
				( pin "b"
					( attribute "PN" "2"
						( Origin gPackager )
					)
					( objectStatus "C7D3.2" )
				)
			)
			( gate "@baseboard_fab2_lib.baseboard_fab2(sch_1):page130_i39"
				( attribute "BOM_COST" "SB"
					( Origin gFrontEnd )
				)
				( attribute "CDS_LIB" "dev_discrete"
					( Origin gPackager )
				)
				( attribute "CDS_LOCATION" "C8B4"
					( Origin gPackager )
				)
				( attribute "CDS_SEC" "1"
					( Origin gPackager )
				)
				( attribute "LOCATION" "C8B4"
					( Origin gFrontEnd )
				)
				( attribute "MATERIAL" "X6S"
					( Origin gFrontEnd )
				)
				( attribute "PACK_TYPE" "0603V"
					( Origin gFrontEnd )
				)
				( attribute "PART_NUMBER" "E15431-004"
					( Origin gFrontEnd )
				)
				( attribute "PHYS_PAGE" "130"
					( Origin gFrontEnd )
				)
				( attribute "ROOM" "SB_DECOUPLING"
					( Origin gFrontEnd )
				)
				( attribute "ROT" "0"
					( Origin gFrontEnd )
				)
				( attribute "SEC" "1"
					( Origin gPackager )
				)
				( attribute "TOLERANCE" "20%"
					( Origin gFrontEnd )
				)
				( attribute "VALUE" "22.0UF"
					( Origin gFrontEnd )
				)
				( attribute "VER" "1"
					( Origin gFrontEnd )
				)
				( attribute "VOLTAGE" "4V"
					( Units "uVoltage" "V" 1.000000)
					( Origin gFrontEnd )
				)
				( attribute "XY" "(-3925,2750)"
					( Origin gFrontEnd )
				)
				( attribute "CHIPS_PART_NAME" "CAP_A"
					( Origin gPackager )
				)
				( attribute "CDS_PART_NAME" "CAP_A_0603V-22.0UF,4V,20%,X6S,A"
					( Origin gPackager )
				)
				( objectStatus "C8B4" )
				( pin "a"
					( attribute "PN" "1"
						( Origin gPackager )
					)
					( objectStatus "C8B4.1" )
				)
				( pin "b"
					( attribute "PN" "2"
						( Origin gPackager )
					)
					( objectStatus "C8B4.2" )
				)
			)
			( gate "@baseboard_fab2_lib.baseboard_fab2(sch_1):page130_i41"
				( attribute "BOM_COST" "SB"
					( Origin gFrontEnd )
				)
				( attribute "CDS_LIB" "dev_discrete"
					( Origin gPackager )
				)
				( attribute "CDS_LOCATION" "C8B1"
					( Origin gPackager )
				)
				( attribute "CDS_SEC" "1"
					( Origin gPackager )
				)
				( attribute "LOCATION" "C8B1"
					( Origin gFrontEnd )
				)
				( attribute "MATERIAL" "X6S"
					( Origin gFrontEnd )
				)
				( attribute "PACK_TYPE" "0603V"
					( Origin gFrontEnd )
				)
				( attribute "PART_NUMBER" "E15431-004"
					( Origin gFrontEnd )
				)
				( attribute "PHYS_PAGE" "130"
					( Origin gFrontEnd )
				)
				( attribute "ROOM" "SB_DECOUPLING"
					( Origin gFrontEnd )
				)
				( attribute "ROT" "0"
					( Origin gFrontEnd )
				)
				( attribute "SEC" "1"
					( Origin gPackager )
				)
				( attribute "TOLERANCE" "20%"
					( Origin gFrontEnd )
				)
				( attribute "VALUE" "22.0UF"
					( Origin gFrontEnd )
				)
				( attribute "VER" "1"
					( Origin gFrontEnd )
				)
				( attribute "VOLTAGE" "4V"
					( Units "uVoltage" "V" 1.000000)
					( Origin gFrontEnd )
				)
				( attribute "XY" "(-4350,2750)"
					( Origin gFrontEnd )
				)
				( attribute "CHIPS_PART_NAME" "CAP_A"
					( Origin gPackager )
				)
				( attribute "CDS_PART_NAME" "CAP_A_0603V-22.0UF,4V,20%,X6S,A"
					( Origin gPackager )
				)
				( objectStatus "C8B1" )
				( pin "a"
					( attribute "PN" "1"
						( Origin gPackager )
					)
					( objectStatus "C8B1.1" )
				)
				( pin "b"
					( attribute "PN" "2"
						( Origin gPackager )
					)
					( objectStatus "C8B1.2" )
				)
			)
			( gate "@baseboard_fab2_lib.baseboard_fab2(sch_1):page130_i42"
				( attribute "BOM_COST" "SB"
					( Origin gFrontEnd )
				)
				( attribute "CDS_LIB" "dev_discrete"
					( Origin gPackager )
				)
				( attribute "CDS_LOCATION" "C3N23"
					( Origin gPackager )
				)
				( attribute "CDS_SEC" "1"
					( Origin gPackager )
				)
				( attribute "LOCATION" "C3N23"
					( Origin gFrontEnd )
				)
				( attribute "MATERIAL" "X6S"
					( Origin gFrontEnd )
				)
				( attribute "PACK_TYPE" "0402V"
					( Origin gFrontEnd )
				)
				( attribute "PART_NUMBER" "D97712-004"
					( Origin gFrontEnd )
				)
				( attribute "PHYS_PAGE" "130"
					( Origin gFrontEnd )
				)
				( attribute "ROOM" "SB_DECOUPLING"
					( Origin gFrontEnd )
				)
				( attribute "ROT" "0"
					( Origin gFrontEnd )
				)
				( attribute "SEC" "1"
					( Origin gPackager )
				)
				( attribute "TOLERANCE" "10%"
					( Origin gFrontEnd )
				)
				( attribute "VALUE" "1.0UF"
					( Origin gFrontEnd )
				)
				( attribute "VER" "1"
					( Origin gFrontEnd )
				)
				( attribute "VOLTAGE" "6.3V"
					( Units "uVoltage" "V" 1.000000)
					( Origin gFrontEnd )
				)
				( attribute "XY" "(-4600,3925)"
					( Origin gFrontEnd )
				)
				( attribute "CHIPS_PART_NAME" "CAP_A"
					( Origin gPackager )
				)
				( attribute "CDS_PART_NAME" "CAP_A_0402V-1.0UF,6.3V,10%,X6SA"
					( Origin gPackager )
				)
				( objectStatus "C3N23" )
				( pin "a"
					( attribute "PN" "1"
						( Origin gPackager )
					)
					( objectStatus "C3N23.1" )
				)
				( pin "b"
					( attribute "PN" "2"
						( Origin gPackager )
					)
					( objectStatus "C3N23.2" )
				)
			)
			( gate "@baseboard_fab2_lib.baseboard_fab2(sch_1):page130_i43"
				( attribute "BOM_COST" "SB"
					( Origin gFrontEnd )
				)
				( attribute "CDS_LIB" "dev_discrete"
					( Origin gPackager )
				)
				( attribute "CDS_LOCATION" "C2M1"
					( Origin gPackager )
				)
				( attribute "CDS_SEC" "1"
					( Origin gPackager )
				)
				( attribute "LOCATION" "C2M1"
					( Origin gFrontEnd )
				)
				( attribute "MATERIAL" "X6S"
					( Origin gFrontEnd )
				)
				( attribute "PACK_TYPE" "0603V"
					( Origin gFrontEnd )
				)
				( attribute "PART_NUMBER" "E15431-004"
					( Origin gFrontEnd )
				)
				( attribute "PHYS_PAGE" "130"
					( Origin gFrontEnd )
				)
				( attribute "ROOM" "SB_DECOUPLING"
					( Origin gFrontEnd )
				)
				( attribute "ROT" "0"
					( Origin gFrontEnd )
				)
				( attribute "SEC" "1"
					( Origin gPackager )
				)
				( attribute "TOLERANCE" "20%"
					( Origin gFrontEnd )
				)
				( attribute "VALUE" "22.0UF"
					( Origin gFrontEnd )
				)
				( attribute "VER" "1"
					( Origin gFrontEnd )
				)
				( attribute "VOLTAGE" "4V"
					( Units "uVoltage" "V" 1.000000)
					( Origin gFrontEnd )
				)
				( attribute "XY" "(-4725,2750)"
					( Origin gFrontEnd )
				)
				( attribute "CHIPS_PART_NAME" "CAP_A"
					( Origin gPackager )
				)
				( attribute "CDS_PART_NAME" "CAP_A_0603V-22.0UF,4V,20%,X6S,A"
					( Origin gPackager )
				)
				( objectStatus "C2M1" )
				( pin "a"
					( attribute "PN" "1"
						( Origin gPackager )
					)
					( objectStatus "C2M1.1" )
				)
				( pin "b"
					( attribute "PN" "2"
						( Origin gPackager )
					)
					( objectStatus "C2M1.2" )
				)
			)
			( gate "@baseboard_fab2_lib.baseboard_fab2(sch_1):page130_i45"
				( attribute "BOM_COST" "SB"
					( Origin gFrontEnd )
				)
				( attribute "CDS_LIB" "dev_discrete"
					( Origin gPackager )
				)
				( attribute "CDS_LOCATION" "C2M2"
					( Origin gPackager )
				)
				( attribute "CDS_SEC" "1"
					( Origin gPackager )
				)
				( attribute "LOCATION" "C2M2"
					( Origin gFrontEnd )
				)
				( attribute "MATERIAL" "X6S"
					( Origin gFrontEnd )
				)
				( attribute "PACK_TYPE" "0603V"
					( Origin gFrontEnd )
				)
				( attribute "PART_NUMBER" "E15431-004"
					( Origin gFrontEnd )
				)
				( attribute "PHYS_PAGE" "130"
					( Origin gFrontEnd )
				)
				( attribute "ROOM" "SB_DECOUPLING"
					( Origin gFrontEnd )
				)
				( attribute "ROT" "0"
					( Origin gFrontEnd )
				)
				( attribute "SEC" "1"
					( Origin gPackager )
				)
				( attribute "TOLERANCE" "20%"
					( Origin gFrontEnd )
				)
				( attribute "VALUE" "22.0UF"
					( Origin gFrontEnd )
				)
				( attribute "VER" "1"
					( Origin gFrontEnd )
				)
				( attribute "VOLTAGE" "4V"
					( Units "uVoltage" "V" 1.000000)
					( Origin gFrontEnd )
				)
				( attribute "XY" "(-5150,2750)"
					( Origin gFrontEnd )
				)
				( attribute "CHIPS_PART_NAME" "CAP_A"
					( Origin gPackager )
				)
				( attribute "CDS_PART_NAME" "CAP_A_0603V-22.0UF,4V,20%,X6S,A"
					( Origin gPackager )
				)
				( objectStatus "C2M2" )
				( pin "a"
					( attribute "PN" "1"
						( Origin gPackager )
					)
					( objectStatus "C2M2.1" )
				)
				( pin "b"
					( attribute "PN" "2"
						( Origin gPackager )
					)
					( objectStatus "C2M2.2" )
				)
			)
			( gate "@baseboard_fab2_lib.baseboard_fab2(sch_1):page130_i47"
				( attribute "BOM_COST" "SB"
					( Origin gFrontEnd )
				)
				( attribute "CDS_LIB" "dev_discrete"
					( Origin gPackager )
				)
				( attribute "CDS_LOCATION" "C2N15"
					( Origin gPackager )
				)
				( attribute "CDS_SEC" "1"
					( Origin gPackager )
				)
				( attribute "LOCATION" "C2N15"
					( Origin gFrontEnd )
				)
				( attribute "MATERIAL" "X6S"
					( Origin gFrontEnd )
				)
				( attribute "PACK_TYPE" "0402V"
					( Origin gFrontEnd )
				)
				( attribute "PART_NUMBER" "D97712-004"
					( Origin gFrontEnd )
				)
				( attribute "PHYS_PAGE" "130"
					( Origin gFrontEnd )
				)
				( attribute "ROOM" "SB_DECOUPLING"
					( Origin gFrontEnd )
				)
				( attribute "ROT" "0"
					( Origin gFrontEnd )
				)
				( attribute "SEC" "1"
					( Origin gPackager )
				)
				( attribute "TOLERANCE" "10%"
					( Origin gFrontEnd )
				)
				( attribute "VALUE" "1.0UF"
					( Origin gFrontEnd )
				)
				( attribute "VER" "1"
					( Origin gFrontEnd )
				)
				( attribute "VOLTAGE" "6.3V"
					( Units "uVoltage" "V" 1.000000)
					( Origin gFrontEnd )
				)
				( attribute "XY" "(-3600,1475)"
					( Origin gFrontEnd )
				)
				( attribute "CHIPS_PART_NAME" "CAP_A"
					( Origin gPackager )
				)
				( attribute "CDS_PART_NAME" "CAP_A_0402V-1.0UF,6.3V,10%,X6SA"
					( Origin gPackager )
				)
				( objectStatus "C2N15" )
				( pin "a"
					( attribute "PN" "1"
						( Origin gPackager )
					)
					( objectStatus "C2N15.1" )
				)
				( pin "b"
					( attribute "PN" "2"
						( Origin gPackager )
					)
					( objectStatus "C2N15.2" )
				)
			)
			( gate "@baseboard_fab2_lib.baseboard_fab2(sch_1):page130_i49"
				( attribute "BOM_COST" "SB"
					( Origin gFrontEnd )
				)
				( attribute "CDS_LIB" "dev_discrete"
					( Origin gPackager )
				)
				( attribute "CDS_LOCATION" "C3N21"
					( Origin gPackager )
				)
				( attribute "CDS_SEC" "1"
					( Origin gPackager )
				)
				( attribute "LOCATION" "C3N21"
					( Origin gFrontEnd )
				)
				( attribute "MATERIAL" "X6S"
					( Origin gFrontEnd )
				)
				( attribute "PACK_TYPE" "0402V"
					( Origin gFrontEnd )
				)
				( attribute "PART_NUMBER" "D97712-004"
					( Origin gFrontEnd )
				)
				( attribute "PHYS_PAGE" "130"
					( Origin gFrontEnd )
				)
				( attribute "ROOM" "SB_DECOUPLING"
					( Origin gFrontEnd )
				)
				( attribute "ROT" "0"
					( Origin gFrontEnd )
				)
				( attribute "SEC" "1"
					( Origin gPackager )
				)
				( attribute "TOLERANCE" "10%"
					( Origin gFrontEnd )
				)
				( attribute "VALUE" "1.0UF"
					( Origin gFrontEnd )
				)
				( attribute "VER" "1"
					( Origin gFrontEnd )
				)
				( attribute "VOLTAGE" "6.3V"
					( Units "uVoltage" "V" 1.000000)
					( Origin gFrontEnd )
				)
				( attribute "XY" "(-3975,1475)"
					( Origin gFrontEnd )
				)
				( attribute "CHIPS_PART_NAME" "CAP_A"
					( Origin gPackager )
				)
				( attribute "CDS_PART_NAME" "CAP_A_0402V-1.0UF,6.3V,10%,X6SA"
					( Origin gPackager )
				)
				( objectStatus "C3N21" )
				( pin "a"
					( attribute "PN" "1"
						( Origin gPackager )
					)
					( objectStatus "C3N21.1" )
				)
				( pin "b"
					( attribute "PN" "2"
						( Origin gPackager )
					)
					( objectStatus "C3N21.2" )
				)
			)
			( gate "@baseboard_fab2_lib.baseboard_fab2(sch_1):page130_i50"
				( attribute "BOM_COST" "SB"
					( Origin gFrontEnd )
				)
				( attribute "CDS_LIB" "dev_discrete"
					( Origin gPackager )
				)
				( attribute "CDS_LOCATION" "C3N25"
					( Origin gPackager )
				)
				( attribute "CDS_SEC" "1"
					( Origin gPackager )
				)
				( attribute "LOCATION" "C3N25"
					( Origin gFrontEnd )
				)
				( attribute "MATERIAL" "X6S"
					( Origin gFrontEnd )
				)
				( attribute "PACK_TYPE" "0402V"
					( Origin gFrontEnd )
				)
				( attribute "PART_NUMBER" "D97712-004"
					( Origin gFrontEnd )
				)
				( attribute "PHYS_PAGE" "130"
					( Origin gFrontEnd )
				)
				( attribute "ROOM" "SB_DECOUPLING"
					( Origin gFrontEnd )
				)
				( attribute "ROT" "0"
					( Origin gFrontEnd )
				)
				( attribute "SEC" "1"
					( Origin gPackager )
				)
				( attribute "TOLERANCE" "10%"
					( Origin gFrontEnd )
				)
				( attribute "VALUE" "1.0UF"
					( Origin gFrontEnd )
				)
				( attribute "VER" "1"
					( Origin gFrontEnd )
				)
				( attribute "VOLTAGE" "6.3V"
					( Units "uVoltage" "V" 1.000000)
					( Origin gFrontEnd )
				)
				( attribute "XY" "(-4350,1475)"
					( Origin gFrontEnd )
				)
				( attribute "CHIPS_PART_NAME" "CAP_A"
					( Origin gPackager )
				)
				( attribute "CDS_PART_NAME" "CAP_A_0402V-1.0UF,6.3V,10%,X6SA"
					( Origin gPackager )
				)
				( objectStatus "C3N25" )
				( pin "a"
					( attribute "PN" "1"
						( Origin gPackager )
					)
					( objectStatus "C3N25.1" )
				)
				( pin "b"
					( attribute "PN" "2"
						( Origin gPackager )
					)
					( objectStatus "C3N25.2" )
				)
			)
			( gate "@baseboard_fab2_lib.baseboard_fab2(sch_1):page130_i52"
				( attribute "BOM_COST" "SB"
					( Origin gFrontEnd )
				)
				( attribute "CDS_LIB" "dev_discrete"
					( Origin gPackager )
				)
				( attribute "CDS_LOCATION" "C2N16"
					( Origin gPackager )
				)
				( attribute "CDS_SEC" "1"
					( Origin gPackager )
				)
				( attribute "LOCATION" "C2N16"
					( Origin gFrontEnd )
				)
				( attribute "MATERIAL" "X6S"
					( Origin gFrontEnd )
				)
				( attribute "PACK_TYPE" "0402V"
					( Origin gFrontEnd )
				)
				( attribute "PART_NUMBER" "D97712-004"
					( Origin gFrontEnd )
				)
				( attribute "PHYS_PAGE" "130"
					( Origin gFrontEnd )
				)
				( attribute "ROOM" "SB_DECOUPLING"
					( Origin gFrontEnd )
				)
				( attribute "ROT" "0"
					( Origin gFrontEnd )
				)
				( attribute "SEC" "1"
					( Origin gPackager )
				)
				( attribute "TOLERANCE" "10%"
					( Origin gFrontEnd )
				)
				( attribute "VALUE" "1.0UF"
					( Origin gFrontEnd )
				)
				( attribute "VER" "1"
					( Origin gFrontEnd )
				)
				( attribute "VOLTAGE" "6.3V"
					( Units "uVoltage" "V" 1.000000)
					( Origin gFrontEnd )
				)
				( attribute "XY" "(-4775,1475)"
					( Origin gFrontEnd )
				)
				( attribute "CHIPS_PART_NAME" "CAP_A"
					( Origin gPackager )
				)
				( attribute "CDS_PART_NAME" "CAP_A_0402V-1.0UF,6.3V,10%,X6SA"
					( Origin gPackager )
				)
				( objectStatus "C2N16" )
				( pin "a"
					( attribute "PN" "1"
						( Origin gPackager )
					)
					( objectStatus "C2N16.1" )
				)
				( pin "b"
					( attribute "PN" "2"
						( Origin gPackager )
					)
					( objectStatus "C2N16.2" )
				)
			)
			( gate "@baseboard_fab2_lib.baseboard_fab2(sch_1):page130_i53"
				( attribute "BOM_COST" "SB"
					( Origin gFrontEnd )
				)
				( attribute "CDS_LIB" "dev_discrete"
					( Origin gPackager )
				)
				( attribute "CDS_LOCATION" "C3N22"
					( Origin gPackager )
				)
				( attribute "CDS_SEC" "1"
					( Origin gPackager )
				)
				( attribute "LOCATION" "C3N22"
					( Origin gFrontEnd )
				)
				( attribute "MATERIAL" "X6S"
					( Origin gFrontEnd )
				)
				( attribute "PACK_TYPE" "0402V"
					( Origin gFrontEnd )
				)
				( attribute "PART_NUMBER" "D97712-004"
					( Origin gFrontEnd )
				)
				( attribute "PHYS_PAGE" "130"
					( Origin gFrontEnd )
				)
				( attribute "ROOM" "SB_DECOUPLING"
					( Origin gFrontEnd )
				)
				( attribute "ROT" "0"
					( Origin gFrontEnd )
				)
				( attribute "SEC" "1"
					( Origin gPackager )
				)
				( attribute "TOLERANCE" "10%"
					( Origin gFrontEnd )
				)
				( attribute "VALUE" "1.0UF"
					( Origin gFrontEnd )
				)
				( attribute "VER" "1"
					( Origin gFrontEnd )
				)
				( attribute "VOLTAGE" "6.3V"
					( Units "uVoltage" "V" 1.000000)
					( Origin gFrontEnd )
				)
				( attribute "XY" "(-5200,1475)"
					( Origin gFrontEnd )
				)
				( attribute "CHIPS_PART_NAME" "CAP_A"
					( Origin gPackager )
				)
				( attribute "CDS_PART_NAME" "CAP_A_0402V-1.0UF,6.3V,10%,X6SA"
					( Origin gPackager )
				)
				( objectStatus "C3N22" )
				( pin "a"
					( attribute "PN" "1"
						( Origin gPackager )
					)
					( objectStatus "C3N22.1" )
				)
				( pin "b"
					( attribute "PN" "2"
						( Origin gPackager )
					)
					( objectStatus "C3N22.2" )
				)
			)
			( gate "@baseboard_fab2_lib.baseboard_fab2(sch_1):page131_i1"
				( attribute "BOM_COST" "SB"
					( Origin gFrontEnd )
				)
				( attribute "CDS_LIB" "dev_discrete"
					( Origin gPackager )
				)
				( attribute "CDS_LOCATION" "C7B15"
					( Origin gPackager )
				)
				( attribute "CDS_SEC" "1"
					( Origin gPackager )
				)
				( attribute "LOCATION" "C7B15"
					( Origin gFrontEnd )
				)
				( attribute "MATERIAL" "X6S"
					( Origin gFrontEnd )
				)
				( attribute "PACK_TYPE" "0603V"
					( Origin gFrontEnd )
				)
				( attribute "PART_NUMBER" "E15431-004"
					( Origin gFrontEnd )
				)
				( attribute "PHYS_PAGE" "131"
					( Origin gFrontEnd )
				)
				( attribute "ROOM" "SB_DECOUPLING"
					( Origin gFrontEnd )
				)
				( attribute "ROT" "0"
					( Origin gFrontEnd )
				)
				( attribute "SEC" "1"
					( Origin gPackager )
				)
				( attribute "TOLERANCE" "20%"
					( Origin gFrontEnd )
				)
				( attribute "VALUE" "22.0UF"
					( Origin gFrontEnd )
				)
				( attribute "VER" "1"
					( Origin gFrontEnd )
				)
				( attribute "VOLTAGE" "4V"
					( Units "uVoltage" "V" 1.000000)
					( Origin gFrontEnd )
				)
				( attribute "XY" "(975,4975)"
					( Origin gFrontEnd )
				)
				( attribute "CHIPS_PART_NAME" "CAP_A"
					( Origin gPackager )
				)
				( attribute "CDS_PART_NAME" "CAP_A_0603V-22.0UF,4V,20%,X6S,A"
					( Origin gPackager )
				)
				( objectStatus "C7B15" )
				( pin "a"
					( attribute "PN" "1"
						( Origin gPackager )
					)
					( objectStatus "C7B15.1" )
				)
				( pin "b"
					( attribute "PN" "2"
						( Origin gPackager )
					)
					( objectStatus "C7B15.2" )
				)
			)
			( gate "@baseboard_fab2_lib.baseboard_fab2(sch_1):page131_i2"
				( attribute "BOM_COST" "SB"
					( Origin gFrontEnd )
				)
				( attribute "CDS_LIB" "dev_discrete"
					( Origin gPackager )
				)
				( attribute "CDS_LOCATION" "C7B19"
					( Origin gPackager )
				)
				( attribute "CDS_SEC" "1"
					( Origin gPackager )
				)
				( attribute "LOCATION" "C7B19"
					( Origin gFrontEnd )
				)
				( attribute "MATERIAL" "X6S"
					( Origin gFrontEnd )
				)
				( attribute "PACK_TYPE" "0603V"
					( Origin gFrontEnd )
				)
				( attribute "PART_NUMBER" "E15431-004"
					( Origin gFrontEnd )
				)
				( attribute "PHYS_PAGE" "131"
					( Origin gFrontEnd )
				)
				( attribute "ROOM" "SB_DECOUPLING"
					( Origin gFrontEnd )
				)
				( attribute "ROT" "0"
					( Origin gFrontEnd )
				)
				( attribute "SEC" "1"
					( Origin gPackager )
				)
				( attribute "TOLERANCE" "20%"
					( Origin gFrontEnd )
				)
				( attribute "VALUE" "22.0UF"
					( Origin gFrontEnd )
				)
				( attribute "VER" "1"
					( Origin gFrontEnd )
				)
				( attribute "VOLTAGE" "4V"
					( Units "uVoltage" "V" 1.000000)
					( Origin gFrontEnd )
				)
				( attribute "XY" "(500,4975)"
					( Origin gFrontEnd )
				)
				( attribute "CHIPS_PART_NAME" "CAP_A"
					( Origin gPackager )
				)
				( attribute "CDS_PART_NAME" "CAP_A_0603V-22.0UF,4V,20%,X6S,A"
					( Origin gPackager )
				)
				( objectStatus "C7B19" )
				( pin "a"
					( attribute "PN" "1"
						( Origin gPackager )
					)
					( objectStatus "C7B19.1" )
				)
				( pin "b"
					( attribute "PN" "2"
						( Origin gPackager )
					)
					( objectStatus "C7B19.2" )
				)
			)
			( gate "@baseboard_fab2_lib.baseboard_fab2(sch_1):page131_i3"
				( attribute "BOM_COST" "SB"
					( Origin gFrontEnd )
				)
				( attribute "CDS_LIB" "dev_discrete"
					( Origin gPackager )
				)
				( attribute "CDS_LOCATION" "C7B16"
					( Origin gPackager )
				)
				( attribute "CDS_SEC" "1"
					( Origin gPackager )
				)
				( attribute "LOCATION" "C7B16"
					( Origin gFrontEnd )
				)
				( attribute "MATERIAL" "X6S"
					( Origin gFrontEnd )
				)
				( attribute "PACK_TYPE" "0603V"
					( Origin gFrontEnd )
				)
				( attribute "PART_NUMBER" "E15431-004"
					( Origin gFrontEnd )
				)
				( attribute "PHYS_PAGE" "131"
					( Origin gFrontEnd )
				)
				( attribute "ROOM" "SB_DECOUPLING"
					( Origin gFrontEnd )
				)
				( attribute "ROT" "0"
					( Origin gFrontEnd )
				)
				( attribute "SEC" "1"
					( Origin gPackager )
				)
				( attribute "TOLERANCE" "20%"
					( Origin gFrontEnd )
				)
				( attribute "VALUE" "22.0UF"
					( Origin gFrontEnd )
				)
				( attribute "VER" "1"
					( Origin gFrontEnd )
				)
				( attribute "VOLTAGE" "4V"
					( Units "uVoltage" "V" 1.000000)
					( Origin gFrontEnd )
				)
				( attribute "XY" "(50,4975)"
					( Origin gFrontEnd )
				)
				( attribute "CHIPS_PART_NAME" "CAP_A"
					( Origin gPackager )
				)
				( attribute "CDS_PART_NAME" "CAP_A_0603V-22.0UF,4V,20%,X6S,A"
					( Origin gPackager )
				)
				( objectStatus "C7B16" )
				( pin "a"
					( attribute "PN" "1"
						( Origin gPackager )
					)
					( objectStatus "C7B16.1" )
				)
				( pin "b"
					( attribute "PN" "2"
						( Origin gPackager )
					)
					( objectStatus "C7B16.2" )
				)
			)
			( gate "@baseboard_fab2_lib.baseboard_fab2(sch_1):page131_i4"
				( attribute "BOM_COST" "SB"
					( Origin gFrontEnd )
				)
				( attribute "CDS_LIB" "dev_discrete"
					( Origin gPackager )
				)
				( attribute "CDS_LOCATION" "C7B21"
					( Origin gPackager )
				)
				( attribute "CDS_SEC" "1"
					( Origin gPackager )
				)
				( attribute "LOCATION" "C7B21"
					( Origin gFrontEnd )
				)
				( attribute "MATERIAL" "X6S"
					( Origin gFrontEnd )
				)
				( attribute "PACK_TYPE" "0603V"
					( Origin gFrontEnd )
				)
				( attribute "PART_NUMBER" "E15431-004"
					( Origin gFrontEnd )
				)
				( attribute "PHYS_PAGE" "131"
					( Origin gFrontEnd )
				)
				( attribute "ROOM" "SB_DECOUPLING"
					( Origin gFrontEnd )
				)
				( attribute "ROT" "0"
					( Origin gFrontEnd )
				)
				( attribute "SEC" "1"
					( Origin gPackager )
				)
				( attribute "TOLERANCE" "20%"
					( Origin gFrontEnd )
				)
				( attribute "VALUE" "22.0UF"
					( Origin gFrontEnd )
				)
				( attribute "VER" "1"
					( Origin gFrontEnd )
				)
				( attribute "VOLTAGE" "4V"
					( Units "uVoltage" "V" 1.000000)
					( Origin gFrontEnd )
				)
				( attribute "XY" "(-425,4975)"
					( Origin gFrontEnd )
				)
				( attribute "CHIPS_PART_NAME" "CAP_A"
					( Origin gPackager )
				)
				( attribute "CDS_PART_NAME" "CAP_A_0603V-22.0UF,4V,20%,X6S,A"
					( Origin gPackager )
				)
				( objectStatus "C7B21" )
				( pin "a"
					( attribute "PN" "1"
						( Origin gPackager )
					)
					( objectStatus "C7B21.1" )
				)
				( pin "b"
					( attribute "PN" "2"
						( Origin gPackager )
					)
					( objectStatus "C7B21.2" )
				)
			)
			( gate "@baseboard_fab2_lib.baseboard_fab2(sch_1):page131_i6"
				( attribute "BOM_COST" "SB"
					( Origin gFrontEnd )
				)
				( attribute "CDS_LIB" "dev_discrete"
					( Origin gPackager )
				)
				( attribute "CDS_LOCATION" "C7B20"
					( Origin gPackager )
				)
				( attribute "CDS_SEC" "1"
					( Origin gPackager )
				)
				( attribute "LOCATION" "C7B20"
					( Origin gFrontEnd )
				)
				( attribute "MATERIAL" "X6S"
					( Origin gFrontEnd )
				)
				( attribute "PACK_TYPE" "0603V"
					( Origin gFrontEnd )
				)
				( attribute "PART_NUMBER" "E15431-004"
					( Origin gFrontEnd )
				)
				( attribute "PHYS_PAGE" "131"
					( Origin gFrontEnd )
				)
				( attribute "ROOM" "SB_DECOUPLING"
					( Origin gFrontEnd )
				)
				( attribute "ROT" "0"
					( Origin gFrontEnd )
				)
				( attribute "SEC" "1"
					( Origin gPackager )
				)
				( attribute "TOLERANCE" "20%"
					( Origin gFrontEnd )
				)
				( attribute "VALUE" "22.0UF"
					( Origin gFrontEnd )
				)
				( attribute "VER" "1"
					( Origin gFrontEnd )
				)
				( attribute "VOLTAGE" "4V"
					( Units "uVoltage" "V" 1.000000)
					( Origin gFrontEnd )
				)
				( attribute "XY" "(-875,4975)"
					( Origin gFrontEnd )
				)
				( attribute "CHIPS_PART_NAME" "CAP_A"
					( Origin gPackager )
				)
				( attribute "CDS_PART_NAME" "CAP_A_0603V-22.0UF,4V,20%,X6S,A"
					( Origin gPackager )
				)
				( objectStatus "C7B20" )
				( pin "a"
					( attribute "PN" "1"
						( Origin gPackager )
					)
					( objectStatus "C7B20.1" )
				)
				( pin "b"
					( attribute "PN" "2"
						( Origin gPackager )
					)
					( objectStatus "C7B20.2" )
				)
			)
			( gate "@baseboard_fab2_lib.baseboard_fab2(sch_1):page131_i7"
				( attribute "BOM_COST" "SB"
					( Origin gFrontEnd )
				)
				( attribute "CDS_LIB" "dev_discrete"
					( Origin gPackager )
				)
				( attribute "CDS_LOCATION" "C7B23"
					( Origin gPackager )
				)
				( attribute "CDS_SEC" "1"
					( Origin gPackager )
				)
				( attribute "LOCATION" "C7B23"
					( Origin gFrontEnd )
				)
				( attribute "MATERIAL" "X6S"
					( Origin gFrontEnd )
				)
				( attribute "PACK_TYPE" "0603V"
					( Origin gFrontEnd )
				)
				( attribute "PART_NUMBER" "E15431-004"
					( Origin gFrontEnd )
				)
				( attribute "PHYS_PAGE" "131"
					( Origin gFrontEnd )
				)
				( attribute "ROOM" "SB_DECOUPLING"
					( Origin gFrontEnd )
				)
				( attribute "ROT" "0"
					( Origin gFrontEnd )
				)
				( attribute "SEC" "1"
					( Origin gPackager )
				)
				( attribute "TOLERANCE" "20%"
					( Origin gFrontEnd )
				)
				( attribute "VALUE" "22.0UF"
					( Origin gFrontEnd )
				)
				( attribute "VER" "1"
					( Origin gFrontEnd )
				)
				( attribute "VOLTAGE" "4V"
					( Units "uVoltage" "V" 1.000000)
					( Origin gFrontEnd )
				)
				( attribute "XY" "(975,4025)"
					( Origin gFrontEnd )
				)
				( attribute "CHIPS_PART_NAME" "CAP_A"
					( Origin gPackager )
				)
				( attribute "CDS_PART_NAME" "CAP_A_0603V-22.0UF,4V,20%,X6S,A"
					( Origin gPackager )
				)
				( objectStatus "C7B23" )
				( pin "a"
					( attribute "PN" "1"
						( Origin gPackager )
					)
					( objectStatus "C7B23.1" )
				)
				( pin "b"
					( attribute "PN" "2"
						( Origin gPackager )
					)
					( objectStatus "C7B23.2" )
				)
			)
			( gate "@baseboard_fab2_lib.baseboard_fab2(sch_1):page131_i8"
				( attribute "BOM_COST" "SB"
					( Origin gFrontEnd )
				)
				( attribute "CDS_LIB" "dev_discrete"
					( Origin gPackager )
				)
				( attribute "CDS_LOCATION" "C8B10"
					( Origin gPackager )
				)
				( attribute "CDS_SEC" "1"
					( Origin gPackager )
				)
				( attribute "LOCATION" "C8B10"
					( Origin gFrontEnd )
				)
				( attribute "MATERIAL" "X6S"
					( Origin gFrontEnd )
				)
				( attribute "PACK_TYPE" "0603V"
					( Origin gFrontEnd )
				)
				( attribute "PART_NUMBER" "E15431-004"
					( Origin gFrontEnd )
				)
				( attribute "PHYS_PAGE" "131"
					( Origin gFrontEnd )
				)
				( attribute "ROOM" "SB_DECOUPLING"
					( Origin gFrontEnd )
				)
				( attribute "ROT" "0"
					( Origin gFrontEnd )
				)
				( attribute "SEC" "1"
					( Origin gPackager )
				)
				( attribute "TOLERANCE" "20%"
					( Origin gFrontEnd )
				)
				( attribute "VALUE" "22.0UF"
					( Origin gFrontEnd )
				)
				( attribute "VER" "1"
					( Origin gFrontEnd )
				)
				( attribute "VOLTAGE" "4V"
					( Units "uVoltage" "V" 1.000000)
					( Origin gFrontEnd )
				)
				( attribute "XY" "(950,3025)"
					( Origin gFrontEnd )
				)
				( attribute "CHIPS_PART_NAME" "CAP_A"
					( Origin gPackager )
				)
				( attribute "CDS_PART_NAME" "CAP_A_0603V-22.0UF,4V,20%,X6S,A"
					( Origin gPackager )
				)
				( objectStatus "C8B10" )
				( pin "a"
					( attribute "PN" "1"
						( Origin gPackager )
					)
					( objectStatus "C8B10.1" )
				)
				( pin "b"
					( attribute "PN" "2"
						( Origin gPackager )
					)
					( objectStatus "C8B10.2" )
				)
			)
			( gate "@baseboard_fab2_lib.baseboard_fab2(sch_1):page131_i10"
				( attribute "BOM_COST" "SB"
					( Origin gFrontEnd )
				)
				( attribute "CDS_LIB" "dev_discrete"
					( Origin gPackager )
				)
				( attribute "CDS_LOCATION" "C7B22"
					( Origin gPackager )
				)
				( attribute "CDS_SEC" "1"
					( Origin gPackager )
				)
				( attribute "LOCATION" "C7B22"
					( Origin gFrontEnd )
				)
				( attribute "MATERIAL" "X6S"
					( Origin gFrontEnd )
				)
				( attribute "PACK_TYPE" "0603V"
					( Origin gFrontEnd )
				)
				( attribute "PART_NUMBER" "E15431-004"
					( Origin gFrontEnd )
				)
				( attribute "PHYS_PAGE" "131"
					( Origin gFrontEnd )
				)
				( attribute "ROOM" "SB_DECOUPLING"
					( Origin gFrontEnd )
				)
				( attribute "ROT" "0"
					( Origin gFrontEnd )
				)
				( attribute "SEC" "1"
					( Origin gPackager )
				)
				( attribute "TOLERANCE" "20%"
					( Origin gFrontEnd )
				)
				( attribute "VALUE" "22.0UF"
					( Origin gFrontEnd )
				)
				( attribute "VER" "1"
					( Origin gFrontEnd )
				)
				( attribute "VOLTAGE" "4V"
					( Units "uVoltage" "V" 1.000000)
					( Origin gFrontEnd )
				)
				( attribute "XY" "(500,4025)"
					( Origin gFrontEnd )
				)
				( attribute "CHIPS_PART_NAME" "CAP_A"
					( Origin gPackager )
				)
				( attribute "CDS_PART_NAME" "CAP_A_0603V-22.0UF,4V,20%,X6S,A"
					( Origin gPackager )
				)
				( objectStatus "C7B22" )
				( pin "a"
					( attribute "PN" "1"
						( Origin gPackager )
					)
					( objectStatus "C7B22.1" )
				)
				( pin "b"
					( attribute "PN" "2"
						( Origin gPackager )
					)
					( objectStatus "C7B22.2" )
				)
			)
			( gate "@baseboard_fab2_lib.baseboard_fab2(sch_1):page131_i11"
				( attribute "BOM_COST" "SB"
					( Origin gFrontEnd )
				)
				( attribute "CDS_LIB" "dev_discrete"
					( Origin gPackager )
				)
				( attribute "CDS_LOCATION" "C7B24"
					( Origin gPackager )
				)
				( attribute "CDS_SEC" "1"
					( Origin gPackager )
				)
				( attribute "LOCATION" "C7B24"
					( Origin gFrontEnd )
				)
				( attribute "MATERIAL" "X6S"
					( Origin gFrontEnd )
				)
				( attribute "PACK_TYPE" "0603V"
					( Origin gFrontEnd )
				)
				( attribute "PART_NUMBER" "E15431-004"
					( Origin gFrontEnd )
				)
				( attribute "PHYS_PAGE" "131"
					( Origin gFrontEnd )
				)
				( attribute "ROOM" "SB_DECOUPLING"
					( Origin gFrontEnd )
				)
				( attribute "ROT" "0"
					( Origin gFrontEnd )
				)
				( attribute "SEC" "1"
					( Origin gPackager )
				)
				( attribute "TOLERANCE" "20%"
					( Origin gFrontEnd )
				)
				( attribute "VALUE" "22.0UF"
					( Origin gFrontEnd )
				)
				( attribute "VER" "1"
					( Origin gFrontEnd )
				)
				( attribute "VOLTAGE" "4V"
					( Units "uVoltage" "V" 1.000000)
					( Origin gFrontEnd )
				)
				( attribute "XY" "(50,4025)"
					( Origin gFrontEnd )
				)
				( attribute "CHIPS_PART_NAME" "CAP_A"
					( Origin gPackager )
				)
				( attribute "CDS_PART_NAME" "CAP_A_0603V-22.0UF,4V,20%,X6S,A"
					( Origin gPackager )
				)
				( objectStatus "C7B24" )
				( pin "a"
					( attribute "PN" "1"
						( Origin gPackager )
					)
					( objectStatus "C7B24.1" )
				)
				( pin "b"
					( attribute "PN" "2"
						( Origin gPackager )
					)
					( objectStatus "C7B24.2" )
				)
			)
			( gate "@baseboard_fab2_lib.baseboard_fab2(sch_1):page131_i12"
				( attribute "BOM_COST" "SB"
					( Origin gFrontEnd )
				)
				( attribute "CDS_LIB" "dev_discrete"
					( Origin gPackager )
				)
				( attribute "CDS_LOCATION" "C7B18"
					( Origin gPackager )
				)
				( attribute "CDS_SEC" "1"
					( Origin gPackager )
				)
				( attribute "LOCATION" "C7B18"
					( Origin gFrontEnd )
				)
				( attribute "MATERIAL" "X6S"
					( Origin gFrontEnd )
				)
				( attribute "PACK_TYPE" "0603V"
					( Origin gFrontEnd )
				)
				( attribute "PART_NUMBER" "E15431-004"
					( Origin gFrontEnd )
				)
				( attribute "PHYS_PAGE" "131"
					( Origin gFrontEnd )
				)
				( attribute "ROOM" "SB_DECOUPLING"
					( Origin gFrontEnd )
				)
				( attribute "ROT" "0"
					( Origin gFrontEnd )
				)
				( attribute "SEC" "1"
					( Origin gPackager )
				)
				( attribute "TOLERANCE" "20%"
					( Origin gFrontEnd )
				)
				( attribute "VALUE" "22.0UF"
					( Origin gFrontEnd )
				)
				( attribute "VER" "1"
					( Origin gFrontEnd )
				)
				( attribute "VOLTAGE" "4V"
					( Units "uVoltage" "V" 1.000000)
					( Origin gFrontEnd )
				)
				( attribute "XY" "(-425,4025)"
					( Origin gFrontEnd )
				)
				( attribute "CHIPS_PART_NAME" "CAP_A"
					( Origin gPackager )
				)
				( attribute "CDS_PART_NAME" "CAP_A_0603V-22.0UF,4V,20%,X6S,A"
					( Origin gPackager )
				)
				( objectStatus "C7B18" )
				( pin "a"
					( attribute "PN" "1"
						( Origin gPackager )
					)
					( objectStatus "C7B18.1" )
				)
				( pin "b"
					( attribute "PN" "2"
						( Origin gPackager )
					)
					( objectStatus "C7B18.2" )
				)
			)
			( gate "@baseboard_fab2_lib.baseboard_fab2(sch_1):page131_i14"
				( attribute "BOM_COST" "SB"
					( Origin gFrontEnd )
				)
				( attribute "CDS_LIB" "dev_discrete"
					( Origin gPackager )
				)
				( attribute "CDS_LOCATION" "C8B9"
					( Origin gPackager )
				)
				( attribute "CDS_SEC" "1"
					( Origin gPackager )
				)
				( attribute "LOCATION" "C8B9"
					( Origin gFrontEnd )
				)
				( attribute "MATERIAL" "X6S"
					( Origin gFrontEnd )
				)
				( attribute "PACK_TYPE" "0603V"
					( Origin gFrontEnd )
				)
				( attribute "PART_NUMBER" "E15431-004"
					( Origin gFrontEnd )
				)
				( attribute "PHYS_PAGE" "131"
					( Origin gFrontEnd )
				)
				( attribute "ROOM" "SB_DECOUPLING"
					( Origin gFrontEnd )
				)
				( attribute "ROT" "0"
					( Origin gFrontEnd )
				)
				( attribute "SEC" "1"
					( Origin gPackager )
				)
				( attribute "TOLERANCE" "20%"
					( Origin gFrontEnd )
				)
				( attribute "VALUE" "22.0UF"
					( Origin gFrontEnd )
				)
				( attribute "VER" "1"
					( Origin gFrontEnd )
				)
				( attribute "VOLTAGE" "4V"
					( Units "uVoltage" "V" 1.000000)
					( Origin gFrontEnd )
				)
				( attribute "XY" "(500,3025)"
					( Origin gFrontEnd )
				)
				( attribute "CHIPS_PART_NAME" "CAP_A"
					( Origin gPackager )
				)
				( attribute "CDS_PART_NAME" "CAP_A_0603V-22.0UF,4V,20%,X6S,A"
					( Origin gPackager )
				)
				( objectStatus "C8B9" )
				( pin "a"
					( attribute "PN" "1"
						( Origin gPackager )
					)
					( objectStatus "C8B9.1" )
				)
				( pin "b"
					( attribute "PN" "2"
						( Origin gPackager )
					)
					( objectStatus "C8B9.2" )
				)
			)
			( gate "@baseboard_fab2_lib.baseboard_fab2(sch_1):page131_i15"
				( attribute "BOM_COST" "SB"
					( Origin gFrontEnd )
				)
				( attribute "CDS_LIB" "dev_discrete"
					( Origin gPackager )
				)
				( attribute "CDS_LOCATION" "C8B11"
					( Origin gPackager )
				)
				( attribute "CDS_SEC" "1"
					( Origin gPackager )
				)
				( attribute "LOCATION" "C8B11"
					( Origin gFrontEnd )
				)
				( attribute "MATERIAL" "X6S"
					( Origin gFrontEnd )
				)
				( attribute "PACK_TYPE" "0603V"
					( Origin gFrontEnd )
				)
				( attribute "PART_NUMBER" "E15431-004"
					( Origin gFrontEnd )
				)
				( attribute "PHYS_PAGE" "131"
					( Origin gFrontEnd )
				)
				( attribute "ROOM" "SB_DECOUPLING"
					( Origin gFrontEnd )
				)
				( attribute "ROT" "0"
					( Origin gFrontEnd )
				)
				( attribute "SEC" "1"
					( Origin gPackager )
				)
				( attribute "TOLERANCE" "20%"
					( Origin gFrontEnd )
				)
				( attribute "VALUE" "22.0UF"
					( Origin gFrontEnd )
				)
				( attribute "VER" "1"
					( Origin gFrontEnd )
				)
				( attribute "VOLTAGE" "4V"
					( Units "uVoltage" "V" 1.000000)
					( Origin gFrontEnd )
				)
				( attribute "XY" "(50,3025)"
					( Origin gFrontEnd )
				)
				( attribute "CHIPS_PART_NAME" "CAP_A"
					( Origin gPackager )
				)
				( attribute "CDS_PART_NAME" "CAP_A_0603V-22.0UF,4V,20%,X6S,A"
					( Origin gPackager )
				)
				( objectStatus "C8B11" )
				( pin "a"
					( attribute "PN" "1"
						( Origin gPackager )
					)
					( objectStatus "C8B11.1" )
				)
				( pin "b"
					( attribute "PN" "2"
						( Origin gPackager )
					)
					( objectStatus "C8B11.2" )
				)
			)
			( gate "@baseboard_fab2_lib.baseboard_fab2(sch_1):page131_i16"
				( attribute "BOM_COST" "SB"
					( Origin gFrontEnd )
				)
				( attribute "CDS_LIB" "dev_discrete"
					( Origin gPackager )
				)
				( attribute "CDS_LOCATION" "C8B14"
					( Origin gPackager )
				)
				( attribute "CDS_SEC" "1"
					( Origin gPackager )
				)
				( attribute "LOCATION" "C8B14"
					( Origin gFrontEnd )
				)
				( attribute "MATERIAL" "X6S"
					( Origin gFrontEnd )
				)
				( attribute "PACK_TYPE" "0603V"
					( Origin gFrontEnd )
				)
				( attribute "PART_NUMBER" "E15431-004"
					( Origin gFrontEnd )
				)
				( attribute "PHYS_PAGE" "131"
					( Origin gFrontEnd )
				)
				( attribute "ROOM" "SB_DECOUPLING"
					( Origin gFrontEnd )
				)
				( attribute "ROT" "0"
					( Origin gFrontEnd )
				)
				( attribute "SEC" "1"
					( Origin gPackager )
				)
				( attribute "TOLERANCE" "20%"
					( Origin gFrontEnd )
				)
				( attribute "VALUE" "22.0UF"
					( Origin gFrontEnd )
				)
				( attribute "VER" "1"
					( Origin gFrontEnd )
				)
				( attribute "VOLTAGE" "4V"
					( Units "uVoltage" "V" 1.000000)
					( Origin gFrontEnd )
				)
				( attribute "XY" "(-400,3025)"
					( Origin gFrontEnd )
				)
				( attribute "CHIPS_PART_NAME" "CAP_A"
					( Origin gPackager )
				)
				( attribute "CDS_PART_NAME" "CAP_A_0603V-22.0UF,4V,20%,X6S,A"
					( Origin gPackager )
				)
				( objectStatus "C8B14" )
				( pin "a"
					( attribute "PN" "1"
						( Origin gPackager )
					)
					( objectStatus "C8B14.1" )
				)
				( pin "b"
					( attribute "PN" "2"
						( Origin gPackager )
					)
					( objectStatus "C8B14.2" )
				)
			)
			( gate "@baseboard_fab2_lib.baseboard_fab2(sch_1):page131_i18"
				( attribute "BOM_COST" "SB"
					( Origin gFrontEnd )
				)
				( attribute "CDS_LIB" "dev_discrete"
					( Origin gPackager )
				)
				( attribute "CDS_LOCATION" "C7B17"
					( Origin gPackager )
				)
				( attribute "CDS_SEC" "1"
					( Origin gPackager )
				)
				( attribute "LOCATION" "C7B17"
					( Origin gFrontEnd )
				)
				( attribute "MATERIAL" "X6S"
					( Origin gFrontEnd )
				)
				( attribute "PACK_TYPE" "0603V"
					( Origin gFrontEnd )
				)
				( attribute "PART_NUMBER" "E15431-004"
					( Origin gFrontEnd )
				)
				( attribute "PHYS_PAGE" "131"
					( Origin gFrontEnd )
				)
				( attribute "ROOM" "SB_DECOUPLING"
					( Origin gFrontEnd )
				)
				( attribute "ROT" "0"
					( Origin gFrontEnd )
				)
				( attribute "SEC" "1"
					( Origin gPackager )
				)
				( attribute "TOLERANCE" "20%"
					( Origin gFrontEnd )
				)
				( attribute "VALUE" "22.0UF"
					( Origin gFrontEnd )
				)
				( attribute "VER" "1"
					( Origin gFrontEnd )
				)
				( attribute "VOLTAGE" "4V"
					( Units "uVoltage" "V" 1.000000)
					( Origin gFrontEnd )
				)
				( attribute "XY" "(-875,4025)"
					( Origin gFrontEnd )
				)
				( attribute "CHIPS_PART_NAME" "CAP_A"
					( Origin gPackager )
				)
				( attribute "CDS_PART_NAME" "CAP_A_0603V-22.0UF,4V,20%,X6S,A"
					( Origin gPackager )
				)
				( objectStatus "C7B17" )
				( pin "a"
					( attribute "PN" "1"
						( Origin gPackager )
					)
					( objectStatus "C7B17.1" )
				)
				( pin "b"
					( attribute "PN" "2"
						( Origin gPackager )
					)
					( objectStatus "C7B17.2" )
				)
			)
			( gate "@baseboard_fab2_lib.baseboard_fab2(sch_1):page131_i20"
				( attribute "BOM_COST" "SB"
					( Origin gFrontEnd )
				)
				( attribute "CDS_LIB" "dev_discrete"
					( Origin gPackager )
				)
				( attribute "CDS_LOCATION" "C8B13"
					( Origin gPackager )
				)
				( attribute "CDS_SEC" "1"
					( Origin gPackager )
				)
				( attribute "LOCATION" "C8B13"
					( Origin gFrontEnd )
				)
				( attribute "MATERIAL" "X6S"
					( Origin gFrontEnd )
				)
				( attribute "PACK_TYPE" "0603V"
					( Origin gFrontEnd )
				)
				( attribute "PART_NUMBER" "E15431-004"
					( Origin gFrontEnd )
				)
				( attribute "PHYS_PAGE" "131"
					( Origin gFrontEnd )
				)
				( attribute "ROOM" "SB_DECOUPLING"
					( Origin gFrontEnd )
				)
				( attribute "ROT" "0"
					( Origin gFrontEnd )
				)
				( attribute "SEC" "1"
					( Origin gPackager )
				)
				( attribute "TOLERANCE" "20%"
					( Origin gFrontEnd )
				)
				( attribute "VALUE" "22.0UF"
					( Origin gFrontEnd )
				)
				( attribute "VER" "1"
					( Origin gFrontEnd )
				)
				( attribute "VOLTAGE" "4V"
					( Units "uVoltage" "V" 1.000000)
					( Origin gFrontEnd )
				)
				( attribute "XY" "(-850,3025)"
					( Origin gFrontEnd )
				)
				( attribute "CHIPS_PART_NAME" "CAP_A"
					( Origin gPackager )
				)
				( attribute "CDS_PART_NAME" "CAP_A_0603V-22.0UF,4V,20%,X6S,A"
					( Origin gPackager )
				)
				( objectStatus "C8B13" )
				( pin "a"
					( attribute "PN" "1"
						( Origin gPackager )
					)
					( objectStatus "C8B13.1" )
				)
				( pin "b"
					( attribute "PN" "2"
						( Origin gPackager )
					)
					( objectStatus "C8B13.2" )
				)
			)
			( gate "@baseboard_fab2_lib.baseboard_fab2(sch_1):page131_i22"
				( attribute "BOM_COST" "SB"
					( Origin gFrontEnd )
				)
				( attribute "CDS_LIB" "mstr_discrete"
					( Origin gPackager )
				)
				( attribute "CDS_LOCATION" "C8B16"
					( Origin gPackager )
				)
				( attribute "CDS_SEC" "1"
					( Origin gPackager )
				)
				( attribute "LOCATION" "C8B16"
					( Origin gFrontEnd )
				)
				( attribute "MATERIAL" "X6S"
					( Origin gFrontEnd )
				)
				( attribute "PACK_TYPE" "0805"
					( Origin gFrontEnd )
				)
				( attribute "PART_NUMBER" "C95333-006"
					( Origin gFrontEnd )
				)
				( attribute "PHYS_PAGE" "131"
					( Origin gFrontEnd )
				)
				( attribute "ROOM" "SB_DECOUPLING"
					( Origin gFrontEnd )
				)
				( attribute "ROT" "0"
					( Origin gFrontEnd )
				)
				( attribute "SEC" "1"
					( Origin gPackager )
				)
				( attribute "TOLERANCE" "20%"
					( Origin gFrontEnd )
				)
				( attribute "VALUE" "47UF"
					( Origin gFrontEnd )
				)
				( attribute "VER" "1"
					( Origin gFrontEnd )
				)
				( attribute "VOLTAGE" "4V"
					( Units "uVoltage" "V" 1.000000)
					( Origin gFrontEnd )
				)
				( attribute "XY" "(50,2025)"
					( Origin gFrontEnd )
				)
				( attribute "CHIPS_PART_NAME" "CAP"
					( Origin gPackager )
				)
				( attribute "CDS_PART_NAME" "CAP_0805-47UF,4V,20%,X6S,C9533A"
					( Origin gPackager )
				)
				( objectStatus "C8B16" )
				( pin "a"
					( attribute "PN" "1"
						( Origin gPackager )
					)
					( objectStatus "C8B16.1" )
				)
				( pin "b"
					( attribute "PN" "2"
						( Origin gPackager )
					)
					( objectStatus "C8B16.2" )
				)
			)
			( gate "@baseboard_fab2_lib.baseboard_fab2(sch_1):page131_i24"
				( attribute "BOM_COST" "SB"
					( Origin gFrontEnd )
				)
				( attribute "CDS_LIB" "mstr_discrete"
					( Origin gPackager )
				)
				( attribute "CDS_LOCATION" "C8B15"
					( Origin gPackager )
				)
				( attribute "CDS_SEC" "1"
					( Origin gPackager )
				)
				( attribute "LOCATION" "C8B15"
					( Origin gFrontEnd )
				)
				( attribute "MATERIAL" "X6S"
					( Origin gFrontEnd )
				)
				( attribute "PACK_TYPE" "0805"
					( Origin gFrontEnd )
				)
				( attribute "PART_NUMBER" "C95333-006"
					( Origin gFrontEnd )
				)
				( attribute "PHYS_PAGE" "131"
					( Origin gFrontEnd )
				)
				( attribute "ROOM" "SB_DECOUPLING"
					( Origin gFrontEnd )
				)
				( attribute "ROT" "0"
					( Origin gFrontEnd )
				)
				( attribute "SEC" "1"
					( Origin gPackager )
				)
				( attribute "TOLERANCE" "20%"
					( Origin gFrontEnd )
				)
				( attribute "VALUE" "47UF"
					( Origin gFrontEnd )
				)
				( attribute "VER" "1"
					( Origin gFrontEnd )
				)
				( attribute "VOLTAGE" "4V"
					( Units "uVoltage" "V" 1.000000)
					( Origin gFrontEnd )
				)
				( attribute "XY" "(-400,2025)"
					( Origin gFrontEnd )
				)
				( attribute "CHIPS_PART_NAME" "CAP"
					( Origin gPackager )
				)
				( attribute "CDS_PART_NAME" "CAP_0805-47UF,4V,20%,X6S,C9533A"
					( Origin gPackager )
				)
				( objectStatus "C8B15" )
				( pin "a"
					( attribute "PN" "1"
						( Origin gPackager )
					)
					( objectStatus "C8B15.1" )
				)
				( pin "b"
					( attribute "PN" "2"
						( Origin gPackager )
					)
					( objectStatus "C8B15.2" )
				)
			)
			( gate "@baseboard_fab2_lib.baseboard_fab2(sch_1):page131_i27"
				( attribute "BOM_COST" "SB"
					( Origin gFrontEnd )
				)
				( attribute "CDS_LIB" "dev_discrete"
					( Origin gPackager )
				)
				( attribute "CDS_LOCATION" "C2M22"
					( Origin gPackager )
				)
				( attribute "CDS_SEC" "1"
					( Origin gPackager )
				)
				( attribute "LOCATION" "C2M22"
					( Origin gFrontEnd )
				)
				( attribute "MATERIAL" "X6S"
					( Origin gFrontEnd )
				)
				( attribute "PACK_TYPE" "0402V"
					( Origin gFrontEnd )
				)
				( attribute "PART_NUMBER" "D97712-004"
					( Origin gFrontEnd )
				)
				( attribute "PHYS_PAGE" "131"
					( Origin gFrontEnd )
				)
				( attribute "ROOM" "SB_DECOUPLING"
					( Origin gFrontEnd )
				)
				( attribute "ROT" "0"
					( Origin gFrontEnd )
				)
				( attribute "SEC" "1"
					( Origin gPackager )
				)
				( attribute "TOLERANCE" "10%"
					( Origin gFrontEnd )
				)
				( attribute "VALUE" "1.0UF"
					( Origin gFrontEnd )
				)
				( attribute "VER" "1"
					( Origin gFrontEnd )
				)
				( attribute "VOLTAGE" "6.3V"
					( Units "uVoltage" "V" 1.000000)
					( Origin gFrontEnd )
				)
				( attribute "XY" "(-2375,4725)"
					( Origin gFrontEnd )
				)
				( attribute "CHIPS_PART_NAME" "CAP_A"
					( Origin gPackager )
				)
				( attribute "CDS_PART_NAME" "CAP_A_0402V-1.0UF,6.3V,10%,X6SA"
					( Origin gPackager )
				)
				( objectStatus "C2M22" )
				( pin "a"
					( attribute "PN" "1"
						( Origin gPackager )
					)
					( objectStatus "C2M22.1" )
				)
				( pin "b"
					( attribute "PN" "2"
						( Origin gPackager )
					)
					( objectStatus "C2M22.2" )
				)
			)
			( gate "@baseboard_fab2_lib.baseboard_fab2(sch_1):page131_i28"
				( attribute "BOM_COST" "SB"
					( Origin gFrontEnd )
				)
				( attribute "CDS_LIB" "dev_discrete"
					( Origin gPackager )
				)
				( attribute "CDS_LOCATION" "C2M21"
					( Origin gPackager )
				)
				( attribute "CDS_SEC" "1"
					( Origin gPackager )
				)
				( attribute "LOCATION" "C2M21"
					( Origin gFrontEnd )
				)
				( attribute "MATERIAL" "X6S"
					( Origin gFrontEnd )
				)
				( attribute "PACK_TYPE" "0402V"
					( Origin gFrontEnd )
				)
				( attribute "PART_NUMBER" "D97712-004"
					( Origin gFrontEnd )
				)
				( attribute "PHYS_PAGE" "131"
					( Origin gFrontEnd )
				)
				( attribute "ROOM" "SB_DECOUPLING"
					( Origin gFrontEnd )
				)
				( attribute "ROT" "0"
					( Origin gFrontEnd )
				)
				( attribute "SEC" "1"
					( Origin gPackager )
				)
				( attribute "TOLERANCE" "10%"
					( Origin gFrontEnd )
				)
				( attribute "VALUE" "1.0UF"
					( Origin gFrontEnd )
				)
				( attribute "VER" "1"
					( Origin gFrontEnd )
				)
				( attribute "VOLTAGE" "6.3V"
					( Units "uVoltage" "V" 1.000000)
					( Origin gFrontEnd )
				)
				( attribute "XY" "(-2800,4725)"
					( Origin gFrontEnd )
				)
				( attribute "CHIPS_PART_NAME" "CAP_A"
					( Origin gPackager )
				)
				( attribute "CDS_PART_NAME" "CAP_A_0402V-1.0UF,6.3V,10%,X6SA"
					( Origin gPackager )
				)
				( objectStatus "C2M21" )
				( pin "a"
					( attribute "PN" "1"
						( Origin gPackager )
					)
					( objectStatus "C2M21.1" )
				)
				( pin "b"
					( attribute "PN" "2"
						( Origin gPackager )
					)
					( objectStatus "C2M21.2" )
				)
			)
			( gate "@baseboard_fab2_lib.baseboard_fab2(sch_1):page131_i29"
				( attribute "BOM_COST" "SB"
					( Origin gFrontEnd )
				)
				( attribute "CDS_LIB" "dev_discrete"
					( Origin gPackager )
				)
				( attribute "CDS_LOCATION" "C2M18"
					( Origin gPackager )
				)
				( attribute "CDS_SEC" "1"
					( Origin gPackager )
				)
				( attribute "LOCATION" "C2M18"
					( Origin gFrontEnd )
				)
				( attribute "MATERIAL" "X6S"
					( Origin gFrontEnd )
				)
				( attribute "PACK_TYPE" "0402V"
					( Origin gFrontEnd )
				)
				( attribute "PART_NUMBER" "D97712-004"
					( Origin gFrontEnd )
				)
				( attribute "PHYS_PAGE" "131"
					( Origin gFrontEnd )
				)
				( attribute "ROOM" "SB_DECOUPLING"
					( Origin gFrontEnd )
				)
				( attribute "ROT" "0"
					( Origin gFrontEnd )
				)
				( attribute "SEC" "1"
					( Origin gPackager )
				)
				( attribute "TOLERANCE" "10%"
					( Origin gFrontEnd )
				)
				( attribute "VALUE" "1.0UF"
					( Origin gFrontEnd )
				)
				( attribute "VER" "1"
					( Origin gFrontEnd )
				)
				( attribute "VOLTAGE" "6.3V"
					( Units "uVoltage" "V" 1.000000)
					( Origin gFrontEnd )
				)
				( attribute "XY" "(-3175,4725)"
					( Origin gFrontEnd )
				)
				( attribute "CHIPS_PART_NAME" "CAP_A"
					( Origin gPackager )
				)
				( attribute "CDS_PART_NAME" "CAP_A_0402V-1.0UF,6.3V,10%,X6SA"
					( Origin gPackager )
				)
				( objectStatus "C2M18" )
				( pin "a"
					( attribute "PN" "1"
						( Origin gPackager )
					)
					( objectStatus "C2M18.1" )
				)
				( pin "b"
					( attribute "PN" "2"
						( Origin gPackager )
					)
					( objectStatus "C2M18.2" )
				)
			)
			( gate "@baseboard_fab2_lib.baseboard_fab2(sch_1):page131_i31"
				( attribute "BOM_COST" "SB"
					( Origin gFrontEnd )
				)
				( attribute "CDS_LIB" "dev_discrete"
					( Origin gPackager )
				)
				( attribute "CDS_LOCATION" "C2M19"
					( Origin gPackager )
				)
				( attribute "CDS_SEC" "1"
					( Origin gPackager )
				)
				( attribute "LOCATION" "C2M19"
					( Origin gFrontEnd )
				)
				( attribute "MATERIAL" "X6S"
					( Origin gFrontEnd )
				)
				( attribute "PACK_TYPE" "0402V"
					( Origin gFrontEnd )
				)
				( attribute "PART_NUMBER" "D97712-004"
					( Origin gFrontEnd )
				)
				( attribute "PHYS_PAGE" "131"
					( Origin gFrontEnd )
				)
				( attribute "ROOM" "SB_DECOUPLING"
					( Origin gFrontEnd )
				)
				( attribute "ROT" "0"
					( Origin gFrontEnd )
				)
				( attribute "SEC" "1"
					( Origin gPackager )
				)
				( attribute "TOLERANCE" "10%"
					( Origin gFrontEnd )
				)
				( attribute "VALUE" "1.0UF"
					( Origin gFrontEnd )
				)
				( attribute "VER" "1"
					( Origin gFrontEnd )
				)
				( attribute "VOLTAGE" "6.3V"
					( Units "uVoltage" "V" 1.000000)
					( Origin gFrontEnd )
				)
				( attribute "XY" "(-2850,3525)"
					( Origin gFrontEnd )
				)
				( attribute "CHIPS_PART_NAME" "CAP_A"
					( Origin gPackager )
				)
				( attribute "CDS_PART_NAME" "CAP_A_0402V-1.0UF,6.3V,10%,X6SA"
					( Origin gPackager )
				)
				( objectStatus "C2M19" )
				( pin "a"
					( attribute "PN" "1"
						( Origin gPackager )
					)
					( objectStatus "C2M19.1" )
				)
				( pin "b"
					( attribute "PN" "2"
						( Origin gPackager )
					)
					( objectStatus "C2M19.2" )
				)
			)
			( gate "@baseboard_fab2_lib.baseboard_fab2(sch_1):page131_i32"
				( attribute "BOM_COST" "SB"
					( Origin gFrontEnd )
				)
				( attribute "CDS_LIB" "dev_discrete"
					( Origin gPackager )
				)
				( attribute "CDS_LOCATION" "C3M38"
					( Origin gPackager )
				)
				( attribute "CDS_SEC" "1"
					( Origin gPackager )
				)
				( attribute "LOCATION" "C3M38"
					( Origin gFrontEnd )
				)
				( attribute "MATERIAL" "X6S"
					( Origin gFrontEnd )
				)
				( attribute "PACK_TYPE" "0402V"
					( Origin gFrontEnd )
				)
				( attribute "PART_NUMBER" "D97712-004"
					( Origin gFrontEnd )
				)
				( attribute "PHYS_PAGE" "131"
					( Origin gFrontEnd )
				)
				( attribute "ROOM" "SB_DECOUPLING"
					( Origin gFrontEnd )
				)
				( attribute "ROT" "0"
					( Origin gFrontEnd )
				)
				( attribute "SEC" "1"
					( Origin gPackager )
				)
				( attribute "TOLERANCE" "10%"
					( Origin gFrontEnd )
				)
				( attribute "VALUE" "1.0UF"
					( Origin gFrontEnd )
				)
				( attribute "VER" "1"
					( Origin gFrontEnd )
				)
				( attribute "VOLTAGE" "6.3V"
					( Units "uVoltage" "V" 1.000000)
					( Origin gFrontEnd )
				)
				( attribute "XY" "(-3225,3525)"
					( Origin gFrontEnd )
				)
				( attribute "CHIPS_PART_NAME" "CAP_A"
					( Origin gPackager )
				)
				( attribute "CDS_PART_NAME" "CAP_A_0402V-1.0UF,6.3V,10%,X6SA"
					( Origin gPackager )
				)
				( objectStatus "C3M38" )
				( pin "a"
					( attribute "PN" "1"
						( Origin gPackager )
					)
					( objectStatus "C3M38.1" )
				)
				( pin "b"
					( attribute "PN" "2"
						( Origin gPackager )
					)
					( objectStatus "C3M38.2" )
				)
			)
			( gate "@baseboard_fab2_lib.baseboard_fab2(sch_1):page131_i34"
				( attribute "BOM_COST" "SB"
					( Origin gFrontEnd )
				)
				( attribute "CDS_LIB" "mstr_discrete"
					( Origin gPackager )
				)
				( attribute "CDS_LOCATION" "C2M17"
					( Origin gPackager )
				)
				( attribute "CDS_SEC" "1"
					( Origin gPackager )
				)
				( attribute "LOCATION" "C2M17"
					( Origin gFrontEnd )
				)
				( attribute "MATERIAL" "X6S"
					( Origin gFrontEnd )
				)
				( attribute "PACK_TYPE" "0805"
					( Origin gFrontEnd )
				)
				( attribute "PART_NUMBER" "C95333-006"
					( Origin gFrontEnd )
				)
				( attribute "PHYS_PAGE" "131"
					( Origin gFrontEnd )
				)
				( attribute "ROOM" "SB_DECOUPLING"
					( Origin gFrontEnd )
				)
				( attribute "ROT" "0"
					( Origin gFrontEnd )
				)
				( attribute "SEC" "1"
					( Origin gPackager )
				)
				( attribute "TOLERANCE" "20%"
					( Origin gFrontEnd )
				)
				( attribute "VALUE" "47UF"
					( Origin gFrontEnd )
				)
				( attribute "VER" "1"
					( Origin gFrontEnd )
				)
				( attribute "VOLTAGE" "4V"
					( Units "uVoltage" "V" 1.000000)
					( Origin gFrontEnd )
				)
				( attribute "XY" "(-2400,2025)"
					( Origin gFrontEnd )
				)
				( attribute "CHIPS_PART_NAME" "CAP"
					( Origin gPackager )
				)
				( attribute "CDS_PART_NAME" "CAP_0805-47UF,4V,20%,X6S,C9533A"
					( Origin gPackager )
				)
				( objectStatus "C2M17" )
				( pin "a"
					( attribute "PN" "1"
						( Origin gPackager )
					)
					( objectStatus "C2M17.1" )
				)
				( pin "b"
					( attribute "PN" "2"
						( Origin gPackager )
					)
					( objectStatus "C2M17.2" )
				)
			)
			( gate "@baseboard_fab2_lib.baseboard_fab2(sch_1):page131_i35"
				( attribute "BOM_COST" "SB"
					( Origin gFrontEnd )
				)
				( attribute "CDS_LIB" "mstr_discrete"
					( Origin gPackager )
				)
				( attribute "CDS_LOCATION" "C2M11"
					( Origin gPackager )
				)
				( attribute "CDS_SEC" "1"
					( Origin gPackager )
				)
				( attribute "LOCATION" "C2M11"
					( Origin gFrontEnd )
				)
				( attribute "MATERIAL" "X6S"
					( Origin gFrontEnd )
				)
				( attribute "PACK_TYPE" "0805"
					( Origin gFrontEnd )
				)
				( attribute "PART_NUMBER" "C95333-006"
					( Origin gFrontEnd )
				)
				( attribute "PHYS_PAGE" "131"
					( Origin gFrontEnd )
				)
				( attribute "ROOM" "SB_DECOUPLING"
					( Origin gFrontEnd )
				)
				( attribute "ROT" "0"
					( Origin gFrontEnd )
				)
				( attribute "SEC" "1"
					( Origin gPackager )
				)
				( attribute "TOLERANCE" "20%"
					( Origin gFrontEnd )
				)
				( attribute "VALUE" "47UF"
					( Origin gFrontEnd )
				)
				( attribute "VER" "1"
					( Origin gFrontEnd )
				)
				( attribute "VOLTAGE" "4V"
					( Units "uVoltage" "V" 1.000000)
					( Origin gFrontEnd )
				)
				( attribute "XY" "(-2800,2025)"
					( Origin gFrontEnd )
				)
				( attribute "CHIPS_PART_NAME" "CAP"
					( Origin gPackager )
				)
				( attribute "CDS_PART_NAME" "CAP_0805-47UF,4V,20%,X6S,C9533A"
					( Origin gPackager )
				)
				( objectStatus "C2M11" )
				( pin "a"
					( attribute "PN" "1"
						( Origin gPackager )
					)
					( objectStatus "C2M11.1" )
				)
				( pin "b"
					( attribute "PN" "2"
						( Origin gPackager )
					)
					( objectStatus "C2M11.2" )
				)
			)
			( gate "@baseboard_fab2_lib.baseboard_fab2(sch_1):page131_i37"
				( attribute "BOM_COST" "SB"
					( Origin gFrontEnd )
				)
				( attribute "CDS_LIB" "mstr_discrete"
					( Origin gPackager )
				)
				( attribute "CDS_LOCATION" "C8A13"
					( Origin gPackager )
				)
				( attribute "CDS_SEC" "1"
					( Origin gPackager )
				)
				( attribute "LOCATION" "C8A13"
					( Origin gFrontEnd )
				)
				( attribute "MATERIAL" "X6S"
					( Origin gFrontEnd )
				)
				( attribute "PACK_TYPE" "0805"
					( Origin gFrontEnd )
				)
				( attribute "PART_NUMBER" "C95333-006"
					( Origin gFrontEnd )
				)
				( attribute "PHYS_PAGE" "131"
					( Origin gFrontEnd )
				)
				( attribute "ROOM" "SB_DECOUPLING"
					( Origin gFrontEnd )
				)
				( attribute "ROT" "0"
					( Origin gFrontEnd )
				)
				( attribute "SEC" "1"
					( Origin gPackager )
				)
				( attribute "TOLERANCE" "20%"
					( Origin gFrontEnd )
				)
				( attribute "VALUE" "47UF"
					( Origin gFrontEnd )
				)
				( attribute "VER" "1"
					( Origin gFrontEnd )
				)
				( attribute "VOLTAGE" "4V"
					( Units "uVoltage" "V" 1.000000)
					( Origin gFrontEnd )
				)
				( attribute "XY" "(-3250,2025)"
					( Origin gFrontEnd )
				)
				( attribute "CHIPS_PART_NAME" "CAP"
					( Origin gPackager )
				)
				( attribute "CDS_PART_NAME" "CAP_0805-47UF,4V,20%,X6S,C9533A"
					( Origin gPackager )
				)
				( objectStatus "C8A13" )
				( pin "a"
					( attribute "PN" "1"
						( Origin gPackager )
					)
					( objectStatus "C8A13.1" )
				)
				( pin "b"
					( attribute "PN" "2"
						( Origin gPackager )
					)
					( objectStatus "C8A13.2" )
				)
			)
			( gate "@baseboard_fab2_lib.baseboard_fab2(sch_1):page131_i39"
				( attribute "BOM_COST" "SB"
					( Origin gFrontEnd )
				)
				( attribute "CDS_LIB" "dev_discrete"
					( Origin gPackager )
				)
				( attribute "CDS_LOCATION" "C2M20"
					( Origin gPackager )
				)
				( attribute "CDS_SEC" "1"
					( Origin gPackager )
				)
				( attribute "LOCATION" "C2M20"
					( Origin gFrontEnd )
				)
				( attribute "MATERIAL" "X6S"
					( Origin gFrontEnd )
				)
				( attribute "PACK_TYPE" "0402V"
					( Origin gFrontEnd )
				)
				( attribute "PART_NUMBER" "D97712-004"
					( Origin gFrontEnd )
				)
				( attribute "PHYS_PAGE" "131"
					( Origin gFrontEnd )
				)
				( attribute "ROOM" "SB_DECOUPLING"
					( Origin gFrontEnd )
				)
				( attribute "ROT" "0"
					( Origin gFrontEnd )
				)
				( attribute "SEC" "1"
					( Origin gPackager )
				)
				( attribute "TOLERANCE" "10%"
					( Origin gFrontEnd )
				)
				( attribute "VALUE" "1.0UF"
					( Origin gFrontEnd )
				)
				( attribute "VER" "1"
					( Origin gFrontEnd )
				)
				( attribute "VOLTAGE" "6.3V"
					( Units "uVoltage" "V" 1.000000)
					( Origin gFrontEnd )
				)
				( attribute "XY" "(-3550,4725)"
					( Origin gFrontEnd )
				)
				( attribute "CHIPS_PART_NAME" "CAP_A"
					( Origin gPackager )
				)
				( attribute "CDS_PART_NAME" "CAP_A_0402V-1.0UF,6.3V,10%,X6SA"
					( Origin gPackager )
				)
				( objectStatus "C2M20" )
				( pin "a"
					( attribute "PN" "1"
						( Origin gPackager )
					)
					( objectStatus "C2M20.1" )
				)
				( pin "b"
					( attribute "PN" "2"
						( Origin gPackager )
					)
					( objectStatus "C2M20.2" )
				)
			)
			( gate "@baseboard_fab2_lib.baseboard_fab2(sch_1):page131_i40"
				( attribute "BOM_COST" "SB"
					( Origin gFrontEnd )
				)
				( attribute "CDS_LIB" "dev_discrete"
					( Origin gPackager )
				)
				( attribute "CDS_LOCATION" "C2N13"
					( Origin gPackager )
				)
				( attribute "CDS_SEC" "1"
					( Origin gPackager )
				)
				( attribute "LOCATION" "C2N13"
					( Origin gFrontEnd )
				)
				( attribute "MATERIAL" "X6S"
					( Origin gFrontEnd )
				)
				( attribute "PACK_TYPE" "0402V"
					( Origin gFrontEnd )
				)
				( attribute "PART_NUMBER" "D97712-004"
					( Origin gFrontEnd )
				)
				( attribute "PHYS_PAGE" "131"
					( Origin gFrontEnd )
				)
				( attribute "ROOM" "SB_DECOUPLING"
					( Origin gFrontEnd )
				)
				( attribute "ROT" "0"
					( Origin gFrontEnd )
				)
				( attribute "SEC" "1"
					( Origin gPackager )
				)
				( attribute "TOLERANCE" "10%"
					( Origin gFrontEnd )
				)
				( attribute "VALUE" "1.0UF"
					( Origin gFrontEnd )
				)
				( attribute "VER" "1"
					( Origin gFrontEnd )
				)
				( attribute "VOLTAGE" "6.3V"
					( Units "uVoltage" "V" 1.000000)
					( Origin gFrontEnd )
				)
				( attribute "XY" "(-3950,4725)"
					( Origin gFrontEnd )
				)
				( attribute "CHIPS_PART_NAME" "CAP_A"
					( Origin gPackager )
				)
				( attribute "CDS_PART_NAME" "CAP_A_0402V-1.0UF,6.3V,10%,X6SA"
					( Origin gPackager )
				)
				( objectStatus "C2N13" )
				( pin "a"
					( attribute "PN" "1"
						( Origin gPackager )
					)
					( objectStatus "C2N13.1" )
				)
				( pin "b"
					( attribute "PN" "2"
						( Origin gPackager )
					)
					( objectStatus "C2N13.2" )
				)
			)
			( gate "@baseboard_fab2_lib.baseboard_fab2(sch_1):page131_i41"
				( attribute "BOM_COST" "SB"
					( Origin gFrontEnd )
				)
				( attribute "CDS_LIB" "dev_discrete"
					( Origin gPackager )
				)
				( attribute "CDS_LOCATION" "C2N2"
					( Origin gPackager )
				)
				( attribute "CDS_SEC" "1"
					( Origin gPackager )
				)
				( attribute "LOCATION" "C2N2"
					( Origin gFrontEnd )
				)
				( attribute "MATERIAL" "X6S"
					( Origin gFrontEnd )
				)
				( attribute "PACK_TYPE" "0402V"
					( Origin gFrontEnd )
				)
				( attribute "PART_NUMBER" "D97712-004"
					( Origin gFrontEnd )
				)
				( attribute "PHYS_PAGE" "131"
					( Origin gFrontEnd )
				)
				( attribute "ROOM" "SB_DECOUPLING"
					( Origin gFrontEnd )
				)
				( attribute "ROT" "0"
					( Origin gFrontEnd )
				)
				( attribute "SEC" "1"
					( Origin gPackager )
				)
				( attribute "TOLERANCE" "10%"
					( Origin gFrontEnd )
				)
				( attribute "VALUE" "1.0UF"
					( Origin gFrontEnd )
				)
				( attribute "VER" "1"
					( Origin gFrontEnd )
				)
				( attribute "VOLTAGE" "6.3V"
					( Units "uVoltage" "V" 1.000000)
					( Origin gFrontEnd )
				)
				( attribute "XY" "(-4350,4725)"
					( Origin gFrontEnd )
				)
				( attribute "CHIPS_PART_NAME" "CAP_A"
					( Origin gPackager )
				)
				( attribute "CDS_PART_NAME" "CAP_A_0402V-1.0UF,6.3V,10%,X6SA"
					( Origin gPackager )
				)
				( objectStatus "C2N2" )
				( pin "a"
					( attribute "PN" "1"
						( Origin gPackager )
					)
					( objectStatus "C2N2.1" )
				)
				( pin "b"
					( attribute "PN" "2"
						( Origin gPackager )
					)
					( objectStatus "C2N2.2" )
				)
			)
			( gate "@baseboard_fab2_lib.baseboard_fab2(sch_1):page131_i42"
				( attribute "BOM_COST" "SB"
					( Origin gFrontEnd )
				)
				( attribute "CDS_LIB" "dev_discrete"
					( Origin gPackager )
				)
				( attribute "CDS_LOCATION" "C3M43"
					( Origin gPackager )
				)
				( attribute "CDS_SEC" "1"
					( Origin gPackager )
				)
				( attribute "LOCATION" "C3M43"
					( Origin gFrontEnd )
				)
				( attribute "MATERIAL" "X6S"
					( Origin gFrontEnd )
				)
				( attribute "PACK_TYPE" "0402V"
					( Origin gFrontEnd )
				)
				( attribute "PART_NUMBER" "D97712-004"
					( Origin gFrontEnd )
				)
				( attribute "PHYS_PAGE" "131"
					( Origin gFrontEnd )
				)
				( attribute "ROOM" "SB_DECOUPLING"
					( Origin gFrontEnd )
				)
				( attribute "ROT" "0"
					( Origin gFrontEnd )
				)
				( attribute "SEC" "1"
					( Origin gPackager )
				)
				( attribute "TOLERANCE" "10%"
					( Origin gFrontEnd )
				)
				( attribute "VALUE" "1.0UF"
					( Origin gFrontEnd )
				)
				( attribute "VER" "1"
					( Origin gFrontEnd )
				)
				( attribute "VOLTAGE" "6.3V"
					( Units "uVoltage" "V" 1.000000)
					( Origin gFrontEnd )
				)
				( attribute "XY" "(-3600,3525)"
					( Origin gFrontEnd )
				)
				( attribute "CHIPS_PART_NAME" "CAP_A"
					( Origin gPackager )
				)
				( attribute "CDS_PART_NAME" "CAP_A_0402V-1.0UF,6.3V,10%,X6SA"
					( Origin gPackager )
				)
				( objectStatus "C3M43" )
				( pin "a"
					( attribute "PN" "1"
						( Origin gPackager )
					)
					( objectStatus "C3M43.1" )
				)
				( pin "b"
					( attribute "PN" "2"
						( Origin gPackager )
					)
					( objectStatus "C3M43.2" )
				)
			)
			( gate "@baseboard_fab2_lib.baseboard_fab2(sch_1):page131_i43"
				( attribute "BOM_COST" "SB"
					( Origin gFrontEnd )
				)
				( attribute "CDS_LIB" "dev_discrete"
					( Origin gPackager )
				)
				( attribute "CDS_LOCATION" "C2N7"
					( Origin gPackager )
				)
				( attribute "CDS_SEC" "1"
					( Origin gPackager )
				)
				( attribute "LOCATION" "C2N7"
					( Origin gFrontEnd )
				)
				( attribute "MATERIAL" "X6S"
					( Origin gFrontEnd )
				)
				( attribute "PACK_TYPE" "0402V"
					( Origin gFrontEnd )
				)
				( attribute "PART_NUMBER" "D97712-004"
					( Origin gFrontEnd )
				)
				( attribute "PHYS_PAGE" "131"
					( Origin gFrontEnd )
				)
				( attribute "ROOM" "SB_DECOUPLING"
					( Origin gFrontEnd )
				)
				( attribute "ROT" "0"
					( Origin gFrontEnd )
				)
				( attribute "SEC" "1"
					( Origin gPackager )
				)
				( attribute "TOLERANCE" "10%"
					( Origin gFrontEnd )
				)
				( attribute "VALUE" "1.0UF"
					( Origin gFrontEnd )
				)
				( attribute "VER" "1"
					( Origin gFrontEnd )
				)
				( attribute "VOLTAGE" "6.3V"
					( Units "uVoltage" "V" 1.000000)
					( Origin gFrontEnd )
				)
				( attribute "XY" "(-4000,3525)"
					( Origin gFrontEnd )
				)
				( attribute "CHIPS_PART_NAME" "CAP_A"
					( Origin gPackager )
				)
				( attribute "CDS_PART_NAME" "CAP_A_0402V-1.0UF,6.3V,10%,X6SA"
					( Origin gPackager )
				)
				( objectStatus "C2N7" )
				( pin "a"
					( attribute "PN" "1"
						( Origin gPackager )
					)
					( objectStatus "C2N7.1" )
				)
				( pin "b"
					( attribute "PN" "2"
						( Origin gPackager )
					)
					( objectStatus "C2N7.2" )
				)
			)
			( gate "@baseboard_fab2_lib.baseboard_fab2(sch_1):page131_i44"
				( attribute "BOM_COST" "SB"
					( Origin gFrontEnd )
				)
				( attribute "CDS_LIB" "dev_discrete"
					( Origin gPackager )
				)
				( attribute "CDS_LOCATION" "C3M39"
					( Origin gPackager )
				)
				( attribute "CDS_SEC" "1"
					( Origin gPackager )
				)
				( attribute "LOCATION" "C3M39"
					( Origin gFrontEnd )
				)
				( attribute "MATERIAL" "X6S"
					( Origin gFrontEnd )
				)
				( attribute "PACK_TYPE" "0402V"
					( Origin gFrontEnd )
				)
				( attribute "PART_NUMBER" "D97712-004"
					( Origin gFrontEnd )
				)
				( attribute "PHYS_PAGE" "131"
					( Origin gFrontEnd )
				)
				( attribute "ROOM" "SB_DECOUPLING"
					( Origin gFrontEnd )
				)
				( attribute "ROT" "0"
					( Origin gFrontEnd )
				)
				( attribute "SEC" "1"
					( Origin gPackager )
				)
				( attribute "TOLERANCE" "10%"
					( Origin gFrontEnd )
				)
				( attribute "VALUE" "1.0UF"
					( Origin gFrontEnd )
				)
				( attribute "VER" "1"
					( Origin gFrontEnd )
				)
				( attribute "VOLTAGE" "6.3V"
					( Units "uVoltage" "V" 1.000000)
					( Origin gFrontEnd )
				)
				( attribute "XY" "(-4375,3525)"
					( Origin gFrontEnd )
				)
				( attribute "CHIPS_PART_NAME" "CAP_A"
					( Origin gPackager )
				)
				( attribute "CDS_PART_NAME" "CAP_A_0402V-1.0UF,6.3V,10%,X6SA"
					( Origin gPackager )
				)
				( objectStatus "C3M39" )
				( pin "a"
					( attribute "PN" "1"
						( Origin gPackager )
					)
					( objectStatus "C3M39.1" )
				)
				( pin "b"
					( attribute "PN" "2"
						( Origin gPackager )
					)
					( objectStatus "C3M39.2" )
				)
			)
			( gate "@baseboard_fab2_lib.baseboard_fab2(sch_1):page131_i45"
				( attribute "BOM_COST" "SB"
					( Origin gFrontEnd )
				)
				( attribute "CDS_LIB" "dev_discrete"
					( Origin gPackager )
				)
				( attribute "CDS_LOCATION" "C3M42"
					( Origin gPackager )
				)
				( attribute "CDS_SEC" "1"
					( Origin gPackager )
				)
				( attribute "LOCATION" "C3M42"
					( Origin gFrontEnd )
				)
				( attribute "MATERIAL" "X6S"
					( Origin gFrontEnd )
				)
				( attribute "PACK_TYPE" "0402V"
					( Origin gFrontEnd )
				)
				( attribute "PART_NUMBER" "D97712-004"
					( Origin gFrontEnd )
				)
				( attribute "PHYS_PAGE" "131"
					( Origin gFrontEnd )
				)
				( attribute "ROOM" "SB_DECOUPLING"
					( Origin gFrontEnd )
				)
				( attribute "ROT" "0"
					( Origin gFrontEnd )
				)
				( attribute "SEC" "1"
					( Origin gPackager )
				)
				( attribute "TOLERANCE" "10%"
					( Origin gFrontEnd )
				)
				( attribute "VALUE" "1.0UF"
					( Origin gFrontEnd )
				)
				( attribute "VER" "1"
					( Origin gFrontEnd )
				)
				( attribute "VOLTAGE" "6.3V"
					( Units "uVoltage" "V" 1.000000)
					( Origin gFrontEnd )
				)
				( attribute "XY" "(-4750,4725)"
					( Origin gFrontEnd )
				)
				( attribute "CHIPS_PART_NAME" "CAP_A"
					( Origin gPackager )
				)
				( attribute "CDS_PART_NAME" "CAP_A_0402V-1.0UF,6.3V,10%,X6SA"
					( Origin gPackager )
				)
				( objectStatus "C3M42" )
				( pin "a"
					( attribute "PN" "1"
						( Origin gPackager )
					)
					( objectStatus "C3M42.1" )
				)
				( pin "b"
					( attribute "PN" "2"
						( Origin gPackager )
					)
					( objectStatus "C3M42.2" )
				)
			)
			( gate "@baseboard_fab2_lib.baseboard_fab2(sch_1):page131_i47"
				( attribute "BOM_COST" "SB"
					( Origin gFrontEnd )
				)
				( attribute "CDS_LIB" "dev_discrete"
					( Origin gPackager )
				)
				( attribute "CDS_LOCATION" "C2N8"
					( Origin gPackager )
				)
				( attribute "CDS_SEC" "1"
					( Origin gPackager )
				)
				( attribute "LOCATION" "C2N8"
					( Origin gFrontEnd )
				)
				( attribute "MATERIAL" "X6S"
					( Origin gFrontEnd )
				)
				( attribute "PACK_TYPE" "0402V"
					( Origin gFrontEnd )
				)
				( attribute "PART_NUMBER" "D97712-004"
					( Origin gFrontEnd )
				)
				( attribute "PHYS_PAGE" "131"
					( Origin gFrontEnd )
				)
				( attribute "ROOM" "SB_DECOUPLING"
					( Origin gFrontEnd )
				)
				( attribute "ROT" "0"
					( Origin gFrontEnd )
				)
				( attribute "SEC" "1"
					( Origin gPackager )
				)
				( attribute "TOLERANCE" "10%"
					( Origin gFrontEnd )
				)
				( attribute "VALUE" "1.0UF"
					( Origin gFrontEnd )
				)
				( attribute "VER" "1"
					( Origin gFrontEnd )
				)
				( attribute "VOLTAGE" "6.3V"
					( Units "uVoltage" "V" 1.000000)
					( Origin gFrontEnd )
				)
				( attribute "XY" "(-4775,3525)"
					( Origin gFrontEnd )
				)
				( attribute "CHIPS_PART_NAME" "CAP_A"
					( Origin gPackager )
				)
				( attribute "CDS_PART_NAME" "CAP_A_0402V-1.0UF,6.3V,10%,X6SA"
					( Origin gPackager )
				)
				( objectStatus "C2N8" )
				( pin "a"
					( attribute "PN" "1"
						( Origin gPackager )
					)
					( objectStatus "C2N8.1" )
				)
				( pin "b"
					( attribute "PN" "2"
						( Origin gPackager )
					)
					( objectStatus "C2N8.2" )
				)
			)
			( gate "@baseboard_fab2_lib.baseboard_fab2(sch_1):page131_i48"
				( attribute "BOM_COST" "SB"
					( Origin gFrontEnd )
				)
				( attribute "CDS_LIB" "dev_discrete"
					( Origin gPackager )
				)
				( attribute "CDS_LOCATION" "C2M13"
					( Origin gPackager )
				)
				( attribute "CDS_SEC" "1"
					( Origin gPackager )
				)
				( attribute "LOCATION" "C2M13"
					( Origin gFrontEnd )
				)
				( attribute "MATERIAL" "X6S"
					( Origin gFrontEnd )
				)
				( attribute "PACK_TYPE" "0603V"
					( Origin gFrontEnd )
				)
				( attribute "PART_NUMBER" "E15431-004"
					( Origin gFrontEnd )
				)
				( attribute "PHYS_PAGE" "131"
					( Origin gFrontEnd )
				)
				( attribute "ROOM" "SB_DECOUPLING"
					( Origin gFrontEnd )
				)
				( attribute "ROT" "0"
					( Origin gFrontEnd )
				)
				( attribute "SEC" "1"
					( Origin gPackager )
				)
				( attribute "TOLERANCE" "20%"
					( Origin gFrontEnd )
				)
				( attribute "VALUE" "22.0UF"
					( Origin gFrontEnd )
				)
				( attribute "VER" "1"
					( Origin gFrontEnd )
				)
				( attribute "VOLTAGE" "4V"
					( Units "uVoltage" "V" 1.000000)
					( Origin gFrontEnd )
				)
				( attribute "XY" "(-4250,2100)"
					( Origin gFrontEnd )
				)
				( attribute "CHIPS_PART_NAME" "CAP_A"
					( Origin gPackager )
				)
				( attribute "CDS_PART_NAME" "CAP_A_0603V-22.0UF,4V,20%,X6S,A"
					( Origin gPackager )
				)
				( objectStatus "C2M13" )
				( pin "a"
					( attribute "PN" "1"
						( Origin gPackager )
					)
					( objectStatus "C2M13.1" )
				)
				( pin "b"
					( attribute "PN" "2"
						( Origin gPackager )
					)
					( objectStatus "C2M13.2" )
				)
			)
			( gate "@baseboard_fab2_lib.baseboard_fab2(sch_1):page131_i50"
				( attribute "BOM_COST" "SB"
					( Origin gFrontEnd )
				)
				( attribute "CDS_LIB" "dev_discrete"
					( Origin gPackager )
				)
				( attribute "CDS_LOCATION" "C2N10"
					( Origin gPackager )
				)
				( attribute "CDS_SEC" "1"
					( Origin gPackager )
				)
				( attribute "LOCATION" "C2N10"
					( Origin gFrontEnd )
				)
				( attribute "MATERIAL" "X6S"
					( Origin gFrontEnd )
				)
				( attribute "PACK_TYPE" "0603V"
					( Origin gFrontEnd )
				)
				( attribute "PART_NUMBER" "E15431-004"
					( Origin gFrontEnd )
				)
				( attribute "PHYS_PAGE" "131"
					( Origin gFrontEnd )
				)
				( attribute "ROOM" "SB_DECOUPLING"
					( Origin gFrontEnd )
				)
				( attribute "ROT" "0"
					( Origin gFrontEnd )
				)
				( attribute "SEC" "1"
					( Origin gPackager )
				)
				( attribute "TOLERANCE" "20%"
					( Origin gFrontEnd )
				)
				( attribute "VALUE" "22.0UF"
					( Origin gFrontEnd )
				)
				( attribute "VER" "1"
					( Origin gFrontEnd )
				)
				( attribute "VOLTAGE" "4V"
					( Units "uVoltage" "V" 1.000000)
					( Origin gFrontEnd )
				)
				( attribute "XY" "(-4650,2100)"
					( Origin gFrontEnd )
				)
				( attribute "CHIPS_PART_NAME" "CAP_A"
					( Origin gPackager )
				)
				( attribute "CDS_PART_NAME" "CAP_A_0603V-22.0UF,4V,20%,X6S,A"
					( Origin gPackager )
				)
				( objectStatus "C2N10" )
				( pin "a"
					( attribute "PN" "1"
						( Origin gPackager )
					)
					( objectStatus "C2N10.1" )
				)
				( pin "b"
					( attribute "PN" "2"
						( Origin gPackager )
					)
					( objectStatus "C2N10.2" )
				)
			)
			( gate "@baseboard_fab2_lib.baseboard_fab2(sch_1):page131_i52"
				( attribute "BOM_COST" "SB"
					( Origin gFrontEnd )
				)
				( attribute "CDS_LIB" "dev_discrete"
					( Origin gPackager )
				)
				( attribute "CDS_LOCATION" "C2M12"
					( Origin gPackager )
				)
				( attribute "CDS_SEC" "1"
					( Origin gPackager )
				)
				( attribute "LOCATION" "C2M12"
					( Origin gFrontEnd )
				)
				( attribute "MATERIAL" "X6S"
					( Origin gFrontEnd )
				)
				( attribute "PACK_TYPE" "0603V"
					( Origin gFrontEnd )
				)
				( attribute "PART_NUMBER" "E15431-004"
					( Origin gFrontEnd )
				)
				( attribute "PHYS_PAGE" "131"
					( Origin gFrontEnd )
				)
				( attribute "ROOM" "SB_DECOUPLING"
					( Origin gFrontEnd )
				)
				( attribute "ROT" "0"
					( Origin gFrontEnd )
				)
				( attribute "SEC" "1"
					( Origin gPackager )
				)
				( attribute "TOLERANCE" "20%"
					( Origin gFrontEnd )
				)
				( attribute "VALUE" "22.0UF"
					( Origin gFrontEnd )
				)
				( attribute "VER" "1"
					( Origin gFrontEnd )
				)
				( attribute "VOLTAGE" "4V"
					( Units "uVoltage" "V" 1.000000)
					( Origin gFrontEnd )
				)
				( attribute "XY" "(-5075,2100)"
					( Origin gFrontEnd )
				)
				( attribute "CHIPS_PART_NAME" "CAP_A"
					( Origin gPackager )
				)
				( attribute "CDS_PART_NAME" "CAP_A_0603V-22.0UF,4V,20%,X6S,A"
					( Origin gPackager )
				)
				( objectStatus "C2M12" )
				( pin "a"
					( attribute "PN" "1"
						( Origin gPackager )
					)
					( objectStatus "C2M12.1" )
				)
				( pin "b"
					( attribute "PN" "2"
						( Origin gPackager )
					)
					( objectStatus "C2M12.2" )
				)
			)
			( gate "@baseboard_fab2_lib.baseboard_fab2(sch_1):page132_i1"
				( attribute "BOM_COST" "SB"
					( Origin gFrontEnd )
				)
				( attribute "CDS_LIB" "dev_discrete"
					( Origin gPackager )
				)
				( attribute "CDS_LOCATION" "C3L25"
					( Origin gPackager )
				)
				( attribute "CDS_SEC" "1"
					( Origin gPackager )
				)
				( attribute "LOCATION" "C3L25"
					( Origin gFrontEnd )
				)
				( attribute "MATERIAL" "X6S"
					( Origin gFrontEnd )
				)
				( attribute "PACK_TYPE" "0603V"
					( Origin gFrontEnd )
				)
				( attribute "PART_NUMBER" "E15431-004"
					( Origin gFrontEnd )
				)
				( attribute "PHYS_PAGE" "132"
					( Origin gFrontEnd )
				)
				( attribute "ROOM" "SB_DECOUPLING"
					( Origin gFrontEnd )
				)
				( attribute "ROT" "0"
					( Origin gFrontEnd )
				)
				( attribute "SEC" "1"
					( Origin gPackager )
				)
				( attribute "TOLERANCE" "20%"
					( Origin gFrontEnd )
				)
				( attribute "VALUE" "22.0UF"
					( Origin gFrontEnd )
				)
				( attribute "VER" "1"
					( Origin gFrontEnd )
				)
				( attribute "VOLTAGE" "4V"
					( Units "uVoltage" "V" 1.000000)
					( Origin gFrontEnd )
				)
				( attribute "XY" "(2575,4475)"
					( Origin gFrontEnd )
				)
				( attribute "CHIPS_PART_NAME" "CAP_A"
					( Origin gPackager )
				)
				( attribute "CDS_PART_NAME" "CAP_A_0603V-22.0UF,4V,20%,X6S,A"
					( Origin gPackager )
				)
				( objectStatus "C3L25" )
				( pin "a"
					( attribute "PN" "1"
						( Origin gPackager )
					)
					( objectStatus "C3L25.1" )
				)
				( pin "b"
					( attribute "PN" "2"
						( Origin gPackager )
					)
					( objectStatus "C3L25.2" )
				)
			)
			( gate "@baseboard_fab2_lib.baseboard_fab2(sch_1):page132_i2"
				( attribute "BOM_COST" "SB"
					( Origin gFrontEnd )
				)
				( attribute "CDS_LIB" "dev_discrete"
					( Origin gPackager )
				)
				( attribute "CDS_LOCATION" "C3M7"
					( Origin gPackager )
				)
				( attribute "CDS_SEC" "1"
					( Origin gPackager )
				)
				( attribute "LOCATION" "C3M7"
					( Origin gFrontEnd )
				)
				( attribute "MATERIAL" "X6S"
					( Origin gFrontEnd )
				)
				( attribute "PACK_TYPE" "0603V"
					( Origin gFrontEnd )
				)
				( attribute "PART_NUMBER" "E15431-004"
					( Origin gFrontEnd )
				)
				( attribute "PHYS_PAGE" "132"
					( Origin gFrontEnd )
				)
				( attribute "ROOM" "SB_DECOUPLING"
					( Origin gFrontEnd )
				)
				( attribute "ROT" "0"
					( Origin gFrontEnd )
				)
				( attribute "SEC" "1"
					( Origin gPackager )
				)
				( attribute "TOLERANCE" "20%"
					( Origin gFrontEnd )
				)
				( attribute "VALUE" "22.0UF"
					( Origin gFrontEnd )
				)
				( attribute "VER" "1"
					( Origin gFrontEnd )
				)
				( attribute "VOLTAGE" "4V"
					( Units "uVoltage" "V" 1.000000)
					( Origin gFrontEnd )
				)
				( attribute "XY" "(2200,4475)"
					( Origin gFrontEnd )
				)
				( attribute "CHIPS_PART_NAME" "CAP_A"
					( Origin gPackager )
				)
				( attribute "CDS_PART_NAME" "CAP_A_0603V-22.0UF,4V,20%,X6S,A"
					( Origin gPackager )
				)
				( objectStatus "C3M7" )
				( pin "a"
					( attribute "PN" "1"
						( Origin gPackager )
					)
					( objectStatus "C3M7.1" )
				)
				( pin "b"
					( attribute "PN" "2"
						( Origin gPackager )
					)
					( objectStatus "C3M7.2" )
				)
			)
			( gate "@baseboard_fab2_lib.baseboard_fab2(sch_1):page132_i3"
				( attribute "BOM_COST" "SB"
					( Origin gFrontEnd )
				)
				( attribute "CDS_LIB" "dev_discrete"
					( Origin gPackager )
				)
				( attribute "CDS_LOCATION" "C3L26"
					( Origin gPackager )
				)
				( attribute "CDS_SEC" "1"
					( Origin gPackager )
				)
				( attribute "LOCATION" "C3L26"
					( Origin gFrontEnd )
				)
				( attribute "MATERIAL" "X6S"
					( Origin gFrontEnd )
				)
				( attribute "PACK_TYPE" "0603V"
					( Origin gFrontEnd )
				)
				( attribute "PART_NUMBER" "E15431-004"
					( Origin gFrontEnd )
				)
				( attribute "PHYS_PAGE" "132"
					( Origin gFrontEnd )
				)
				( attribute "ROOM" "SB_DECOUPLING"
					( Origin gFrontEnd )
				)
				( attribute "ROT" "0"
					( Origin gFrontEnd )
				)
				( attribute "SEC" "1"
					( Origin gPackager )
				)
				( attribute "TOLERANCE" "20%"
					( Origin gFrontEnd )
				)
				( attribute "VALUE" "22.0UF"
					( Origin gFrontEnd )
				)
				( attribute "VER" "1"
					( Origin gFrontEnd )
				)
				( attribute "VOLTAGE" "4V"
					( Units "uVoltage" "V" 1.000000)
					( Origin gFrontEnd )
				)
				( attribute "XY" "(1825,4475)"
					( Origin gFrontEnd )
				)
				( attribute "CHIPS_PART_NAME" "CAP_A"
					( Origin gPackager )
				)
				( attribute "CDS_PART_NAME" "CAP_A_0603V-22.0UF,4V,20%,X6S,A"
					( Origin gPackager )
				)
				( objectStatus "C3L26" )
				( pin "a"
					( attribute "PN" "1"
						( Origin gPackager )
					)
					( objectStatus "C3L26.1" )
				)
				( pin "b"
					( attribute "PN" "2"
						( Origin gPackager )
					)
					( objectStatus "C3L26.2" )
				)
			)
			( gate "@baseboard_fab2_lib.baseboard_fab2(sch_1):page132_i4"
				( attribute "BOM_COST" "SB"
					( Origin gFrontEnd )
				)
				( attribute "CDS_LIB" "dev_discrete"
					( Origin gPackager )
				)
				( attribute "CDS_LOCATION" "C3L27"
					( Origin gPackager )
				)
				( attribute "CDS_SEC" "1"
					( Origin gPackager )
				)
				( attribute "LOCATION" "C3L27"
					( Origin gFrontEnd )
				)
				( attribute "MATERIAL" "X6S"
					( Origin gFrontEnd )
				)
				( attribute "PACK_TYPE" "0603V"
					( Origin gFrontEnd )
				)
				( attribute "PART_NUMBER" "E15431-004"
					( Origin gFrontEnd )
				)
				( attribute "PHYS_PAGE" "132"
					( Origin gFrontEnd )
				)
				( attribute "ROOM" "SB_DECOUPLING"
					( Origin gFrontEnd )
				)
				( attribute "ROT" "0"
					( Origin gFrontEnd )
				)
				( attribute "SEC" "1"
					( Origin gPackager )
				)
				( attribute "TOLERANCE" "20%"
					( Origin gFrontEnd )
				)
				( attribute "VALUE" "22.0UF"
					( Origin gFrontEnd )
				)
				( attribute "VER" "1"
					( Origin gFrontEnd )
				)
				( attribute "VOLTAGE" "4V"
					( Units "uVoltage" "V" 1.000000)
					( Origin gFrontEnd )
				)
				( attribute "XY" "(1450,4475)"
					( Origin gFrontEnd )
				)
				( attribute "CHIPS_PART_NAME" "CAP_A"
					( Origin gPackager )
				)
				( attribute "CDS_PART_NAME" "CAP_A_0603V-22.0UF,4V,20%,X6S,A"
					( Origin gPackager )
				)
				( objectStatus "C3L27" )
				( pin "a"
					( attribute "PN" "1"
						( Origin gPackager )
					)
					( objectStatus "C3L27.1" )
				)
				( pin "b"
					( attribute "PN" "2"
						( Origin gPackager )
					)
					( objectStatus "C3L27.2" )
				)
			)
			( gate "@baseboard_fab2_lib.baseboard_fab2(sch_1):page132_i6"
				( attribute "BOM_COST" "SB"
					( Origin gFrontEnd )
				)
				( attribute "CDS_LIB" "dev_discrete"
					( Origin gPackager )
				)
				( attribute "CDS_LOCATION" "C3M6"
					( Origin gPackager )
				)
				( attribute "CDS_SEC" "1"
					( Origin gPackager )
				)
				( attribute "LOCATION" "C3M6"
					( Origin gFrontEnd )
				)
				( attribute "MATERIAL" "X6S"
					( Origin gFrontEnd )
				)
				( attribute "PACK_TYPE" "0603V"
					( Origin gFrontEnd )
				)
				( attribute "PART_NUMBER" "E15431-004"
					( Origin gFrontEnd )
				)
				( attribute "PHYS_PAGE" "132"
					( Origin gFrontEnd )
				)
				( attribute "ROOM" "SB_DECOUPLING"
					( Origin gFrontEnd )
				)
				( attribute "ROT" "0"
					( Origin gFrontEnd )
				)
				( attribute "SEC" "1"
					( Origin gPackager )
				)
				( attribute "TOLERANCE" "20%"
					( Origin gFrontEnd )
				)
				( attribute "VALUE" "22.0UF"
					( Origin gFrontEnd )
				)
				( attribute "VER" "1"
					( Origin gFrontEnd )
				)
				( attribute "VOLTAGE" "4V"
					( Units "uVoltage" "V" 1.000000)
					( Origin gFrontEnd )
				)
				( attribute "XY" "(1075,4475)"
					( Origin gFrontEnd )
				)
				( attribute "CHIPS_PART_NAME" "CAP_A"
					( Origin gPackager )
				)
				( attribute "CDS_PART_NAME" "CAP_A_0603V-22.0UF,4V,20%,X6S,A"
					( Origin gPackager )
				)
				( objectStatus "C3M6" )
				( pin "a"
					( attribute "PN" "1"
						( Origin gPackager )
					)
					( objectStatus "C3M6.1" )
				)
				( pin "b"
					( attribute "PN" "2"
						( Origin gPackager )
					)
					( objectStatus "C3M6.2" )
				)
			)
			( gate "@baseboard_fab2_lib.baseboard_fab2(sch_1):page132_i7"
				( attribute "BOM_COST" "SB"
					( Origin gFrontEnd )
				)
				( attribute "CDS_LIB" "dev_discrete"
					( Origin gPackager )
				)
				( attribute "CDS_LOCATION" "C7C9"
					( Origin gPackager )
				)
				( attribute "CDS_SEC" "1"
					( Origin gPackager )
				)
				( attribute "LOCATION" "C7C9"
					( Origin gFrontEnd )
				)
				( attribute "MATERIAL" "X6S"
					( Origin gFrontEnd )
				)
				( attribute "PACK_TYPE" "0603V"
					( Origin gFrontEnd )
				)
				( attribute "PART_NUMBER" "E15431-004"
					( Origin gFrontEnd )
				)
				( attribute "PHYS_PAGE" "132"
					( Origin gFrontEnd )
				)
				( attribute "ROOM" "SB_DECOUPLING"
					( Origin gFrontEnd )
				)
				( attribute "ROT" "0"
					( Origin gFrontEnd )
				)
				( attribute "SEC" "1"
					( Origin gPackager )
				)
				( attribute "TOLERANCE" "20%"
					( Origin gFrontEnd )
				)
				( attribute "VALUE" "22.0UF"
					( Origin gFrontEnd )
				)
				( attribute "VER" "1"
					( Origin gFrontEnd )
				)
				( attribute "VOLTAGE" "4V"
					( Units "uVoltage" "V" 1.000000)
					( Origin gFrontEnd )
				)
				( attribute "XY" "(2550,3500)"
					( Origin gFrontEnd )
				)
				( attribute "CHIPS_PART_NAME" "CAP_A"
					( Origin gPackager )
				)
				( attribute "CDS_PART_NAME" "CAP_A_0603V-22.0UF,4V,20%,X6S,A"
					( Origin gPackager )
				)
				( objectStatus "C7C9" )
				( pin "a"
					( attribute "PN" "1"
						( Origin gPackager )
					)
					( objectStatus "C7C9.1" )
				)
				( pin "b"
					( attribute "PN" "2"
						( Origin gPackager )
					)
					( objectStatus "C7C9.2" )
				)
			)
			( gate "@baseboard_fab2_lib.baseboard_fab2(sch_1):page132_i8"
				( attribute "BOM_COST" "SB"
					( Origin gFrontEnd )
				)
				( attribute "CDS_LIB" "dev_discrete"
					( Origin gPackager )
				)
				( attribute "CDS_LOCATION" "C3N27"
					( Origin gPackager )
				)
				( attribute "CDS_SEC" "1"
					( Origin gPackager )
				)
				( attribute "LOCATION" "C3N27"
					( Origin gFrontEnd )
				)
				( attribute "MATERIAL" "X6S"
					( Origin gFrontEnd )
				)
				( attribute "PACK_TYPE" "0603V"
					( Origin gFrontEnd )
				)
				( attribute "PART_NUMBER" "E15431-004"
					( Origin gFrontEnd )
				)
				( attribute "PHYS_PAGE" "132"
					( Origin gFrontEnd )
				)
				( attribute "ROOM" "SB_DECOUPLING"
					( Origin gFrontEnd )
				)
				( attribute "ROT" "0"
					( Origin gFrontEnd )
				)
				( attribute "SEC" "1"
					( Origin gPackager )
				)
				( attribute "TOLERANCE" "20%"
					( Origin gFrontEnd )
				)
				( attribute "VALUE" "22.0UF"
					( Origin gFrontEnd )
				)
				( attribute "VER" "1"
					( Origin gFrontEnd )
				)
				( attribute "VOLTAGE" "4V"
					( Units "uVoltage" "V" 1.000000)
					( Origin gFrontEnd )
				)
				( attribute "XY" "(2600,2525)"
					( Origin gFrontEnd )
				)
				( attribute "CHIPS_PART_NAME" "CAP_A"
					( Origin gPackager )
				)
				( attribute "CDS_PART_NAME" "CAP_A_0603V-22.0UF,4V,20%,X6S,A"
					( Origin gPackager )
				)
				( objectStatus "C3N27" )
				( pin "a"
					( attribute "PN" "1"
						( Origin gPackager )
					)
					( objectStatus "C3N27.1" )
				)
				( pin "b"
					( attribute "PN" "2"
						( Origin gPackager )
					)
					( objectStatus "C3N27.2" )
				)
			)
			( gate "@baseboard_fab2_lib.baseboard_fab2(sch_1):page132_i9"
				( attribute "BOM_COST" "SB"
					( Origin gFrontEnd )
				)
				( attribute "CDS_LIB" "dev_discrete"
					( Origin gPackager )
				)
				( attribute "CDS_LOCATION" "C3N30"
					( Origin gPackager )
				)
				( attribute "CDS_SEC" "1"
					( Origin gPackager )
				)
				( attribute "LOCATION" "C3N30"
					( Origin gFrontEnd )
				)
				( attribute "MATERIAL" "X6S"
					( Origin gFrontEnd )
				)
				( attribute "PACK_TYPE" "0603V"
					( Origin gFrontEnd )
				)
				( attribute "PART_NUMBER" "E15431-004"
					( Origin gFrontEnd )
				)
				( attribute "PHYS_PAGE" "132"
					( Origin gFrontEnd )
				)
				( attribute "ROOM" "SB_DECOUPLING"
					( Origin gFrontEnd )
				)
				( attribute "ROT" "0"
					( Origin gFrontEnd )
				)
				( attribute "SEC" "1"
					( Origin gPackager )
				)
				( attribute "TOLERANCE" "20%"
					( Origin gFrontEnd )
				)
				( attribute "VALUE" "22.0UF"
					( Origin gFrontEnd )
				)
				( attribute "VER" "1"
					( Origin gFrontEnd )
				)
				( attribute "VOLTAGE" "4V"
					( Units "uVoltage" "V" 1.000000)
					( Origin gFrontEnd )
				)
				( attribute "XY" "(2225,2525)"
					( Origin gFrontEnd )
				)
				( attribute "CHIPS_PART_NAME" "CAP_A"
					( Origin gPackager )
				)
				( attribute "CDS_PART_NAME" "CAP_A_0603V-22.0UF,4V,20%,X6S,A"
					( Origin gPackager )
				)
				( objectStatus "C3N30" )
				( pin "a"
					( attribute "PN" "1"
						( Origin gPackager )
					)
					( objectStatus "C3N30.1" )
				)
				( pin "b"
					( attribute "PN" "2"
						( Origin gPackager )
					)
					( objectStatus "C3N30.2" )
				)
			)
			( gate "@baseboard_fab2_lib.baseboard_fab2(sch_1):page132_i11"
				( attribute "BOM_COST" "SB"
					( Origin gFrontEnd )
				)
				( attribute "CDS_LIB" "dev_discrete"
					( Origin gPackager )
				)
				( attribute "CDS_LOCATION" "C7A36"
					( Origin gPackager )
				)
				( attribute "CDS_SEC" "1"
					( Origin gPackager )
				)
				( attribute "LOCATION" "C7A36"
					( Origin gFrontEnd )
				)
				( attribute "MATERIAL" "X6S"
					( Origin gFrontEnd )
				)
				( attribute "PACK_TYPE" "0603V"
					( Origin gFrontEnd )
				)
				( attribute "PART_NUMBER" "E15431-004"
					( Origin gFrontEnd )
				)
				( attribute "PHYS_PAGE" "132"
					( Origin gFrontEnd )
				)
				( attribute "ROOM" "SB_DECOUPLING"
					( Origin gFrontEnd )
				)
				( attribute "ROT" "0"
					( Origin gFrontEnd )
				)
				( attribute "SEC" "1"
					( Origin gPackager )
				)
				( attribute "TOLERANCE" "20%"
					( Origin gFrontEnd )
				)
				( attribute "VALUE" "22.0UF"
					( Origin gFrontEnd )
				)
				( attribute "VER" "1"
					( Origin gFrontEnd )
				)
				( attribute "VOLTAGE" "4V"
					( Units "uVoltage" "V" 1.000000)
					( Origin gFrontEnd )
				)
				( attribute "XY" "(2200,3500)"
					( Origin gFrontEnd )
				)
				( attribute "CHIPS_PART_NAME" "CAP_A"
					( Origin gPackager )
				)
				( attribute "CDS_PART_NAME" "CAP_A_0603V-22.0UF,4V,20%,X6S,A"
					( Origin gPackager )
				)
				( objectStatus "C7A36" )
				( pin "a"
					( attribute "PN" "1"
						( Origin gPackager )
					)
					( objectStatus "C7A36.1" )
				)
				( pin "b"
					( attribute "PN" "2"
						( Origin gPackager )
					)
					( objectStatus "C7A36.2" )
				)
			)
			( gate "@baseboard_fab2_lib.baseboard_fab2(sch_1):page132_i12"
				( attribute "BOM_COST" "SB"
					( Origin gFrontEnd )
				)
				( attribute "CDS_LIB" "dev_discrete"
					( Origin gPackager )
				)
				( attribute "CDS_LOCATION" "C3N12"
					( Origin gPackager )
				)
				( attribute "CDS_SEC" "1"
					( Origin gPackager )
				)
				( attribute "LOCATION" "C3N12"
					( Origin gFrontEnd )
				)
				( attribute "MATERIAL" "X6S"
					( Origin gFrontEnd )
				)
				( attribute "PACK_TYPE" "0603V"
					( Origin gFrontEnd )
				)
				( attribute "PART_NUMBER" "E15431-004"
					( Origin gFrontEnd )
				)
				( attribute "PHYS_PAGE" "132"
					( Origin gFrontEnd )
				)
				( attribute "ROOM" "SB_DECOUPLING"
					( Origin gFrontEnd )
				)
				( attribute "ROT" "0"
					( Origin gFrontEnd )
				)
				( attribute "SEC" "1"
					( Origin gPackager )
				)
				( attribute "TOLERANCE" "20%"
					( Origin gFrontEnd )
				)
				( attribute "VALUE" "22.0UF"
					( Origin gFrontEnd )
				)
				( attribute "VER" "1"
					( Origin gFrontEnd )
				)
				( attribute "VOLTAGE" "4V"
					( Units "uVoltage" "V" 1.000000)
					( Origin gFrontEnd )
				)
				( attribute "XY" "(1825,3500)"
					( Origin gFrontEnd )
				)
				( attribute "CHIPS_PART_NAME" "CAP_A"
					( Origin gPackager )
				)
				( attribute "CDS_PART_NAME" "CAP_A_0603V-22.0UF,4V,20%,X6S,A"
					( Origin gPackager )
				)
				( objectStatus "C3N12" )
				( pin "a"
					( attribute "PN" "1"
						( Origin gPackager )
					)
					( objectStatus "C3N12.1" )
				)
				( pin "b"
					( attribute "PN" "2"
						( Origin gPackager )
					)
					( objectStatus "C3N12.2" )
				)
			)
			( gate "@baseboard_fab2_lib.baseboard_fab2(sch_1):page132_i13"
				( attribute "BOM_COST" "SB"
					( Origin gFrontEnd )
				)
				( attribute "CDS_LIB" "dev_discrete"
					( Origin gPackager )
				)
				( attribute "CDS_LOCATION" "C3N10"
					( Origin gPackager )
				)
				( attribute "CDS_SEC" "1"
					( Origin gPackager )
				)
				( attribute "LOCATION" "C3N10"
					( Origin gFrontEnd )
				)
				( attribute "MATERIAL" "X6S"
					( Origin gFrontEnd )
				)
				( attribute "PACK_TYPE" "0603V"
					( Origin gFrontEnd )
				)
				( attribute "PART_NUMBER" "E15431-004"
					( Origin gFrontEnd )
				)
				( attribute "PHYS_PAGE" "132"
					( Origin gFrontEnd )
				)
				( attribute "ROOM" "SB_DECOUPLING"
					( Origin gFrontEnd )
				)
				( attribute "ROT" "0"
					( Origin gFrontEnd )
				)
				( attribute "SEC" "1"
					( Origin gPackager )
				)
				( attribute "TOLERANCE" "20%"
					( Origin gFrontEnd )
				)
				( attribute "VALUE" "22.0UF"
					( Origin gFrontEnd )
				)
				( attribute "VER" "1"
					( Origin gFrontEnd )
				)
				( attribute "VOLTAGE" "4V"
					( Units "uVoltage" "V" 1.000000)
					( Origin gFrontEnd )
				)
				( attribute "XY" "(1450,3500)"
					( Origin gFrontEnd )
				)
				( attribute "CHIPS_PART_NAME" "CAP_A"
					( Origin gPackager )
				)
				( attribute "CDS_PART_NAME" "CAP_A_0603V-22.0UF,4V,20%,X6S,A"
					( Origin gPackager )
				)
				( objectStatus "C3N10" )
				( pin "a"
					( attribute "PN" "1"
						( Origin gPackager )
					)
					( objectStatus "C3N10.1" )
				)
				( pin "b"
					( attribute "PN" "2"
						( Origin gPackager )
					)
					( objectStatus "C3N10.2" )
				)
			)
			( gate "@baseboard_fab2_lib.baseboard_fab2(sch_1):page132_i16"
				( attribute "BOM_COST" "SB"
					( Origin gFrontEnd )
				)
				( attribute "CDS_LIB" "dev_discrete"
					( Origin gPackager )
				)
				( attribute "CDS_LOCATION" "C3N24"
					( Origin gPackager )
				)
				( attribute "CDS_SEC" "1"
					( Origin gPackager )
				)
				( attribute "LOCATION" "C3N24"
					( Origin gFrontEnd )
				)
				( attribute "MATERIAL" "X6S"
					( Origin gFrontEnd )
				)
				( attribute "PACK_TYPE" "0603V"
					( Origin gFrontEnd )
				)
				( attribute "PART_NUMBER" "E15431-004"
					( Origin gFrontEnd )
				)
				( attribute "PHYS_PAGE" "132"
					( Origin gFrontEnd )
				)
				( attribute "ROOM" "SB_DECOUPLING"
					( Origin gFrontEnd )
				)
				( attribute "ROT" "0"
					( Origin gFrontEnd )
				)
				( attribute "SEC" "1"
					( Origin gPackager )
				)
				( attribute "TOLERANCE" "20%"
					( Origin gFrontEnd )
				)
				( attribute "VALUE" "22.0UF"
					( Origin gFrontEnd )
				)
				( attribute "VER" "1"
					( Origin gFrontEnd )
				)
				( attribute "VOLTAGE" "4V"
					( Units "uVoltage" "V" 1.000000)
					( Origin gFrontEnd )
				)
				( attribute "XY" "(1850,2525)"
					( Origin gFrontEnd )
				)
				( attribute "CHIPS_PART_NAME" "CAP_A"
					( Origin gPackager )
				)
				( attribute "CDS_PART_NAME" "CAP_A_0603V-22.0UF,4V,20%,X6S,A"
					( Origin gPackager )
				)
				( objectStatus "C3N24" )
				( pin "a"
					( attribute "PN" "1"
						( Origin gPackager )
					)
					( objectStatus "C3N24.1" )
				)
				( pin "b"
					( attribute "PN" "2"
						( Origin gPackager )
					)
					( objectStatus "C3N24.2" )
				)
			)
			( gate "@baseboard_fab2_lib.baseboard_fab2(sch_1):page132_i17"
				( attribute "BOM_COST" "SB"
					( Origin gFrontEnd )
				)
				( attribute "CDS_LIB" "dev_discrete"
					( Origin gPackager )
				)
				( attribute "CDS_LOCATION" "C3N28"
					( Origin gPackager )
				)
				( attribute "CDS_SEC" "1"
					( Origin gPackager )
				)
				( attribute "LOCATION" "C3N28"
					( Origin gFrontEnd )
				)
				( attribute "MATERIAL" "X6S"
					( Origin gFrontEnd )
				)
				( attribute "PACK_TYPE" "0603V"
					( Origin gFrontEnd )
				)
				( attribute "PART_NUMBER" "E15431-004"
					( Origin gFrontEnd )
				)
				( attribute "PHYS_PAGE" "132"
					( Origin gFrontEnd )
				)
				( attribute "ROOM" "SB_DECOUPLING"
					( Origin gFrontEnd )
				)
				( attribute "ROT" "0"
					( Origin gFrontEnd )
				)
				( attribute "SEC" "1"
					( Origin gPackager )
				)
				( attribute "TOLERANCE" "20%"
					( Origin gFrontEnd )
				)
				( attribute "VALUE" "22.0UF"
					( Origin gFrontEnd )
				)
				( attribute "VER" "1"
					( Origin gFrontEnd )
				)
				( attribute "VOLTAGE" "4V"
					( Units "uVoltage" "V" 1.000000)
					( Origin gFrontEnd )
				)
				( attribute "XY" "(1475,2525)"
					( Origin gFrontEnd )
				)
				( attribute "CHIPS_PART_NAME" "CAP_A"
					( Origin gPackager )
				)
				( attribute "CDS_PART_NAME" "CAP_A_0603V-22.0UF,4V,20%,X6S,A"
					( Origin gPackager )
				)
				( objectStatus "C3N28" )
				( pin "a"
					( attribute "PN" "1"
						( Origin gPackager )
					)
					( objectStatus "C3N28.1" )
				)
				( pin "b"
					( attribute "PN" "2"
						( Origin gPackager )
					)
					( objectStatus "C3N28.2" )
				)
			)
			( gate "@baseboard_fab2_lib.baseboard_fab2(sch_1):page132_i19"
				( attribute "BOM_COST" "SB"
					( Origin gFrontEnd )
				)
				( attribute "CDS_LIB" "dev_discrete"
					( Origin gPackager )
				)
				( attribute "CDS_LOCATION" "C3N11"
					( Origin gPackager )
				)
				( attribute "CDS_SEC" "1"
					( Origin gPackager )
				)
				( attribute "LOCATION" "C3N11"
					( Origin gFrontEnd )
				)
				( attribute "MATERIAL" "X6S"
					( Origin gFrontEnd )
				)
				( attribute "PACK_TYPE" "0603V"
					( Origin gFrontEnd )
				)
				( attribute "PART_NUMBER" "E15431-004"
					( Origin gFrontEnd )
				)
				( attribute "PHYS_PAGE" "132"
					( Origin gFrontEnd )
				)
				( attribute "ROOM" "SB_DECOUPLING"
					( Origin gFrontEnd )
				)
				( attribute "ROT" "0"
					( Origin gFrontEnd )
				)
				( attribute "SEC" "1"
					( Origin gPackager )
				)
				( attribute "TOLERANCE" "20%"
					( Origin gFrontEnd )
				)
				( attribute "VALUE" "22.0UF"
					( Origin gFrontEnd )
				)
				( attribute "VER" "1"
					( Origin gFrontEnd )
				)
				( attribute "VOLTAGE" "4V"
					( Units "uVoltage" "V" 1.000000)
					( Origin gFrontEnd )
				)
				( attribute "XY" "(1075,3500)"
					( Origin gFrontEnd )
				)
				( attribute "CHIPS_PART_NAME" "CAP_A"
					( Origin gPackager )
				)
				( attribute "CDS_PART_NAME" "CAP_A_0603V-22.0UF,4V,20%,X6S,A"
					( Origin gPackager )
				)
				( objectStatus "C3N11" )
				( pin "a"
					( attribute "PN" "1"
						( Origin gPackager )
					)
					( objectStatus "C3N11.1" )
				)
				( pin "b"
					( attribute "PN" "2"
						( Origin gPackager )
					)
					( objectStatus "C3N11.2" )
				)
			)
			( gate "@baseboard_fab2_lib.baseboard_fab2(sch_1):page132_i20"
				( attribute "BOM_COST" "SB"
					( Origin gFrontEnd )
				)
				( attribute "CDS_LIB" "dev_discrete"
					( Origin gPackager )
				)
				( attribute "CDS_LOCATION" "C3N31"
					( Origin gPackager )
				)
				( attribute "CDS_SEC" "1"
					( Origin gPackager )
				)
				( attribute "LOCATION" "C3N31"
					( Origin gFrontEnd )
				)
				( attribute "MATERIAL" "X6S"
					( Origin gFrontEnd )
				)
				( attribute "PACK_TYPE" "0603V"
					( Origin gFrontEnd )
				)
				( attribute "PART_NUMBER" "E15431-004"
					( Origin gFrontEnd )
				)
				( attribute "PHYS_PAGE" "132"
					( Origin gFrontEnd )
				)
				( attribute "ROOM" "SB_DECOUPLING"
					( Origin gFrontEnd )
				)
				( attribute "ROT" "0"
					( Origin gFrontEnd )
				)
				( attribute "SEC" "1"
					( Origin gPackager )
				)
				( attribute "TOLERANCE" "20%"
					( Origin gFrontEnd )
				)
				( attribute "VALUE" "22.0UF"
					( Origin gFrontEnd )
				)
				( attribute "VER" "1"
					( Origin gFrontEnd )
				)
				( attribute "VOLTAGE" "4V"
					( Units "uVoltage" "V" 1.000000)
					( Origin gFrontEnd )
				)
				( attribute "XY" "(1100,2525)"
					( Origin gFrontEnd )
				)
				( attribute "CHIPS_PART_NAME" "CAP_A"
					( Origin gPackager )
				)
				( attribute "CDS_PART_NAME" "CAP_A_0603V-22.0UF,4V,20%,X6S,A"
					( Origin gPackager )
				)
				( objectStatus "C3N31" )
				( pin "a"
					( attribute "PN" "1"
						( Origin gPackager )
					)
					( objectStatus "C3N31.1" )
				)
				( pin "b"
					( attribute "PN" "2"
						( Origin gPackager )
					)
					( objectStatus "C3N31.2" )
				)
			)
			( gate "@baseboard_fab2_lib.baseboard_fab2(sch_1):page132_i23"
				( attribute "BOM_COST" "SB"
					( Origin gFrontEnd )
				)
				( attribute "CDS_LIB" "mstr_discrete"
					( Origin gPackager )
				)
				( attribute "CDS_LOCATION" "C7A33"
					( Origin gPackager )
				)
				( attribute "CDS_SEC" "1"
					( Origin gPackager )
				)
				( attribute "LOCATION" "C7A33"
					( Origin gFrontEnd )
				)
				( attribute "MATERIAL" "X6S"
					( Origin gFrontEnd )
				)
				( attribute "PACK_TYPE" "0805"
					( Origin gFrontEnd )
				)
				( attribute "PART_NUMBER" "C95333-006"
					( Origin gFrontEnd )
				)
				( attribute "PHYS_PAGE" "132"
					( Origin gFrontEnd )
				)
				( attribute "ROOM" "SB_DECOUPLING"
					( Origin gFrontEnd )
				)
				( attribute "ROT" "0"
					( Origin gFrontEnd )
				)
				( attribute "SEC" "1"
					( Origin gPackager )
				)
				( attribute "TOLERANCE" "20%"
					( Origin gFrontEnd )
				)
				( attribute "VALUE" "47UF"
					( Origin gFrontEnd )
				)
				( attribute "VER" "1"
					( Origin gFrontEnd )
				)
				( attribute "VOLTAGE" "4V"
					( Units "uVoltage" "V" 1.000000)
					( Origin gFrontEnd )
				)
				( attribute "XY" "(2150,1575)"
					( Origin gFrontEnd )
				)
				( attribute "CHIPS_PART_NAME" "CAP"
					( Origin gPackager )
				)
				( attribute "CDS_PART_NAME" "CAP_0805-47UF,4V,20%,X6S,C9533A"
					( Origin gPackager )
				)
				( objectStatus "C7A33" )
				( pin "a"
					( attribute "PN" "1"
						( Origin gPackager )
					)
					( objectStatus "C7A33.1" )
				)
				( pin "b"
					( attribute "PN" "2"
						( Origin gPackager )
					)
					( objectStatus "C7A33.2" )
				)
			)
			( gate "@baseboard_fab2_lib.baseboard_fab2(sch_1):page132_i24"
				( attribute "BOM_COST" "SB"
					( Origin gFrontEnd )
				)
				( attribute "CDS_LIB" "mstr_discrete"
					( Origin gPackager )
				)
				( attribute "CDS_LOCATION" "C7B4"
					( Origin gPackager )
				)
				( attribute "CDS_SEC" "1"
					( Origin gPackager )
				)
				( attribute "LOCATION" "C7B4"
					( Origin gFrontEnd )
				)
				( attribute "MATERIAL" "X6S"
					( Origin gFrontEnd )
				)
				( attribute "PACK_TYPE" "0805"
					( Origin gFrontEnd )
				)
				( attribute "PART_NUMBER" "C95333-006"
					( Origin gFrontEnd )
				)
				( attribute "PHYS_PAGE" "132"
					( Origin gFrontEnd )
				)
				( attribute "ROOM" "SB_DECOUPLING"
					( Origin gFrontEnd )
				)
				( attribute "ROT" "0"
					( Origin gFrontEnd )
				)
				( attribute "SEC" "1"
					( Origin gPackager )
				)
				( attribute "TOLERANCE" "20%"
					( Origin gFrontEnd )
				)
				( attribute "VALUE" "47UF"
					( Origin gFrontEnd )
				)
				( attribute "VER" "1"
					( Origin gFrontEnd )
				)
				( attribute "VOLTAGE" "4V"
					( Units "uVoltage" "V" 1.000000)
					( Origin gFrontEnd )
				)
				( attribute "XY" "(1700,1575)"
					( Origin gFrontEnd )
				)
				( attribute "CHIPS_PART_NAME" "CAP"
					( Origin gPackager )
				)
				( attribute "CDS_PART_NAME" "CAP_0805-47UF,4V,20%,X6S,C9533A"
					( Origin gPackager )
				)
				( objectStatus "C7B4" )
				( pin "a"
					( attribute "PN" "1"
						( Origin gPackager )
					)
					( objectStatus "C7B4.1" )
				)
				( pin "b"
					( attribute "PN" "2"
						( Origin gPackager )
					)
					( objectStatus "C7B4.2" )
				)
			)
			( gate "@baseboard_fab2_lib.baseboard_fab2(sch_1):page132_i26"
				( attribute "CDS_LIB" "dev_discrete"
					( Origin gPackager )
				)
				( attribute "CDS_LOCATION" "C2N9"
					( Origin gPackager )
				)
				( attribute "CDS_SEC" "1"
					( Origin gPackager )
				)
				( attribute "LOCATION" "C2N9"
					( Origin gFrontEnd )
				)
				( attribute "MATERIAL" "X6S"
					( Origin gFrontEnd )
				)
				( attribute "PACK_TYPE" "0402V"
					( Origin gFrontEnd )
				)
				( attribute "PART_NUMBER" "D97712-004"
					( Origin gFrontEnd )
				)
				( attribute "PHYS_PAGE" "132"
					( Origin gFrontEnd )
				)
				( attribute "ROOM" "SB_DECOUPLING"
					( Origin gFrontEnd )
				)
				( attribute "ROT" "0"
					( Origin gFrontEnd )
				)
				( attribute "SEC" "1"
					( Origin gPackager )
				)
				( attribute "TOLERANCE" "10%"
					( Origin gFrontEnd )
				)
				( attribute "VALUE" "1.0UF"
					( Origin gFrontEnd )
				)
				( attribute "VER" "1"
					( Origin gFrontEnd )
				)
				( attribute "VOLTAGE" "6.3V"
					( Units "uVoltage" "V" 1.000000)
					( Origin gFrontEnd )
				)
				( attribute "XY" "(-325,4050)"
					( Origin gFrontEnd )
				)
				( attribute "CHIPS_PART_NAME" "CAP_A"
					( Origin gPackager )
				)
				( attribute "CDS_PART_NAME" "CAP_A_0402V-1.0UF,6.3V,10%,X6SA"
					( Origin gPackager )
				)
				( objectStatus "C2N9" )
				( pin "a"
					( attribute "PN" "1"
						( Origin gPackager )
					)
					( objectStatus "C2N9.1" )
				)
				( pin "b"
					( attribute "PN" "2"
						( Origin gPackager )
					)
					( objectStatus "C2N9.2" )
				)
			)
			( gate "@baseboard_fab2_lib.baseboard_fab2(sch_1):page132_i27"
				( attribute "BOM_COST" "SB"
					( Origin gFrontEnd )
				)
				( attribute "CDS_LIB" "dev_discrete"
					( Origin gPackager )
				)
				( attribute "CDS_LOCATION" "C2N3"
					( Origin gPackager )
				)
				( attribute "CDS_SEC" "1"
					( Origin gPackager )
				)
				( attribute "LOCATION" "C2N3"
					( Origin gFrontEnd )
				)
				( attribute "MATERIAL" "X6S"
					( Origin gFrontEnd )
				)
				( attribute "PACK_TYPE" "0402V"
					( Origin gFrontEnd )
				)
				( attribute "PART_NUMBER" "D97712-004"
					( Origin gFrontEnd )
				)
				( attribute "PHYS_PAGE" "132"
					( Origin gFrontEnd )
				)
				( attribute "ROOM" "SB_DECOUPLING"
					( Origin gFrontEnd )
				)
				( attribute "ROT" "0"
					( Origin gFrontEnd )
				)
				( attribute "SEC" "1"
					( Origin gPackager )
				)
				( attribute "TOLERANCE" "10%"
					( Origin gFrontEnd )
				)
				( attribute "VALUE" "1.0UF"
					( Origin gFrontEnd )
				)
				( attribute "VER" "1"
					( Origin gFrontEnd )
				)
				( attribute "VOLTAGE" "6.3V"
					( Units "uVoltage" "V" 1.000000)
					( Origin gFrontEnd )
				)
				( attribute "XY" "(-725,4050)"
					( Origin gFrontEnd )
				)
				( attribute "CHIPS_PART_NAME" "CAP_A"
					( Origin gPackager )
				)
				( attribute "CDS_PART_NAME" "CAP_A_0402V-1.0UF,6.3V,10%,X6SA"
					( Origin gPackager )
				)
				( objectStatus "C2N3" )
				( pin "a"
					( attribute "PN" "1"
						( Origin gPackager )
					)
					( objectStatus "C2N3.1" )
				)
				( pin "b"
					( attribute "PN" "2"
						( Origin gPackager )
					)
					( objectStatus "C2N3.2" )
				)
			)
			( gate "@baseboard_fab2_lib.baseboard_fab2(sch_1):page132_i28"
				( attribute "CDS_LIB" "dev_discrete"
					( Origin gPackager )
				)
				( attribute "CDS_LOCATION" "C2N4"
					( Origin gPackager )
				)
				( attribute "CDS_SEC" "1"
					( Origin gPackager )
				)
				( attribute "LOCATION" "C2N4"
					( Origin gFrontEnd )
				)
				( attribute "MATERIAL" "X6S"
					( Origin gFrontEnd )
				)
				( attribute "PACK_TYPE" "0402V"
					( Origin gFrontEnd )
				)
				( attribute "PART_NUMBER" "D97712-004"
					( Origin gFrontEnd )
				)
				( attribute "PHYS_PAGE" "132"
					( Origin gFrontEnd )
				)
				( attribute "ROOM" "SB_DECOUPLING"
					( Origin gFrontEnd )
				)
				( attribute "ROT" "0"
					( Origin gFrontEnd )
				)
				( attribute "SEC" "1"
					( Origin gPackager )
				)
				( attribute "TOLERANCE" "10%"
					( Origin gFrontEnd )
				)
				( attribute "VALUE" "1.0UF"
					( Origin gFrontEnd )
				)
				( attribute "VER" "1"
					( Origin gFrontEnd )
				)
				( attribute "VOLTAGE" "6.3V"
					( Units "uVoltage" "V" 1.000000)
					( Origin gFrontEnd )
				)
				( attribute "XY" "(-300,3025)"
					( Origin gFrontEnd )
				)
				( attribute "CHIPS_PART_NAME" "CAP_A"
					( Origin gPackager )
				)
				( attribute "CDS_PART_NAME" "CAP_A_0402V-1.0UF,6.3V,10%,X6SA"
					( Origin gPackager )
				)
				( objectStatus "C2N4" )
				( pin "a"
					( attribute "PN" "1"
						( Origin gPackager )
					)
					( objectStatus "C2N4.1" )
				)
				( pin "b"
					( attribute "PN" "2"
						( Origin gPackager )
					)
					( objectStatus "C2N4.2" )
				)
			)
			( gate "@baseboard_fab2_lib.baseboard_fab2(sch_1):page132_i29"
				( attribute "BOM_COST" "SB"
					( Origin gFrontEnd )
				)
				( attribute "CDS_LIB" "dev_discrete"
					( Origin gPackager )
				)
				( attribute "CDS_LOCATION" "C2N12"
					( Origin gPackager )
				)
				( attribute "CDS_SEC" "1"
					( Origin gPackager )
				)
				( attribute "LOCATION" "C2N12"
					( Origin gFrontEnd )
				)
				( attribute "MATERIAL" "X6S"
					( Origin gFrontEnd )
				)
				( attribute "PACK_TYPE" "0402V"
					( Origin gFrontEnd )
				)
				( attribute "PART_NUMBER" "D97712-004"
					( Origin gFrontEnd )
				)
				( attribute "PHYS_PAGE" "132"
					( Origin gFrontEnd )
				)
				( attribute "ROOM" "SB_DECOUPLING"
					( Origin gFrontEnd )
				)
				( attribute "ROT" "0"
					( Origin gFrontEnd )
				)
				( attribute "SEC" "1"
					( Origin gPackager )
				)
				( attribute "TOLERANCE" "10%"
					( Origin gFrontEnd )
				)
				( attribute "VALUE" "1.0UF"
					( Origin gFrontEnd )
				)
				( attribute "VER" "1"
					( Origin gFrontEnd )
				)
				( attribute "VOLTAGE" "6.3V"
					( Units "uVoltage" "V" 1.000000)
					( Origin gFrontEnd )
				)
				( attribute "XY" "(-700,3025)"
					( Origin gFrontEnd )
				)
				( attribute "CHIPS_PART_NAME" "CAP_A"
					( Origin gPackager )
				)
				( attribute "CDS_PART_NAME" "CAP_A_0402V-1.0UF,6.3V,10%,X6SA"
					( Origin gPackager )
				)
				( objectStatus "C2N12" )
				( pin "a"
					( attribute "PN" "1"
						( Origin gPackager )
					)
					( objectStatus "C2N12.1" )
				)
				( pin "b"
					( attribute "PN" "2"
						( Origin gPackager )
					)
					( objectStatus "C2N12.2" )
				)
			)
			( gate "@baseboard_fab2_lib.baseboard_fab2(sch_1):page132_i30"
				( attribute "BOM_COST" "SB"
					( Origin gFrontEnd )
				)
				( attribute "CDS_LIB" "dev_discrete"
					( Origin gPackager )
				)
				( attribute "CDS_LOCATION" "C2N11"
					( Origin gPackager )
				)
				( attribute "CDS_SEC" "1"
					( Origin gPackager )
				)
				( attribute "LOCATION" "C2N11"
					( Origin gFrontEnd )
				)
				( attribute "MATERIAL" "X6S"
					( Origin gFrontEnd )
				)
				( attribute "PACK_TYPE" "0402V"
					( Origin gFrontEnd )
				)
				( attribute "PART_NUMBER" "D97712-004"
					( Origin gFrontEnd )
				)
				( attribute "PHYS_PAGE" "132"
					( Origin gFrontEnd )
				)
				( attribute "ROOM" "SB_DECOUPLING"
					( Origin gFrontEnd )
				)
				( attribute "ROT" "0"
					( Origin gFrontEnd )
				)
				( attribute "SEC" "1"
					( Origin gPackager )
				)
				( attribute "TOLERANCE" "10%"
					( Origin gFrontEnd )
				)
				( attribute "VALUE" "1.0UF"
					( Origin gFrontEnd )
				)
				( attribute "VER" "1"
					( Origin gFrontEnd )
				)
				( attribute "VOLTAGE" "6.3V"
					( Units "uVoltage" "V" 1.000000)
					( Origin gFrontEnd )
				)
				( attribute "XY" "(-1100,4050)"
					( Origin gFrontEnd )
				)
				( attribute "CHIPS_PART_NAME" "CAP_A"
					( Origin gPackager )
				)
				( attribute "CDS_PART_NAME" "CAP_A_0402V-1.0UF,6.3V,10%,X6SA"
					( Origin gPackager )
				)
				( objectStatus "C2N11" )
				( pin "a"
					( attribute "PN" "1"
						( Origin gPackager )
					)
					( objectStatus "C2N11.1" )
				)
				( pin "b"
					( attribute "PN" "2"
						( Origin gPackager )
					)
					( objectStatus "C2N11.2" )
				)
			)
			( gate "@baseboard_fab2_lib.baseboard_fab2(sch_1):page132_i31"
				( attribute "BOM_COST" "SB"
					( Origin gFrontEnd )
				)
				( attribute "CDS_LIB" "dev_discrete"
					( Origin gPackager )
				)
				( attribute "CDS_LOCATION" "C3N19"
					( Origin gPackager )
				)
				( attribute "CDS_SEC" "1"
					( Origin gPackager )
				)
				( attribute "LOCATION" "C3N19"
					( Origin gFrontEnd )
				)
				( attribute "MATERIAL" "X6S"
					( Origin gFrontEnd )
				)
				( attribute "PACK_TYPE" "0402V"
					( Origin gFrontEnd )
				)
				( attribute "PART_NUMBER" "D97712-004"
					( Origin gFrontEnd )
				)
				( attribute "PHYS_PAGE" "132"
					( Origin gFrontEnd )
				)
				( attribute "ROOM" "SB_DECOUPLING"
					( Origin gFrontEnd )
				)
				( attribute "ROT" "0"
					( Origin gFrontEnd )
				)
				( attribute "SEC" "1"
					( Origin gPackager )
				)
				( attribute "TOLERANCE" "10%"
					( Origin gFrontEnd )
				)
				( attribute "VALUE" "1.0UF"
					( Origin gFrontEnd )
				)
				( attribute "VER" "1"
					( Origin gFrontEnd )
				)
				( attribute "VOLTAGE" "6.3V"
					( Units "uVoltage" "V" 1.000000)
					( Origin gFrontEnd )
				)
				( attribute "XY" "(-1475,4050)"
					( Origin gFrontEnd )
				)
				( attribute "CHIPS_PART_NAME" "CAP_A"
					( Origin gPackager )
				)
				( attribute "CDS_PART_NAME" "CAP_A_0402V-1.0UF,6.3V,10%,X6SA"
					( Origin gPackager )
				)
				( objectStatus "C3N19" )
				( pin "a"
					( attribute "PN" "1"
						( Origin gPackager )
					)
					( objectStatus "C3N19.1" )
				)
				( pin "b"
					( attribute "PN" "2"
						( Origin gPackager )
					)
					( objectStatus "C3N19.2" )
				)
			)
			( gate "@baseboard_fab2_lib.baseboard_fab2(sch_1):page132_i32"
				( attribute "BOM_COST" "SB"
					( Origin gFrontEnd )
				)
				( attribute "CDS_LIB" "dev_discrete"
					( Origin gPackager )
				)
				( attribute "CDS_LOCATION" "C3N3"
					( Origin gPackager )
				)
				( attribute "CDS_SEC" "1"
					( Origin gPackager )
				)
				( attribute "LOCATION" "C3N3"
					( Origin gFrontEnd )
				)
				( attribute "MATERIAL" "X6S"
					( Origin gFrontEnd )
				)
				( attribute "PACK_TYPE" "0402V"
					( Origin gFrontEnd )
				)
				( attribute "PART_NUMBER" "D97712-004"
					( Origin gFrontEnd )
				)
				( attribute "PHYS_PAGE" "132"
					( Origin gFrontEnd )
				)
				( attribute "ROOM" "SB_DECOUPLING"
					( Origin gFrontEnd )
				)
				( attribute "ROT" "0"
					( Origin gFrontEnd )
				)
				( attribute "SEC" "1"
					( Origin gPackager )
				)
				( attribute "TOLERANCE" "10%"
					( Origin gFrontEnd )
				)
				( attribute "VALUE" "1.0UF"
					( Origin gFrontEnd )
				)
				( attribute "VER" "1"
					( Origin gFrontEnd )
				)
				( attribute "VOLTAGE" "6.3V"
					( Units "uVoltage" "V" 1.000000)
					( Origin gFrontEnd )
				)
				( attribute "XY" "(-1850,4050)"
					( Origin gFrontEnd )
				)
				( attribute "CHIPS_PART_NAME" "CAP_A"
					( Origin gPackager )
				)
				( attribute "CDS_PART_NAME" "CAP_A_0402V-1.0UF,6.3V,10%,X6SA"
					( Origin gPackager )
				)
				( objectStatus "C3N3" )
				( pin "a"
					( attribute "PN" "1"
						( Origin gPackager )
					)
					( objectStatus "C3N3.1" )
				)
				( pin "b"
					( attribute "PN" "2"
						( Origin gPackager )
					)
					( objectStatus "C3N3.2" )
				)
			)
			( gate "@baseboard_fab2_lib.baseboard_fab2(sch_1):page132_i34"
				( attribute "BOM_COST" "SB"
					( Origin gFrontEnd )
				)
				( attribute "CDS_LIB" "dev_discrete"
					( Origin gPackager )
				)
				( attribute "CDS_LOCATION" "C3N1"
					( Origin gPackager )
				)
				( attribute "CDS_SEC" "1"
					( Origin gPackager )
				)
				( attribute "LOCATION" "C3N1"
					( Origin gFrontEnd )
				)
				( attribute "MATERIAL" "X6S"
					( Origin gFrontEnd )
				)
				( attribute "PACK_TYPE" "0402V"
					( Origin gFrontEnd )
				)
				( attribute "PART_NUMBER" "D97712-004"
					( Origin gFrontEnd )
				)
				( attribute "PHYS_PAGE" "132"
					( Origin gFrontEnd )
				)
				( attribute "ROOM" "SB_DECOUPLING"
					( Origin gFrontEnd )
				)
				( attribute "ROT" "0"
					( Origin gFrontEnd )
				)
				( attribute "SEC" "1"
					( Origin gPackager )
				)
				( attribute "TOLERANCE" "10%"
					( Origin gFrontEnd )
				)
				( attribute "VALUE" "1.0UF"
					( Origin gFrontEnd )
				)
				( attribute "VER" "1"
					( Origin gFrontEnd )
				)
				( attribute "VOLTAGE" "6.3V"
					( Units "uVoltage" "V" 1.000000)
					( Origin gFrontEnd )
				)
				( attribute "XY" "(-1075,3025)"
					( Origin gFrontEnd )
				)
				( attribute "CHIPS_PART_NAME" "CAP_A"
					( Origin gPackager )
				)
				( attribute "CDS_PART_NAME" "CAP_A_0402V-1.0UF,6.3V,10%,X6SA"
					( Origin gPackager )
				)
				( objectStatus "C3N1" )
				( pin "a"
					( attribute "PN" "1"
						( Origin gPackager )
					)
					( objectStatus "C3N1.1" )
				)
				( pin "b"
					( attribute "PN" "2"
						( Origin gPackager )
					)
					( objectStatus "C3N1.2" )
				)
			)
			( gate "@baseboard_fab2_lib.baseboard_fab2(sch_1):page132_i35"
				( attribute "BOM_COST" "SB"
					( Origin gFrontEnd )
				)
				( attribute "CDS_LIB" "dev_discrete"
					( Origin gPackager )
				)
				( attribute "CDS_LOCATION" "C3N7"
					( Origin gPackager )
				)
				( attribute "CDS_SEC" "1"
					( Origin gPackager )
				)
				( attribute "LOCATION" "C3N7"
					( Origin gFrontEnd )
				)
				( attribute "MATERIAL" "X6S"
					( Origin gFrontEnd )
				)
				( attribute "PACK_TYPE" "0402V"
					( Origin gFrontEnd )
				)
				( attribute "PART_NUMBER" "D97712-004"
					( Origin gFrontEnd )
				)
				( attribute "PHYS_PAGE" "132"
					( Origin gFrontEnd )
				)
				( attribute "ROOM" "SB_DECOUPLING"
					( Origin gFrontEnd )
				)
				( attribute "ROT" "0"
					( Origin gFrontEnd )
				)
				( attribute "SEC" "1"
					( Origin gPackager )
				)
				( attribute "TOLERANCE" "10%"
					( Origin gFrontEnd )
				)
				( attribute "VALUE" "1.0UF"
					( Origin gFrontEnd )
				)
				( attribute "VER" "1"
					( Origin gFrontEnd )
				)
				( attribute "VOLTAGE" "6.3V"
					( Units "uVoltage" "V" 1.000000)
					( Origin gFrontEnd )
				)
				( attribute "XY" "(-1450,3025)"
					( Origin gFrontEnd )
				)
				( attribute "CHIPS_PART_NAME" "CAP_A"
					( Origin gPackager )
				)
				( attribute "CDS_PART_NAME" "CAP_A_0402V-1.0UF,6.3V,10%,X6SA"
					( Origin gPackager )
				)
				( objectStatus "C3N7" )
				( pin "a"
					( attribute "PN" "1"
						( Origin gPackager )
					)
					( objectStatus "C3N7.1" )
				)
				( pin "b"
					( attribute "PN" "2"
						( Origin gPackager )
					)
					( objectStatus "C3N7.2" )
				)
			)
			( gate "@baseboard_fab2_lib.baseboard_fab2(sch_1):page132_i36"
				( attribute "BOM_COST" "SB"
					( Origin gFrontEnd )
				)
				( attribute "CDS_LIB" "dev_discrete"
					( Origin gPackager )
				)
				( attribute "CDS_LOCATION" "C3N16"
					( Origin gPackager )
				)
				( attribute "CDS_SEC" "1"
					( Origin gPackager )
				)
				( attribute "LOCATION" "C3N16"
					( Origin gFrontEnd )
				)
				( attribute "MATERIAL" "X6S"
					( Origin gFrontEnd )
				)
				( attribute "PACK_TYPE" "0402V"
					( Origin gFrontEnd )
				)
				( attribute "PART_NUMBER" "D97712-004"
					( Origin gFrontEnd )
				)
				( attribute "PHYS_PAGE" "132"
					( Origin gFrontEnd )
				)
				( attribute "ROOM" "SB_DECOUPLING"
					( Origin gFrontEnd )
				)
				( attribute "ROT" "0"
					( Origin gFrontEnd )
				)
				( attribute "SEC" "1"
					( Origin gPackager )
				)
				( attribute "TOLERANCE" "10%"
					( Origin gFrontEnd )
				)
				( attribute "VALUE" "1.0UF"
					( Origin gFrontEnd )
				)
				( attribute "VER" "1"
					( Origin gFrontEnd )
				)
				( attribute "VOLTAGE" "6.3V"
					( Units "uVoltage" "V" 1.000000)
					( Origin gFrontEnd )
				)
				( attribute "XY" "(-1825,3025)"
					( Origin gFrontEnd )
				)
				( attribute "CHIPS_PART_NAME" "CAP_A"
					( Origin gPackager )
				)
				( attribute "CDS_PART_NAME" "CAP_A_0402V-1.0UF,6.3V,10%,X6SA"
					( Origin gPackager )
				)
				( objectStatus "C3N16" )
				( pin "a"
					( attribute "PN" "1"
						( Origin gPackager )
					)
					( objectStatus "C3N16.1" )
				)
				( pin "b"
					( attribute "PN" "2"
						( Origin gPackager )
					)
					( objectStatus "C3N16.2" )
				)
			)
			( gate "@baseboard_fab2_lib.baseboard_fab2(sch_1):page132_i38"
				( attribute "BOM_COST" "SB"
					( Origin gFrontEnd )
				)
				( attribute "CDS_LIB" "mstr_discrete"
					( Origin gPackager )
				)
				( attribute "CDS_LOCATION" "C7A32"
					( Origin gPackager )
				)
				( attribute "CDS_SEC" "1"
					( Origin gPackager )
				)
				( attribute "LOCATION" "C7A32"
					( Origin gFrontEnd )
				)
				( attribute "MATERIAL" "X6S"
					( Origin gFrontEnd )
				)
				( attribute "PACK_TYPE" "0805"
					( Origin gFrontEnd )
				)
				( attribute "PART_NUMBER" "C95333-006"
					( Origin gFrontEnd )
				)
				( attribute "PHYS_PAGE" "132"
					( Origin gFrontEnd )
				)
				( attribute "ROOM" "SB_DECOUPLING"
					( Origin gFrontEnd )
				)
				( attribute "ROT" "0"
					( Origin gFrontEnd )
				)
				( attribute "SEC" "1"
					( Origin gPackager )
				)
				( attribute "TOLERANCE" "20%"
					( Origin gFrontEnd )
				)
				( attribute "VALUE" "47UF"
					( Origin gFrontEnd )
				)
				( attribute "VER" "1"
					( Origin gFrontEnd )
				)
				( attribute "VOLTAGE" "4V"
					( Units "uVoltage" "V" 1.000000)
					( Origin gFrontEnd )
				)
				( attribute "XY" "(-650,1900)"
					( Origin gFrontEnd )
				)
				( attribute "CHIPS_PART_NAME" "CAP"
					( Origin gPackager )
				)
				( attribute "CDS_PART_NAME" "CAP_0805-47UF,4V,20%,X6S,C9533A"
					( Origin gPackager )
				)
				( objectStatus "C7A32" )
				( pin "a"
					( attribute "PN" "1"
						( Origin gPackager )
					)
					( objectStatus "C7A32.1" )
				)
				( pin "b"
					( attribute "PN" "2"
						( Origin gPackager )
					)
					( objectStatus "C7A32.2" )
				)
			)
			( gate "@baseboard_fab2_lib.baseboard_fab2(sch_1):page132_i40"
				( attribute "BOM_COST" "SB"
					( Origin gFrontEnd )
				)
				( attribute "CDS_LIB" "mstr_discrete"
					( Origin gPackager )
				)
				( attribute "CDS_LOCATION" "C7A31"
					( Origin gPackager )
				)
				( attribute "CDS_SEC" "1"
					( Origin gPackager )
				)
				( attribute "LOCATION" "C7A31"
					( Origin gFrontEnd )
				)
				( attribute "MATERIAL" "X6S"
					( Origin gFrontEnd )
				)
				( attribute "PACK_TYPE" "0805"
					( Origin gFrontEnd )
				)
				( attribute "PART_NUMBER" "C95333-006"
					( Origin gFrontEnd )
				)
				( attribute "PHYS_PAGE" "132"
					( Origin gFrontEnd )
				)
				( attribute "ROOM" "SB_DECOUPLING"
					( Origin gFrontEnd )
				)
				( attribute "ROT" "0"
					( Origin gFrontEnd )
				)
				( attribute "SEC" "1"
					( Origin gPackager )
				)
				( attribute "TOLERANCE" "20%"
					( Origin gFrontEnd )
				)
				( attribute "VALUE" "47UF"
					( Origin gFrontEnd )
				)
				( attribute "VER" "1"
					( Origin gFrontEnd )
				)
				( attribute "VOLTAGE" "4V"
					( Units "uVoltage" "V" 1.000000)
					( Origin gFrontEnd )
				)
				( attribute "XY" "(-1100,1900)"
					( Origin gFrontEnd )
				)
				( attribute "CHIPS_PART_NAME" "CAP"
					( Origin gPackager )
				)
				( attribute "CDS_PART_NAME" "CAP_0805-47UF,4V,20%,X6S,C9533A"
					( Origin gPackager )
				)
				( objectStatus "C7A31" )
				( pin "a"
					( attribute "PN" "1"
						( Origin gPackager )
					)
					( objectStatus "C7A31.1" )
				)
				( pin "b"
					( attribute "PN" "2"
						( Origin gPackager )
					)
					( objectStatus "C7A31.2" )
				)
			)
			( gate "@baseboard_fab2_lib.baseboard_fab2(sch_1):page132_i42"
				( attribute "BOM_COST" "SB"
					( Origin gFrontEnd )
				)
				( attribute "CDS_LIB" "dev_discrete"
					( Origin gPackager )
				)
				( attribute "CDS_LOCATION" "C3N18"
					( Origin gPackager )
				)
				( attribute "CDS_SEC" "1"
					( Origin gPackager )
				)
				( attribute "LOCATION" "C3N18"
					( Origin gFrontEnd )
				)
				( attribute "MATERIAL" "X6S"
					( Origin gFrontEnd )
				)
				( attribute "PACK_TYPE" "0402V"
					( Origin gFrontEnd )
				)
				( attribute "PART_NUMBER" "D97712-004"
					( Origin gFrontEnd )
				)
				( attribute "PHYS_PAGE" "132"
					( Origin gFrontEnd )
				)
				( attribute "ROOM" "SB_DECOUPLING"
					( Origin gFrontEnd )
				)
				( attribute "ROT" "0"
					( Origin gFrontEnd )
				)
				( attribute "SEC" "1"
					( Origin gPackager )
				)
				( attribute "TOLERANCE" "10%"
					( Origin gFrontEnd )
				)
				( attribute "VALUE" "1.0UF"
					( Origin gFrontEnd )
				)
				( attribute "VER" "1"
					( Origin gFrontEnd )
				)
				( attribute "VOLTAGE" "6.3V"
					( Units "uVoltage" "V" 1.000000)
					( Origin gFrontEnd )
				)
				( attribute "XY" "(-2225,4050)"
					( Origin gFrontEnd )
				)
				( attribute "CHIPS_PART_NAME" "CAP_A"
					( Origin gPackager )
				)
				( attribute "CDS_PART_NAME" "CAP_A_0402V-1.0UF,6.3V,10%,X6SA"
					( Origin gPackager )
				)
				( objectStatus "C3N18" )
				( pin "a"
					( attribute "PN" "1"
						( Origin gPackager )
					)
					( objectStatus "C3N18.1" )
				)
				( pin "b"
					( attribute "PN" "2"
						( Origin gPackager )
					)
					( objectStatus "C3N18.2" )
				)
			)
			( gate "@baseboard_fab2_lib.baseboard_fab2(sch_1):page132_i43"
				( attribute "BOM_COST" "SB"
					( Origin gFrontEnd )
				)
				( attribute "CDS_LIB" "dev_discrete"
					( Origin gPackager )
				)
				( attribute "CDS_LOCATION" "C3N2"
					( Origin gPackager )
				)
				( attribute "CDS_SEC" "1"
					( Origin gPackager )
				)
				( attribute "LOCATION" "C3N2"
					( Origin gFrontEnd )
				)
				( attribute "MATERIAL" "X6S"
					( Origin gFrontEnd )
				)
				( attribute "PACK_TYPE" "0402V"
					( Origin gFrontEnd )
				)
				( attribute "PART_NUMBER" "D97712-004"
					( Origin gFrontEnd )
				)
				( attribute "PHYS_PAGE" "132"
					( Origin gFrontEnd )
				)
				( attribute "ROOM" "SB_DECOUPLING"
					( Origin gFrontEnd )
				)
				( attribute "ROT" "0"
					( Origin gFrontEnd )
				)
				( attribute "SEC" "1"
					( Origin gPackager )
				)
				( attribute "TOLERANCE" "10%"
					( Origin gFrontEnd )
				)
				( attribute "VALUE" "1.0UF"
					( Origin gFrontEnd )
				)
				( attribute "VER" "1"
					( Origin gFrontEnd )
				)
				( attribute "VOLTAGE" "6.3V"
					( Units "uVoltage" "V" 1.000000)
					( Origin gFrontEnd )
				)
				( attribute "XY" "(-2625,4050)"
					( Origin gFrontEnd )
				)
				( attribute "CHIPS_PART_NAME" "CAP_A"
					( Origin gPackager )
				)
				( attribute "CDS_PART_NAME" "CAP_A_0402V-1.0UF,6.3V,10%,X6SA"
					( Origin gPackager )
				)
				( objectStatus "C3N2" )
				( pin "a"
					( attribute "PN" "1"
						( Origin gPackager )
					)
					( objectStatus "C3N2.1" )
				)
				( pin "b"
					( attribute "PN" "2"
						( Origin gPackager )
					)
					( objectStatus "C3N2.2" )
				)
			)
			( gate "@baseboard_fab2_lib.baseboard_fab2(sch_1):page132_i44"
				( attribute "BOM_COST" "SB"
					( Origin gFrontEnd )
				)
				( attribute "CDS_LIB" "dev_discrete"
					( Origin gPackager )
				)
				( attribute "CDS_LOCATION" "C3N6"
					( Origin gPackager )
				)
				( attribute "CDS_SEC" "1"
					( Origin gPackager )
				)
				( attribute "LOCATION" "C3N6"
					( Origin gFrontEnd )
				)
				( attribute "MATERIAL" "X6S"
					( Origin gFrontEnd )
				)
				( attribute "PACK_TYPE" "0402V"
					( Origin gFrontEnd )
				)
				( attribute "PART_NUMBER" "D97712-004"
					( Origin gFrontEnd )
				)
				( attribute "PHYS_PAGE" "132"
					( Origin gFrontEnd )
				)
				( attribute "ROOM" "SB_DECOUPLING"
					( Origin gFrontEnd )
				)
				( attribute "ROT" "0"
					( Origin gFrontEnd )
				)
				( attribute "SEC" "1"
					( Origin gPackager )
				)
				( attribute "TOLERANCE" "10%"
					( Origin gFrontEnd )
				)
				( attribute "VALUE" "1.0UF"
					( Origin gFrontEnd )
				)
				( attribute "VER" "1"
					( Origin gFrontEnd )
				)
				( attribute "VOLTAGE" "6.3V"
					( Units "uVoltage" "V" 1.000000)
					( Origin gFrontEnd )
				)
				( attribute "XY" "(-2200,3025)"
					( Origin gFrontEnd )
				)
				( attribute "CHIPS_PART_NAME" "CAP_A"
					( Origin gPackager )
				)
				( attribute "CDS_PART_NAME" "CAP_A_0402V-1.0UF,6.3V,10%,X6SA"
					( Origin gPackager )
				)
				( objectStatus "C3N6" )
				( pin "a"
					( attribute "PN" "1"
						( Origin gPackager )
					)
					( objectStatus "C3N6.1" )
				)
				( pin "b"
					( attribute "PN" "2"
						( Origin gPackager )
					)
					( objectStatus "C3N6.2" )
				)
			)
			( gate "@baseboard_fab2_lib.baseboard_fab2(sch_1):page132_i45"
				( attribute "BOM_COST" "SB"
					( Origin gFrontEnd )
				)
				( attribute "CDS_LIB" "dev_discrete"
					( Origin gPackager )
				)
				( attribute "CDS_LOCATION" "C3N17"
					( Origin gPackager )
				)
				( attribute "CDS_SEC" "1"
					( Origin gPackager )
				)
				( attribute "LOCATION" "C3N17"
					( Origin gFrontEnd )
				)
				( attribute "MATERIAL" "X6S"
					( Origin gFrontEnd )
				)
				( attribute "PACK_TYPE" "0402V"
					( Origin gFrontEnd )
				)
				( attribute "PART_NUMBER" "D97712-004"
					( Origin gFrontEnd )
				)
				( attribute "PHYS_PAGE" "132"
					( Origin gFrontEnd )
				)
				( attribute "ROOM" "SB_DECOUPLING"
					( Origin gFrontEnd )
				)
				( attribute "ROT" "0"
					( Origin gFrontEnd )
				)
				( attribute "SEC" "1"
					( Origin gPackager )
				)
				( attribute "TOLERANCE" "10%"
					( Origin gFrontEnd )
				)
				( attribute "VALUE" "1.0UF"
					( Origin gFrontEnd )
				)
				( attribute "VER" "1"
					( Origin gFrontEnd )
				)
				( attribute "VOLTAGE" "6.3V"
					( Units "uVoltage" "V" 1.000000)
					( Origin gFrontEnd )
				)
				( attribute "XY" "(-2600,3025)"
					( Origin gFrontEnd )
				)
				( attribute "CHIPS_PART_NAME" "CAP_A"
					( Origin gPackager )
				)
				( attribute "CDS_PART_NAME" "CAP_A_0402V-1.0UF,6.3V,10%,X6SA"
					( Origin gPackager )
				)
				( objectStatus "C3N17" )
				( pin "a"
					( attribute "PN" "1"
						( Origin gPackager )
					)
					( objectStatus "C3N17.1" )
				)
				( pin "b"
					( attribute "PN" "2"
						( Origin gPackager )
					)
					( objectStatus "C3N17.2" )
				)
			)
			( gate "@baseboard_fab2_lib.baseboard_fab2(sch_1):page132_i46"
				( attribute "BOM_COST" "SB"
					( Origin gFrontEnd )
				)
				( attribute "CDS_LIB" "dev_discrete"
					( Origin gPackager )
				)
				( attribute "CDS_LOCATION" "C3N4"
					( Origin gPackager )
				)
				( attribute "CDS_SEC" "1"
					( Origin gPackager )
				)
				( attribute "LOCATION" "C3N4"
					( Origin gFrontEnd )
				)
				( attribute "MATERIAL" "X6S"
					( Origin gFrontEnd )
				)
				( attribute "PACK_TYPE" "0402V"
					( Origin gFrontEnd )
				)
				( attribute "PART_NUMBER" "D97712-004"
					( Origin gFrontEnd )
				)
				( attribute "PHYS_PAGE" "132"
					( Origin gFrontEnd )
				)
				( attribute "ROOM" "SB_DECOUPLING"
					( Origin gFrontEnd )
				)
				( attribute "ROT" "0"
					( Origin gFrontEnd )
				)
				( attribute "SEC" "1"
					( Origin gPackager )
				)
				( attribute "TOLERANCE" "10%"
					( Origin gFrontEnd )
				)
				( attribute "VALUE" "1.0UF"
					( Origin gFrontEnd )
				)
				( attribute "VER" "1"
					( Origin gFrontEnd )
				)
				( attribute "VOLTAGE" "6.3V"
					( Units "uVoltage" "V" 1.000000)
					( Origin gFrontEnd )
				)
				( attribute "XY" "(-3000,4050)"
					( Origin gFrontEnd )
				)
				( attribute "CHIPS_PART_NAME" "CAP_A"
					( Origin gPackager )
				)
				( attribute "CDS_PART_NAME" "CAP_A_0402V-1.0UF,6.3V,10%,X6SA"
					( Origin gPackager )
				)
				( objectStatus "C3N4" )
				( pin "a"
					( attribute "PN" "1"
						( Origin gPackager )
					)
					( objectStatus "C3N4.1" )
				)
				( pin "b"
					( attribute "PN" "2"
						( Origin gPackager )
					)
					( objectStatus "C3N4.2" )
				)
			)
			( gate "@baseboard_fab2_lib.baseboard_fab2(sch_1):page132_i48"
				( attribute "BOM_COST" "SB"
					( Origin gFrontEnd )
				)
				( attribute "CDS_LIB" "dev_discrete"
					( Origin gPackager )
				)
				( attribute "CDS_LOCATION" "C3N5"
					( Origin gPackager )
				)
				( attribute "CDS_SEC" "1"
					( Origin gPackager )
				)
				( attribute "LOCATION" "C3N5"
					( Origin gFrontEnd )
				)
				( attribute "MATERIAL" "X6S"
					( Origin gFrontEnd )
				)
				( attribute "PACK_TYPE" "0402V"
					( Origin gFrontEnd )
				)
				( attribute "PART_NUMBER" "D97712-004"
					( Origin gFrontEnd )
				)
				( attribute "PHYS_PAGE" "132"
					( Origin gFrontEnd )
				)
				( attribute "ROOM" "SB_DECOUPLING"
					( Origin gFrontEnd )
				)
				( attribute "ROT" "0"
					( Origin gFrontEnd )
				)
				( attribute "SEC" "1"
					( Origin gPackager )
				)
				( attribute "TOLERANCE" "10%"
					( Origin gFrontEnd )
				)
				( attribute "VALUE" "1.0UF"
					( Origin gFrontEnd )
				)
				( attribute "VER" "1"
					( Origin gFrontEnd )
				)
				( attribute "VOLTAGE" "6.3V"
					( Units "uVoltage" "V" 1.000000)
					( Origin gFrontEnd )
				)
				( attribute "XY" "(-3400,4050)"
					( Origin gFrontEnd )
				)
				( attribute "CHIPS_PART_NAME" "CAP_A"
					( Origin gPackager )
				)
				( attribute "CDS_PART_NAME" "CAP_A_0402V-1.0UF,6.3V,10%,X6SA"
					( Origin gPackager )
				)
				( objectStatus "C3N5" )
				( pin "a"
					( attribute "PN" "1"
						( Origin gPackager )
					)
					( objectStatus "C3N5.1" )
				)
				( pin "b"
					( attribute "PN" "2"
						( Origin gPackager )
					)
					( objectStatus "C3N5.2" )
				)
			)
			( gate "@baseboard_fab2_lib.baseboard_fab2(sch_1):page132_i49"
				( attribute "BOM_COST" "SB"
					( Origin gFrontEnd )
				)
				( attribute "CDS_LIB" "dev_discrete"
					( Origin gPackager )
				)
				( attribute "CDS_LOCATION" "C3N15"
					( Origin gPackager )
				)
				( attribute "CDS_SEC" "1"
					( Origin gPackager )
				)
				( attribute "LOCATION" "C3N15"
					( Origin gFrontEnd )
				)
				( attribute "MATERIAL" "X6S"
					( Origin gFrontEnd )
				)
				( attribute "PACK_TYPE" "0402V"
					( Origin gFrontEnd )
				)
				( attribute "PART_NUMBER" "D97712-004"
					( Origin gFrontEnd )
				)
				( attribute "PHYS_PAGE" "132"
					( Origin gFrontEnd )
				)
				( attribute "ROOM" "SB_DECOUPLING"
					( Origin gFrontEnd )
				)
				( attribute "ROT" "0"
					( Origin gFrontEnd )
				)
				( attribute "SEC" "1"
					( Origin gPackager )
				)
				( attribute "TOLERANCE" "10%"
					( Origin gFrontEnd )
				)
				( attribute "VALUE" "1.0UF"
					( Origin gFrontEnd )
				)
				( attribute "VER" "1"
					( Origin gFrontEnd )
				)
				( attribute "VOLTAGE" "6.3V"
					( Units "uVoltage" "V" 1.000000)
					( Origin gFrontEnd )
				)
				( attribute "XY" "(-2975,3025)"
					( Origin gFrontEnd )
				)
				( attribute "CHIPS_PART_NAME" "CAP_A"
					( Origin gPackager )
				)
				( attribute "CDS_PART_NAME" "CAP_A_0402V-1.0UF,6.3V,10%,X6SA"
					( Origin gPackager )
				)
				( objectStatus "C3N15" )
				( pin "a"
					( attribute "PN" "1"
						( Origin gPackager )
					)
					( objectStatus "C3N15.1" )
				)
				( pin "b"
					( attribute "PN" "2"
						( Origin gPackager )
					)
					( objectStatus "C3N15.2" )
				)
			)
			( gate "@baseboard_fab2_lib.baseboard_fab2(sch_1):page132_i51"
				( attribute "BOM_COST" "SB"
					( Origin gFrontEnd )
				)
				( attribute "CDS_LIB" "dev_discrete"
					( Origin gPackager )
				)
				( attribute "CDS_LOCATION" "C3N20"
					( Origin gPackager )
				)
				( attribute "CDS_SEC" "1"
					( Origin gPackager )
				)
				( attribute "LOCATION" "C3N20"
					( Origin gFrontEnd )
				)
				( attribute "MATERIAL" "X6S"
					( Origin gFrontEnd )
				)
				( attribute "PACK_TYPE" "0402V"
					( Origin gFrontEnd )
				)
				( attribute "PART_NUMBER" "D97712-004"
					( Origin gFrontEnd )
				)
				( attribute "PHYS_PAGE" "132"
					( Origin gFrontEnd )
				)
				( attribute "ROOM" "SB_DECOUPLING"
					( Origin gFrontEnd )
				)
				( attribute "ROT" "0"
					( Origin gFrontEnd )
				)
				( attribute "SEC" "1"
					( Origin gPackager )
				)
				( attribute "TOLERANCE" "10%"
					( Origin gFrontEnd )
				)
				( attribute "VALUE" "1.0UF"
					( Origin gFrontEnd )
				)
				( attribute "VER" "1"
					( Origin gFrontEnd )
				)
				( attribute "VOLTAGE" "6.3V"
					( Units "uVoltage" "V" 1.000000)
					( Origin gFrontEnd )
				)
				( attribute "XY" "(-3375,3025)"
					( Origin gFrontEnd )
				)
				( attribute "CHIPS_PART_NAME" "CAP_A"
					( Origin gPackager )
				)
				( attribute "CDS_PART_NAME" "CAP_A_0402V-1.0UF,6.3V,10%,X6SA"
					( Origin gPackager )
				)
				( objectStatus "C3N20" )
				( pin "a"
					( attribute "PN" "1"
						( Origin gPackager )
					)
					( objectStatus "C3N20.1" )
				)
				( pin "b"
					( attribute "PN" "2"
						( Origin gPackager )
					)
					( objectStatus "C3N20.2" )
				)
			)
			( gate "@baseboard_fab2_lib.baseboard_fab2(sch_1):page132_i52"
				( attribute "BOM_COST" "SB"
					( Origin gFrontEnd )
				)
				( attribute "CDS_LIB" "dev_discrete"
					( Origin gPackager )
				)
				( attribute "CDS_LOCATION" "C3L23"
					( Origin gPackager )
				)
				( attribute "CDS_SEC" "1"
					( Origin gPackager )
				)
				( attribute "LOCATION" "C3L23"
					( Origin gFrontEnd )
				)
				( attribute "MATERIAL" "X6S"
					( Origin gFrontEnd )
				)
				( attribute "PACK_TYPE" "0603V"
					( Origin gFrontEnd )
				)
				( attribute "PART_NUMBER" "E15431-004"
					( Origin gFrontEnd )
				)
				( attribute "PHYS_PAGE" "132"
					( Origin gFrontEnd )
				)
				( attribute "ROOM" "SB_DECOUPLING"
					( Origin gFrontEnd )
				)
				( attribute "ROT" "0"
					( Origin gFrontEnd )
				)
				( attribute "SEC" "1"
					( Origin gPackager )
				)
				( attribute "TOLERANCE" "20%"
					( Origin gFrontEnd )
				)
				( attribute "VALUE" "22.0UF"
					( Origin gFrontEnd )
				)
				( attribute "VER" "1"
					( Origin gFrontEnd )
				)
				( attribute "VOLTAGE" "4V"
					( Units "uVoltage" "V" 1.000000)
					( Origin gFrontEnd )
				)
				( attribute "XY" "(-2550,1925)"
					( Origin gFrontEnd )
				)
				( attribute "CHIPS_PART_NAME" "CAP_A"
					( Origin gPackager )
				)
				( attribute "CDS_PART_NAME" "CAP_A_0603V-22.0UF,4V,20%,X6S,A"
					( Origin gPackager )
				)
				( objectStatus "C3L23" )
				( pin "a"
					( attribute "PN" "1"
						( Origin gPackager )
					)
					( objectStatus "C3L23.1" )
				)
				( pin "b"
					( attribute "PN" "2"
						( Origin gPackager )
					)
					( objectStatus "C3L23.2" )
				)
			)
			( gate "@baseboard_fab2_lib.baseboard_fab2(sch_1):page132_i54"
				( attribute "BOM_COST" "SB"
					( Origin gFrontEnd )
				)
				( attribute "CDS_LIB" "dev_discrete"
					( Origin gPackager )
				)
				( attribute "CDS_LOCATION" "C3L22"
					( Origin gPackager )
				)
				( attribute "CDS_SEC" "1"
					( Origin gPackager )
				)
				( attribute "LOCATION" "C3L22"
					( Origin gFrontEnd )
				)
				( attribute "MATERIAL" "X6S"
					( Origin gFrontEnd )
				)
				( attribute "PACK_TYPE" "0603V"
					( Origin gFrontEnd )
				)
				( attribute "PART_NUMBER" "E15431-004"
					( Origin gFrontEnd )
				)
				( attribute "PHYS_PAGE" "132"
					( Origin gFrontEnd )
				)
				( attribute "ROOM" "SB_DECOUPLING"
					( Origin gFrontEnd )
				)
				( attribute "ROT" "0"
					( Origin gFrontEnd )
				)
				( attribute "SEC" "1"
					( Origin gPackager )
				)
				( attribute "TOLERANCE" "20%"
					( Origin gFrontEnd )
				)
				( attribute "VALUE" "22.0UF"
					( Origin gFrontEnd )
				)
				( attribute "VER" "1"
					( Origin gFrontEnd )
				)
				( attribute "VOLTAGE" "4V"
					( Units "uVoltage" "V" 1.000000)
					( Origin gFrontEnd )
				)
				( attribute "XY" "(-2950,1925)"
					( Origin gFrontEnd )
				)
				( attribute "CHIPS_PART_NAME" "CAP_A"
					( Origin gPackager )
				)
				( attribute "CDS_PART_NAME" "CAP_A_0603V-22.0UF,4V,20%,X6S,A"
					( Origin gPackager )
				)
				( objectStatus "C3L22" )
				( pin "a"
					( attribute "PN" "1"
						( Origin gPackager )
					)
					( objectStatus "C3L22.1" )
				)
				( pin "b"
					( attribute "PN" "2"
						( Origin gPackager )
					)
					( objectStatus "C3L22.2" )
				)
			)
			( gate "@baseboard_fab2_lib.baseboard_fab2(sch_1):page132_i56"
				( attribute "BOM_COST" "SB"
					( Origin gFrontEnd )
				)
				( attribute "CDS_LIB" "dev_discrete"
					( Origin gPackager )
				)
				( attribute "CDS_LOCATION" "C3L24"
					( Origin gPackager )
				)
				( attribute "CDS_SEC" "1"
					( Origin gPackager )
				)
				( attribute "LOCATION" "C3L24"
					( Origin gFrontEnd )
				)
				( attribute "MATERIAL" "X6S"
					( Origin gFrontEnd )
				)
				( attribute "PACK_TYPE" "0603V"
					( Origin gFrontEnd )
				)
				( attribute "PART_NUMBER" "E15431-004"
					( Origin gFrontEnd )
				)
				( attribute "PHYS_PAGE" "132"
					( Origin gFrontEnd )
				)
				( attribute "ROOM" "SB_DECOUPLING"
					( Origin gFrontEnd )
				)
				( attribute "ROT" "0"
					( Origin gFrontEnd )
				)
				( attribute "SEC" "1"
					( Origin gPackager )
				)
				( attribute "TOLERANCE" "20%"
					( Origin gFrontEnd )
				)
				( attribute "VALUE" "22.0UF"
					( Origin gFrontEnd )
				)
				( attribute "VER" "1"
					( Origin gFrontEnd )
				)
				( attribute "VOLTAGE" "4V"
					( Units "uVoltage" "V" 1.000000)
					( Origin gFrontEnd )
				)
				( attribute "XY" "(-3425,1925)"
					( Origin gFrontEnd )
				)
				( attribute "CHIPS_PART_NAME" "CAP_A"
					( Origin gPackager )
				)
				( attribute "CDS_PART_NAME" "CAP_A_0603V-22.0UF,4V,20%,X6S,A"
					( Origin gPackager )
				)
				( objectStatus "C3L24" )
				( pin "a"
					( attribute "PN" "1"
						( Origin gPackager )
					)
					( objectStatus "C3L24.1" )
				)
				( pin "b"
					( attribute "PN" "2"
						( Origin gPackager )
					)
					( objectStatus "C3L24.2" )
				)
			)
			( gate "@baseboard_fab2_lib.baseboard_fab2(sch_1):page133_i120"
				( attribute "BOM_COST" "SB"
					( Origin gFrontEnd )
				)
				( attribute "CDS_LIB" "mstr_discrete"
					( Origin gPackager )
				)
				( attribute "CDS_LOCATION" "R3N3"
					( Origin gPackager )
				)
				( attribute "CDS_SEC" "1"
					( Origin gPackager )
				)
				( attribute "LOCATION" "R3N3"
					( Origin gFrontEnd )
				)
				( attribute "MATERIAL" "CHIP"
					( Origin gFrontEnd )
				)
				( attribute "PACK_TYPE" "0402"
					( Origin gFrontEnd )
				)
				( attribute "PART_NUMBER" "G21796-001"
					( Origin gFrontEnd )
				)
				( attribute "PHYS_PAGE" "133"
					( Origin gFrontEnd )
				)
				( attribute "ROOM" "SB"
					( Origin gFrontEnd )
				)
				( attribute "ROT" "0"
					( Origin gFrontEnd )
				)
				( attribute "SEC" "1"
					( Origin gPackager )
				)
				( attribute "TOLERANCE" "1%"
					( Origin gFrontEnd )
				)
				( attribute "VALUE" "2.0K"
					( Origin gFrontEnd )
				)
				( attribute "VER" "1"
					( Origin gFrontEnd )
				)
				( attribute "WATTAGE" "1/16W"
					( Origin gFrontEnd )
				)
				( attribute "XY" "(-2500,3850)"
					( Origin gFrontEnd )
				)
				( attribute "CHIPS_PART_NAME" "RES"
					( Origin gPackager )
				)
				( attribute "CDS_PART_NAME" "RES_0402-2.0K,1%,1/16W,CHIP,G2A"
					( Origin gPackager )
				)
				( objectStatus "R3N3" )
				( pin "a"
					( attribute "PN" "1"
						( Origin gPackager )
					)
					( objectStatus "R3N3.1" )
				)
				( pin "b"
					( attribute "PN" "2"
						( Origin gPackager )
					)
					( objectStatus "R3N3.2" )
				)
			)
			( gate "@baseboard_fab2_lib.baseboard_fab2(sch_1):page133_i122"
				( attribute "BOM_COST" "SB"
					( Origin gFrontEnd )
				)
				( attribute "CDS_LIB" "mstr_discrete"
					( Origin gPackager )
				)
				( attribute "CDS_LOCATION" "R2N12"
					( Origin gPackager )
				)
				( attribute "CDS_SEC" "1"
					( Origin gPackager )
				)
				( attribute "LOCATION" "R2N12"
					( Origin gFrontEnd )
				)
				( attribute "MATERIAL" "EMPTY"
					( Origin gFrontEnd )
				)
				( attribute "PACK_TYPE" "0402"
					( Origin gFrontEnd )
				)
				( attribute "PART_NUMBER" "G21796-016"
					( Origin gFrontEnd )
				)
				( attribute "PHYS_PAGE" "133"
					( Origin gFrontEnd )
				)
				( attribute "ROOM" "SB"
					( Origin gFrontEnd )
				)
				( attribute "ROT" "0"
					( Origin gFrontEnd )
				)
				( attribute "SEC" "1"
					( Origin gPackager )
				)
				( attribute "TOLERANCE" "1%"
					( Origin gFrontEnd )
				)
				( attribute "VALUE" "10.0K"
					( Origin gFrontEnd )
				)
				( attribute "VER" "1"
					( Origin gFrontEnd )
				)
				( attribute "WATTAGE" "1/16W"
					( Origin gFrontEnd )
				)
				( attribute "XY" "(-2500,4075)"
					( Origin gFrontEnd )
				)
				( attribute "CHIPS_PART_NAME" "RES"
					( Origin gPackager )
				)
				( attribute "CDS_PART_NAME" "RES_0402-10.0K,1%,1/16W,EMPTY,A"
					( Origin gPackager )
				)
				( objectStatus "R2N12" )
				( pin "a"
					( attribute "PN" "1"
						( Origin gPackager )
					)
					( objectStatus "R2N12.1" )
				)
				( pin "b"
					( attribute "PN" "2"
						( Origin gPackager )
					)
					( objectStatus "R2N12.2" )
				)
			)
			( gate "@baseboard_fab2_lib.baseboard_fab2(sch_1):page133_i200"
				( attribute "CDS_LIB" "mstr_discrete"
					( Origin gPackager )
				)
				( attribute "CDS_LOCATION" "R7D8"
					( Origin gPackager )
				)
				( attribute "CDS_SEC" "1"
					( Origin gPackager )
				)
				( attribute "LOCATION" "R7D8"
					( Origin gFrontEnd )
				)
				( attribute "MATERIAL" "CHIP"
					( Origin gFrontEnd )
				)
				( attribute "PACK_TYPE" "0402"
					( Origin gFrontEnd )
				)
				( attribute "PART_NUMBER" "G21796-016"
					( Origin gFrontEnd )
				)
				( attribute "PHYS_PAGE" "133"
					( Origin gFrontEnd )
				)
				( attribute "ROOM" "SB"
					( Origin gFrontEnd )
				)
				( attribute "ROT" "0"
					( Origin gFrontEnd )
				)
				( attribute "SEC" "1"
					( Origin gFrontEnd )
				)
				( attribute "SEC_TYPE" "0402"
					( Origin gFrontEnd )
				)
				( attribute "TOLERANCE" "1%"
					( Origin gFrontEnd )
				)
				( attribute "VALUE" "10.0K"
					( Origin gFrontEnd )
				)
				( attribute "VER" "1"
					( Origin gFrontEnd )
				)
				( attribute "WATTAGE" "1/16W"
					( Origin gFrontEnd )
				)
				( attribute "XY" "(-4700,4500)"
					( Origin gFrontEnd )
				)
				( attribute "CHIPS_PART_NAME" "RES"
					( Origin gPackager )
				)
				( attribute "CDS_PART_NAME" "RES_0402-10.0K,1%,1/16W,CHIP,GA"
					( Origin gPackager )
				)
				( objectStatus "R7D8" )
				( pin "a"
					( attribute "PN" "1"
						( Origin gPackager )
					)
					( objectStatus "R7D8.1" )
				)
				( pin "b"
					( attribute "PN" "2"
						( Origin gPackager )
					)
					( objectStatus "R7D8.2" )
				)
			)
			( gate "@baseboard_fab2_lib.baseboard_fab2(sch_1):page133_i202"
				( attribute "CDS_LIB" "mstr_discrete"
					( Origin gPackager )
				)
				( attribute "CDS_LOCATION" "R7D10"
					( Origin gPackager )
				)
				( attribute "CDS_SEC" "1"
					( Origin gPackager )
				)
				( attribute "LOCATION" "R7D10"
					( Origin gFrontEnd )
				)
				( attribute "MATERIAL" "CHIP"
					( Origin gFrontEnd )
				)
				( attribute "PACK_TYPE" "0402"
					( Origin gFrontEnd )
				)
				( attribute "PART_NUMBER" "G21796-016"
					( Origin gFrontEnd )
				)
				( attribute "PHYS_PAGE" "133"
					( Origin gFrontEnd )
				)
				( attribute "ROOM" "SB"
					( Origin gFrontEnd )
				)
				( attribute "ROT" "0"
					( Origin gFrontEnd )
				)
				( attribute "SEC" "1"
					( Origin gFrontEnd )
				)
				( attribute "SEC_TYPE" "0402"
					( Origin gFrontEnd )
				)
				( attribute "TOLERANCE" "1%"
					( Origin gFrontEnd )
				)
				( attribute "VALUE" "10.0K"
					( Origin gFrontEnd )
				)
				( attribute "VER" "1"
					( Origin gFrontEnd )
				)
				( attribute "WATTAGE" "1/16W"
					( Origin gFrontEnd )
				)
				( attribute "XY" "(-4700,4325)"
					( Origin gFrontEnd )
				)
				( attribute "CHIPS_PART_NAME" "RES"
					( Origin gPackager )
				)
				( attribute "CDS_PART_NAME" "RES_0402-10.0K,1%,1/16W,CHIP,GA"
					( Origin gPackager )
				)
				( objectStatus "R7D10" )
				( pin "a"
					( attribute "PN" "1"
						( Origin gPackager )
					)
					( objectStatus "R7D10.1" )
				)
				( pin "b"
					( attribute "PN" "2"
						( Origin gPackager )
					)
					( objectStatus "R7D10.2" )
				)
			)
			( gate "@baseboard_fab2_lib.baseboard_fab2(sch_1):page133_i237"
				( attribute "CDS_LIB" "mstr_discrete"
					( Origin gPackager )
				)
				( attribute "CDS_LOCATION" "R7D12"
					( Origin gPackager )
				)
				( attribute "CDS_SEC" "1"
					( Origin gPackager )
				)
				( attribute "LOCATION" "R7D12"
					( Origin gFrontEnd )
				)
				( attribute "MATERIAL" "CHIP"
					( Origin gFrontEnd )
				)
				( attribute "PACK_TYPE" "0402"
					( Origin gFrontEnd )
				)
				( attribute "PART_NUMBER" "G21796-016"
					( Origin gFrontEnd )
				)
				( attribute "PHYS_PAGE" "133"
					( Origin gFrontEnd )
				)
				( attribute "ROOM" "SB"
					( Origin gFrontEnd )
				)
				( attribute "ROT" "0"
					( Origin gFrontEnd )
				)
				( attribute "SEC" "1"
					( Origin gFrontEnd )
				)
				( attribute "SEC_TYPE" "0402"
					( Origin gFrontEnd )
				)
				( attribute "TOLERANCE" "1%"
					( Origin gFrontEnd )
				)
				( attribute "VALUE" "10.0K"
					( Origin gFrontEnd )
				)
				( attribute "VER" "1"
					( Origin gFrontEnd )
				)
				( attribute "WATTAGE" "1/16W"
					( Origin gFrontEnd )
				)
				( attribute "XY" "(-4700,3925)"
					( Origin gFrontEnd )
				)
				( attribute "CHIPS_PART_NAME" "RES"
					( Origin gPackager )
				)
				( attribute "CDS_PART_NAME" "RES_0402-10.0K,1%,1/16W,CHIP,GA"
					( Origin gPackager )
				)
				( objectStatus "R7D12" )
				( pin "a"
					( attribute "PN" "1"
						( Origin gPackager )
					)
					( objectStatus "R7D12.1" )
				)
				( pin "b"
					( attribute "PN" "2"
						( Origin gPackager )
					)
					( objectStatus "R7D12.2" )
				)
			)
			( gate "@baseboard_fab2_lib.baseboard_fab2(sch_1):page133_i243"
				( attribute "CDS_LIB" "mstr_discrete"
					( Origin gPackager )
				)
				( attribute "CDS_LOCATION" "R7D3"
					( Origin gPackager )
				)
				( attribute "CDS_SEC" "1"
					( Origin gPackager )
				)
				( attribute "LOCATION" "R7D3"
					( Origin gFrontEnd )
				)
				( attribute "MATERIAL" "CHIP"
					( Origin gFrontEnd )
				)
				( attribute "PACK_TYPE" "0402"
					( Origin gFrontEnd )
				)
				( attribute "PART_NUMBER" "G21796-072"
					( Origin gFrontEnd )
				)
				( attribute "PHYS_PAGE" "133"
					( Origin gFrontEnd )
				)
				( attribute "ROOM" "SB"
					( Origin gFrontEnd )
				)
				( attribute "ROT" "0"
					( Origin gFrontEnd )
				)
				( attribute "SEC" "1"
					( Origin gFrontEnd )
				)
				( attribute "SEC_TYPE" "0402"
					( Origin gFrontEnd )
				)
				( attribute "TOLERANCE" "1%"
					( Origin gFrontEnd )
				)
				( attribute "VALUE" "4.75K"
					( Origin gFrontEnd )
				)
				( attribute "VER" "1"
					( Origin gFrontEnd )
				)
				( attribute "WATTAGE" "1/16W"
					( Origin gFrontEnd )
				)
				( attribute "XY" "(-4700,4900)"
					( Origin gFrontEnd )
				)
				( attribute "CHIPS_PART_NAME" "RES"
					( Origin gPackager )
				)
				( attribute "CDS_PART_NAME" "RES_0402-4.75K,1%,1/16W,CHIP,GA"
					( Origin gPackager )
				)
				( objectStatus "R7D3" )
				( pin "a"
					( attribute "PN" "1"
						( Origin gPackager )
					)
					( objectStatus "R7D3.1" )
				)
				( pin "b"
					( attribute "PN" "2"
						( Origin gPackager )
					)
					( objectStatus "R7D3.2" )
				)
			)
			( gate "@baseboard_fab2_lib.baseboard_fab2(sch_1):page133_i245"
				( attribute "CDS_LIB" "mstr_discrete"
					( Origin gPackager )
				)
				( attribute "CDS_LOCATION" "R7D4"
					( Origin gPackager )
				)
				( attribute "CDS_SEC" "1"
					( Origin gPackager )
				)
				( attribute "LOCATION" "R7D4"
					( Origin gFrontEnd )
				)
				( attribute "MATERIAL" "CHIP"
					( Origin gFrontEnd )
				)
				( attribute "PACK_TYPE" "0402"
					( Origin gFrontEnd )
				)
				( attribute "PART_NUMBER" "G21796-016"
					( Origin gFrontEnd )
				)
				( attribute "PHYS_PAGE" "133"
					( Origin gFrontEnd )
				)
				( attribute "ROOM" "SB"
					( Origin gFrontEnd )
				)
				( attribute "ROT" "0"
					( Origin gFrontEnd )
				)
				( attribute "SEC" "1"
					( Origin gFrontEnd )
				)
				( attribute "SEC_TYPE" "0402"
					( Origin gFrontEnd )
				)
				( attribute "TOLERANCE" "1%"
					( Origin gFrontEnd )
				)
				( attribute "VALUE" "10.0K"
					( Origin gFrontEnd )
				)
				( attribute "VER" "1"
					( Origin gFrontEnd )
				)
				( attribute "WATTAGE" "1/16W"
					( Origin gFrontEnd )
				)
				( attribute "XY" "(-4700,4125)"
					( Origin gFrontEnd )
				)
				( attribute "CHIPS_PART_NAME" "RES"
					( Origin gPackager )
				)
				( attribute "CDS_PART_NAME" "RES_0402-10.0K,1%,1/16W,CHIP,GA"
					( Origin gPackager )
				)
				( objectStatus "R7D4" )
				( pin "a"
					( attribute "PN" "1"
						( Origin gPackager )
					)
					( objectStatus "R7D4.1" )
				)
				( pin "b"
					( attribute "PN" "2"
						( Origin gPackager )
					)
					( objectStatus "R7D4.2" )
				)
			)
			( gate "@baseboard_fab2_lib.baseboard_fab2(sch_1):page133_i247"
				( attribute "BOM_COST" "SB"
					( Origin gFrontEnd )
				)
				( attribute "CDS_LIB" "mstr_discrete"
					( Origin gPackager )
				)
				( attribute "CDS_LOCATION" "R2N16"
					( Origin gPackager )
				)
				( attribute "CDS_SEC" "1"
					( Origin gPackager )
				)
				( attribute "LOCATION" "R2N16"
					( Origin gFrontEnd )
				)
				( attribute "MATERIAL" "CHIP"
					( Origin gFrontEnd )
				)
				( attribute "PACK_TYPE" "0402"
					( Origin gFrontEnd )
				)
				( attribute "PART_NUMBER" "G21796-016"
					( Origin gFrontEnd )
				)
				( attribute "PHYS_PAGE" "133"
					( Origin gFrontEnd )
				)
				( attribute "ROOM" "SB"
					( Origin gFrontEnd )
				)
				( attribute "ROT" "0"
					( Origin gFrontEnd )
				)
				( attribute "SEC" "1"
					( Origin gPackager )
				)
				( attribute "TOLERANCE" "1%"
					( Origin gFrontEnd )
				)
				( attribute "VALUE" "10.0K"
					( Origin gFrontEnd )
				)
				( attribute "VER" "1"
					( Origin gFrontEnd )
				)
				( attribute "WATTAGE" "1/16W"
					( Origin gFrontEnd )
				)
				( attribute "XY" "(-4650,2725)"
					( Origin gFrontEnd )
				)
				( attribute "CHIPS_PART_NAME" "RES"
					( Origin gPackager )
				)
				( attribute "CDS_PART_NAME" "RES_0402-10.0K,1%,1/16W,CHIP,GA"
					( Origin gPackager )
				)
				( objectStatus "R2N16" )
				( pin "a"
					( attribute "PN" "1"
						( Origin gPackager )
					)
					( objectStatus "R2N16.1" )
				)
				( pin "b"
					( attribute "PN" "2"
						( Origin gPackager )
					)
					( objectStatus "R2N16.2" )
				)
			)
			( gate "@baseboard_fab2_lib.baseboard_fab2(sch_1):page133_i258"
				( attribute "BOM_COST" "SB"
					( Origin gFrontEnd )
				)
				( attribute "CDS_LIB" "mstr_discrete"
					( Origin gPackager )
				)
				( attribute "CDS_LOCATION" "R2R5"
					( Origin gPackager )
				)
				( attribute "CDS_SEC" "1"
					( Origin gPackager )
				)
				( attribute "LOCATION" "R2R5"
					( Origin gFrontEnd )
				)
				( attribute "MATERIAL" "CHIP"
					( Origin gFrontEnd )
				)
				( attribute "PACK_TYPE" "0402"
					( Origin gFrontEnd )
				)
				( attribute "PART_NUMBER" "G21796-026"
					( Origin gFrontEnd )
				)
				( attribute "PHYS_PAGE" "133"
					( Origin gFrontEnd )
				)
				( attribute "ROOM" "SB"
					( Origin gFrontEnd )
				)
				( attribute "ROT" "0"
					( Origin gFrontEnd )
				)
				( attribute "SEC" "1"
					( Origin gFrontEnd )
				)
				( attribute "SEC_TYPE" "0402"
					( Origin gFrontEnd )
				)
				( attribute "TOLERANCE" "1%"
					( Origin gFrontEnd )
				)
				( attribute "VALUE" "1.00K"
					( Origin gFrontEnd )
				)
				( attribute "VER" "1"
					( Origin gFrontEnd )
				)
				( attribute "WATTAGE" "1/16W"
					( Origin gFrontEnd )
				)
				( attribute "XY" "(-2600,5125)"
					( Origin gFrontEnd )
				)
				( attribute "CHIPS_PART_NAME" "RES"
					( Origin gPackager )
				)
				( attribute "CDS_PART_NAME" "RES_0402-1.00K,1%,1/16W,CHIP,GA"
					( Origin gPackager )
				)
				( objectStatus "R2R5" )
				( pin "a"
					( attribute "PN" "1"
						( Origin gPackager )
					)
					( objectStatus "R2R5.1" )
				)
				( pin "b"
					( attribute "PN" "2"
						( Origin gPackager )
					)
					( objectStatus "R2R5.2" )
				)
			)
			( gate "@baseboard_fab2_lib.baseboard_fab2(sch_1):page133_i267"
				( attribute "CDS_LIB" "mstr_discrete"
					( Origin gPackager )
				)
				( attribute "CDS_LOCATION" "R2N9"
					( Origin gPackager )
				)
				( attribute "CDS_SEC" "1"
					( Origin gPackager )
				)
				( attribute "LOCATION" "R2N9"
					( Origin gFrontEnd )
				)
				( attribute "MATERIAL" "CHIP"
					( Origin gFrontEnd )
				)
				( attribute "PACK_TYPE" "0402"
					( Origin gFrontEnd )
				)
				( attribute "PART_NUMBER" "G21796-016"
					( Origin gFrontEnd )
				)
				( attribute "PHYS_PAGE" "133"
					( Origin gFrontEnd )
				)
				( attribute "ROOM" "SB"
					( Origin gFrontEnd )
				)
				( attribute "ROT" "0"
					( Origin gFrontEnd )
				)
				( attribute "SEC" "1"
					( Origin gFrontEnd )
				)
				( attribute "SEC_TYPE" "0402"
					( Origin gFrontEnd )
				)
				( attribute "TOLERANCE" "1%"
					( Origin gFrontEnd )
				)
				( attribute "VALUE" "10.0K"
					( Origin gFrontEnd )
				)
				( attribute "VER" "1"
					( Origin gFrontEnd )
				)
				( attribute "WATTAGE" "1/16W"
					( Origin gFrontEnd )
				)
				( attribute "XY" "(-2475,1275)"
					( Origin gFrontEnd )
				)
				( attribute "CHIPS_PART_NAME" "RES"
					( Origin gPackager )
				)
				( attribute "CDS_PART_NAME" "RES_0402-10.0K,1%,1/16W,CHIP,GA"
					( Origin gPackager )
				)
				( objectStatus "R2N9" )
				( pin "a"
					( attribute "PN" "1"
						( Origin gPackager )
					)
					( objectStatus "R2N9.1" )
				)
				( pin "b"
					( attribute "PN" "2"
						( Origin gPackager )
					)
					( objectStatus "R2N9.2" )
				)
			)
			( gate "@baseboard_fab2_lib.baseboard_fab2(sch_1):page133_i280"
				( attribute "BOM_COST" "SB"
					( Origin gFrontEnd )
				)
				( attribute "CDS_LIB" "mstr_discrete"
					( Origin gPackager )
				)
				( attribute "CDS_LOCATION" "R8B23"
					( Origin gPackager )
				)
				( attribute "CDS_SEC" "1"
					( Origin gPackager )
				)
				( attribute "LOCATION" "R8B23"
					( Origin gFrontEnd )
				)
				( attribute "MATERIAL" "CHIP"
					( Origin gFrontEnd )
				)
				( attribute "PACK_TYPE" "0402"
					( Origin gFrontEnd )
				)
				( attribute "PART_NUMBER" "G21796-026"
					( Origin gFrontEnd )
				)
				( attribute "PHYS_PAGE" "133"
					( Origin gFrontEnd )
				)
				( attribute "ROOM" "SB"
					( Origin gFrontEnd )
				)
				( attribute "ROT" "0"
					( Origin gFrontEnd )
				)
				( attribute "SEC" "1"
					( Origin gFrontEnd )
				)
				( attribute "SEC_TYPE" "0402"
					( Origin gFrontEnd )
				)
				( attribute "TOLERANCE" "1%"
					( Origin gFrontEnd )
				)
				( attribute "VALUE" "1.00K"
					( Origin gFrontEnd )
				)
				( attribute "VER" "1"
					( Origin gFrontEnd )
				)
				( attribute "WATTAGE" "1/16W"
					( Origin gFrontEnd )
				)
				( attribute "XY" "(-2575,4675)"
					( Origin gFrontEnd )
				)
				( attribute "CHIPS_PART_NAME" "RES"
					( Origin gPackager )
				)
				( attribute "CDS_PART_NAME" "RES_0402-1.00K,1%,1/16W,CHIP,GA"
					( Origin gPackager )
				)
				( objectStatus "R8B23" )
				( pin "a"
					( attribute "PN" "1"
						( Origin gPackager )
					)
					( objectStatus "R8B23.1" )
				)
				( pin "b"
					( attribute "PN" "2"
						( Origin gPackager )
					)
					( objectStatus "R8B23.2" )
				)
			)
			( gate "@baseboard_fab2_lib.baseboard_fab2(sch_1):page133_i282"
				( attribute "BOM_COST" "SB"
					( Origin gFrontEnd )
				)
				( attribute "CDS_LIB" "mstr_discrete"
					( Origin gPackager )
				)
				( attribute "CDS_LOCATION" "R8B30"
					( Origin gPackager )
				)
				( attribute "CDS_SEC" "1"
					( Origin gPackager )
				)
				( attribute "LOCATION" "R8B30"
					( Origin gFrontEnd )
				)
				( attribute "MATERIAL" "CHIP"
					( Origin gFrontEnd )
				)
				( attribute "PACK_TYPE" "0402"
					( Origin gFrontEnd )
				)
				( attribute "PART_NUMBER" "G21796-026"
					( Origin gFrontEnd )
				)
				( attribute "PHYS_PAGE" "133"
					( Origin gFrontEnd )
				)
				( attribute "ROOM" "SB"
					( Origin gFrontEnd )
				)
				( attribute "ROT" "0"
					( Origin gFrontEnd )
				)
				( attribute "SEC" "1"
					( Origin gFrontEnd )
				)
				( attribute "SEC_TYPE" "0402"
					( Origin gFrontEnd )
				)
				( attribute "TOLERANCE" "1%"
					( Origin gFrontEnd )
				)
				( attribute "VALUE" "1.00K"
					( Origin gFrontEnd )
				)
				( attribute "VER" "1"
					( Origin gFrontEnd )
				)
				( attribute "WATTAGE" "1/16W"
					( Origin gFrontEnd )
				)
				( attribute "XY" "(-2575,4425)"
					( Origin gFrontEnd )
				)
				( attribute "CHIPS_PART_NAME" "RES"
					( Origin gPackager )
				)
				( attribute "CDS_PART_NAME" "RES_0402-1.00K,1%,1/16W,CHIP,GA"
					( Origin gPackager )
				)
				( objectStatus "R8B30" )
				( pin "a"
					( attribute "PN" "1"
						( Origin gPackager )
					)
					( objectStatus "R8B30.1" )
				)
				( pin "b"
					( attribute "PN" "2"
						( Origin gPackager )
					)
					( objectStatus "R8B30.2" )
				)
			)
			( gate "@baseboard_fab2_lib.baseboard_fab2(sch_1):page133_i284"
				( attribute "BOM_COST" "SB"
					( Origin gFrontEnd )
				)
				( attribute "CDS_LIB" "mstr_discrete"
					( Origin gPackager )
				)
				( attribute "CDS_LOCATION" "R2M4"
					( Origin gPackager )
				)
				( attribute "CDS_SEC" "1"
					( Origin gPackager )
				)
				( attribute "LOCATION" "R2M4"
					( Origin gFrontEnd )
				)
				( attribute "MATERIAL" "CHIP"
					( Origin gFrontEnd )
				)
				( attribute "PACK_TYPE" "0402"
					( Origin gFrontEnd )
				)
				( attribute "PART_NUMBER" "G21796-026"
					( Origin gFrontEnd )
				)
				( attribute "PHYS_PAGE" "133"
					( Origin gFrontEnd )
				)
				( attribute "ROOM" "SB"
					( Origin gFrontEnd )
				)
				( attribute "ROT" "0"
					( Origin gFrontEnd )
				)
				( attribute "SEC" "1"
					( Origin gFrontEnd )
				)
				( attribute "SEC_TYPE" "0402"
					( Origin gFrontEnd )
				)
				( attribute "TOLERANCE" "1%"
					( Origin gFrontEnd )
				)
				( attribute "VALUE" "1.00K"
					( Origin gFrontEnd )
				)
				( attribute "VER" "1"
					( Origin gFrontEnd )
				)
				( attribute "WATTAGE" "1/16W"
					( Origin gFrontEnd )
				)
				( attribute "XY" "(-2600,4900)"
					( Origin gFrontEnd )
				)
				( attribute "CHIPS_PART_NAME" "RES"
					( Origin gPackager )
				)
				( attribute "CDS_PART_NAME" "RES_0402-1.00K,1%,1/16W,CHIP,GA"
					( Origin gPackager )
				)
				( objectStatus "R2M4" )
				( pin "a"
					( attribute "PN" "1"
						( Origin gPackager )
					)
					( objectStatus "R2M4.1" )
				)
				( pin "b"
					( attribute "PN" "2"
						( Origin gPackager )
					)
					( objectStatus "R2M4.2" )
				)
			)
			( gate "@baseboard_fab2_lib.baseboard_fab2(sch_1):page133_i286"
				( attribute "BOM_COST" "SB_PU_PD"
					( Origin gFrontEnd )
				)
				( attribute "CDS_LIB" "mstr_discrete"
					( Origin gPackager )
				)
				( attribute "CDS_LOCATION" "R8C4"
					( Origin gPackager )
				)
				( attribute "CDS_SEC" "1"
					( Origin gPackager )
				)
				( attribute "LOCATION" "R8C4"
					( Origin gFrontEnd )
				)
				( attribute "MATERIAL" "CHIP"
					( Origin gFrontEnd )
				)
				( attribute "PACK_TYPE" "0402"
					( Origin gFrontEnd )
				)
				( attribute "PART_NUMBER" "G21796-026"
					( Origin gFrontEnd )
				)
				( attribute "PHYS_PAGE" "133"
					( Origin gFrontEnd )
				)
				( attribute "ROOM" "SB"
					( Origin gFrontEnd )
				)
				( attribute "ROT" "0"
					( Origin gFrontEnd )
				)
				( attribute "SEC" "1"
					( Origin gFrontEnd )
				)
				( attribute "SEC_TYPE" "0402"
					( Origin gFrontEnd )
				)
				( attribute "TOLERANCE" "1%"
					( Origin gFrontEnd )
				)
				( attribute "VALUE" "1.00K"
					( Origin gFrontEnd )
				)
				( attribute "VER" "1"
					( Origin gFrontEnd )
				)
				( attribute "WATTAGE" "1/16W"
					( Origin gFrontEnd )
				)
				( attribute "XY" "(-4800,950)"
					( Origin gFrontEnd )
				)
				( attribute "CHIPS_PART_NAME" "RES"
					( Origin gPackager )
				)
				( attribute "CDS_PART_NAME" "RES_0402-1.00K,1%,1/16W,CHIP,GA"
					( Origin gPackager )
				)
				( objectStatus "R8C4" )
				( pin "a"
					( attribute "PN" "1"
						( Origin gPackager )
					)
					( objectStatus "R8C4.1" )
				)
				( pin "b"
					( attribute "PN" "2"
						( Origin gPackager )
					)
					( objectStatus "R8C4.2" )
				)
			)
			( gate "@baseboard_fab2_lib.baseboard_fab2(sch_1):page133_i295"
				( attribute "CDS_LIB" "mstr_discrete"
					( Origin gPackager )
				)
				( attribute "CDS_LOCATION" "R7B6"
					( Origin gPackager )
				)
				( attribute "CDS_SEC" "1"
					( Origin gPackager )
				)
				( attribute "LOCATION" "R7B6"
					( Origin gFrontEnd )
				)
				( attribute "MATERIAL" "CHIP"
					( Origin gFrontEnd )
				)
				( attribute "PACK_TYPE" "0402"
					( Origin gFrontEnd )
				)
				( attribute "PART_NUMBER" "G21796-016"
					( Origin gFrontEnd )
				)
				( attribute "PHYS_PAGE" "133"
					( Origin gFrontEnd )
				)
				( attribute "ROOM" "SB_PU_PD"
					( Origin gFrontEnd )
				)
				( attribute "ROT" "0"
					( Origin gFrontEnd )
				)
				( attribute "SEC" "1"
					( Origin gFrontEnd )
				)
				( attribute "SEC_TYPE" "0402"
					( Origin gFrontEnd )
				)
				( attribute "TOLERANCE" "1%"
					( Origin gFrontEnd )
				)
				( attribute "VALUE" "10.0K"
					( Origin gFrontEnd )
				)
				( attribute "VER" "2"
					( Origin gFrontEnd )
				)
				( attribute "WATTAGE" "1/16W"
					( Origin gFrontEnd )
				)
				( attribute "XY" "(-175,1425)"
					( Origin gFrontEnd )
				)
				( attribute "CHIPS_PART_NAME" "RES"
					( Origin gPackager )
				)
				( attribute "CDS_PART_NAME" "RES_0402-10.0K,1%,1/16W,CHIP,GA"
					( Origin gPackager )
				)
				( objectStatus "R7B6" )
				( pin "a"
					( attribute "PN" "1"
						( Origin gPackager )
					)
					( objectStatus "R7B6.1" )
				)
				( pin "b"
					( attribute "PN" "2"
						( Origin gPackager )
					)
					( objectStatus "R7B6.2" )
				)
			)
			( gate "@baseboard_fab2_lib.baseboard_fab2(sch_1):page133_i296"
				( attribute "CDS_LIB" "mstr_discrete"
					( Origin gPackager )
				)
				( attribute "CDS_LOCATION" "R7C8"
					( Origin gPackager )
				)
				( attribute "CDS_SEC" "1"
					( Origin gPackager )
				)
				( attribute "LOCATION" "R7C8"
					( Origin gFrontEnd )
				)
				( attribute "MATERIAL" "CHIP"
					( Origin gFrontEnd )
				)
				( attribute "PACK_TYPE" "0402"
					( Origin gFrontEnd )
				)
				( attribute "PART_NUMBER" "G21796-016"
					( Origin gFrontEnd )
				)
				( attribute "PHYS_PAGE" "133"
					( Origin gFrontEnd )
				)
				( attribute "ROOM" "SB_PU_PD"
					( Origin gFrontEnd )
				)
				( attribute "ROT" "0"
					( Origin gFrontEnd )
				)
				( attribute "SEC" "1"
					( Origin gFrontEnd )
				)
				( attribute "SEC_TYPE" "0402"
					( Origin gFrontEnd )
				)
				( attribute "TOLERANCE" "1%"
					( Origin gFrontEnd )
				)
				( attribute "VALUE" "10.0K"
					( Origin gFrontEnd )
				)
				( attribute "VER" "2"
					( Origin gFrontEnd )
				)
				( attribute "WATTAGE" "1/16W"
					( Origin gFrontEnd )
				)
				( attribute "XY" "(-425,1425)"
					( Origin gFrontEnd )
				)
				( attribute "CHIPS_PART_NAME" "RES"
					( Origin gPackager )
				)
				( attribute "CDS_PART_NAME" "RES_0402-10.0K,1%,1/16W,CHIP,GA"
					( Origin gPackager )
				)
				( objectStatus "R7C8" )
				( pin "a"
					( attribute "PN" "1"
						( Origin gPackager )
					)
					( objectStatus "R7C8.1" )
				)
				( pin "b"
					( attribute "PN" "2"
						( Origin gPackager )
					)
					( objectStatus "R7C8.2" )
				)
			)
			( gate "@baseboard_fab2_lib.baseboard_fab2(sch_1):page133_i297"
				( attribute "CDS_LIB" "mstr_discrete"
					( Origin gPackager )
				)
				( attribute "CDS_LOCATION" "R7C5"
					( Origin gPackager )
				)
				( attribute "CDS_SEC" "1"
					( Origin gPackager )
				)
				( attribute "LOCATION" "R7C5"
					( Origin gFrontEnd )
				)
				( attribute "MATERIAL" "CHIP"
					( Origin gFrontEnd )
				)
				( attribute "PACK_TYPE" "0402"
					( Origin gFrontEnd )
				)
				( attribute "PART_NUMBER" "G21796-016"
					( Origin gFrontEnd )
				)
				( attribute "PHYS_PAGE" "133"
					( Origin gFrontEnd )
				)
				( attribute "ROOM" "SB_PU_PD"
					( Origin gFrontEnd )
				)
				( attribute "ROT" "0"
					( Origin gFrontEnd )
				)
				( attribute "SEC" "1"
					( Origin gFrontEnd )
				)
				( attribute "SEC_TYPE" "0402"
					( Origin gFrontEnd )
				)
				( attribute "TOLERANCE" "1%"
					( Origin gFrontEnd )
				)
				( attribute "VALUE" "10.0K"
					( Origin gFrontEnd )
				)
				( attribute "VER" "2"
					( Origin gFrontEnd )
				)
				( attribute "WATTAGE" "1/16W"
					( Origin gFrontEnd )
				)
				( attribute "XY" "(-650,1425)"
					( Origin gFrontEnd )
				)
				( attribute "CHIPS_PART_NAME" "RES"
					( Origin gPackager )
				)
				( attribute "CDS_PART_NAME" "RES_0402-10.0K,1%,1/16W,CHIP,GA"
					( Origin gPackager )
				)
				( objectStatus "R7C5" )
				( pin "a"
					( attribute "PN" "1"
						( Origin gPackager )
					)
					( objectStatus "R7C5.1" )
				)
				( pin "b"
					( attribute "PN" "2"
						( Origin gPackager )
					)
					( objectStatus "R7C5.2" )
				)
			)
			( gate "@baseboard_fab2_lib.baseboard_fab2(sch_1):page133_i301"
				( attribute "BOM_COST" "SB"
					( Origin gFrontEnd )
				)
				( attribute "CDS_LIB" "mstr_discrete"
					( Origin gPackager )
				)
				( attribute "CDS_LOCATION" "R8D14"
					( Origin gPackager )
				)
				( attribute "CDS_SEC" "1"
					( Origin gPackager )
				)
				( attribute "LOCATION" "R8D14"
					( Origin gFrontEnd )
				)
				( attribute "MATERIAL" "CHIP"
					( Origin gFrontEnd )
				)
				( attribute "PACK_TYPE" "0402"
					( Origin gFrontEnd )
				)
				( attribute "PART_NUMBER" "G21796-072"
					( Origin gFrontEnd )
				)
				( attribute "PHYS_PAGE" "133"
					( Origin gFrontEnd )
				)
				( attribute "ROOM" "SB"
					( Origin gFrontEnd )
				)
				( attribute "ROT" "0"
					( Origin gFrontEnd )
				)
				( attribute "SEC" "1"
					( Origin gFrontEnd )
				)
				( attribute "SEC_TYPE" "0402"
					( Origin gFrontEnd )
				)
				( attribute "TOLERANCE" "1%"
					( Origin gFrontEnd )
				)
				( attribute "VALUE" "4.75K"
					( Origin gFrontEnd )
				)
				( attribute "VER" "1"
					( Origin gFrontEnd )
				)
				( attribute "WATTAGE" "1/16W"
					( Origin gFrontEnd )
				)
				( attribute "XY" "(-2475,1800)"
					( Origin gFrontEnd )
				)
				( attribute "CHIPS_PART_NAME" "RES"
					( Origin gPackager )
				)
				( attribute "CDS_PART_NAME" "RES_0402-4.75K,1%,1/16W,CHIP,GA"
					( Origin gPackager )
				)
				( objectStatus "R8D14" )
				( pin "a"
					( attribute "PN" "1"
						( Origin gPackager )
					)
					( objectStatus "R8D14.1" )
				)
				( pin "b"
					( attribute "PN" "2"
						( Origin gPackager )
					)
					( objectStatus "R8D14.2" )
				)
			)
			( gate "@baseboard_fab2_lib.baseboard_fab2(sch_1):page133_i303"
				( attribute "CDS_LIB" "mstr_discrete"
					( Origin gPackager )
				)
				( attribute "CDS_LOCATION" "R8C6"
					( Origin gPackager )
				)
				( attribute "CDS_SEC" "1"
					( Origin gPackager )
				)
				( attribute "LOCATION" "R8C6"
					( Origin gFrontEnd )
				)
				( attribute "MATERIAL" "CHIP"
					( Origin gFrontEnd )
				)
				( attribute "PACK_TYPE" "0402"
					( Origin gFrontEnd )
				)
				( attribute "PART_NUMBER" "G21796-072"
					( Origin gFrontEnd )
				)
				( attribute "PHYS_PAGE" "133"
					( Origin gFrontEnd )
				)
				( attribute "ROOM" "SB_PU_PD"
					( Origin gFrontEnd )
				)
				( attribute "ROT" "0"
					( Origin gFrontEnd )
				)
				( attribute "SEC" "1"
					( Origin gFrontEnd )
				)
				( attribute "SEC_TYPE" "0402"
					( Origin gFrontEnd )
				)
				( attribute "TOLERANCE" "1%"
					( Origin gFrontEnd )
				)
				( attribute "VALUE" "4.75K"
					( Origin gFrontEnd )
				)
				( attribute "VER" "1"
					( Origin gFrontEnd )
				)
				( attribute "WATTAGE" "1/16W"
					( Origin gFrontEnd )
				)
				( attribute "XY" "(-4675,2400)"
					( Origin gFrontEnd )
				)
				( attribute "CHIPS_PART_NAME" "RES"
					( Origin gPackager )
				)
				( attribute "CDS_PART_NAME" "RES_0402-4.75K,1%,1/16W,CHIP,GA"
					( Origin gPackager )
				)
				( objectStatus "R8C6" )
				( pin "a"
					( attribute "PN" "1"
						( Origin gPackager )
					)
					( objectStatus "R8C6.1" )
				)
				( pin "b"
					( attribute "PN" "2"
						( Origin gPackager )
					)
					( objectStatus "R8C6.2" )
				)
			)
			( gate "@baseboard_fab2_lib.baseboard_fab2(sch_1):page133_i304"
				( attribute "CDS_LIB" "mstr_discrete"
					( Origin gPackager )
				)
				( attribute "CDS_LOCATION" "R8C2"
					( Origin gPackager )
				)
				( attribute "CDS_SEC" "1"
					( Origin gPackager )
				)
				( attribute "LOCATION" "R8C2"
					( Origin gFrontEnd )
				)
				( attribute "MATERIAL" "CHIP"
					( Origin gFrontEnd )
				)
				( attribute "PACK_TYPE" "0402"
					( Origin gFrontEnd )
				)
				( attribute "PART_NUMBER" "G21796-072"
					( Origin gFrontEnd )
				)
				( attribute "PHYS_PAGE" "133"
					( Origin gFrontEnd )
				)
				( attribute "ROOM" "SB_PU_PD"
					( Origin gFrontEnd )
				)
				( attribute "ROT" "0"
					( Origin gFrontEnd )
				)
				( attribute "SEC" "1"
					( Origin gFrontEnd )
				)
				( attribute "SEC_TYPE" "0402"
					( Origin gFrontEnd )
				)
				( attribute "TOLERANCE" "1%"
					( Origin gFrontEnd )
				)
				( attribute "VALUE" "4.75K"
					( Origin gFrontEnd )
				)
				( attribute "VER" "1"
					( Origin gFrontEnd )
				)
				( attribute "WATTAGE" "1/16W"
					( Origin gFrontEnd )
				)
				( attribute "XY" "(-4800,1825)"
					( Origin gFrontEnd )
				)
				( attribute "CHIPS_PART_NAME" "RES"
					( Origin gPackager )
				)
				( attribute "CDS_PART_NAME" "RES_0402-4.75K,1%,1/16W,CHIP,GA"
					( Origin gPackager )
				)
				( objectStatus "R8C2" )
				( pin "a"
					( attribute "PN" "1"
						( Origin gPackager )
					)
					( objectStatus "R8C2.1" )
				)
				( pin "b"
					( attribute "PN" "2"
						( Origin gPackager )
					)
					( objectStatus "R8C2.2" )
				)
			)
			( gate "@baseboard_fab2_lib.baseboard_fab2(sch_1):page133_i306"
				( attribute "CDS_LIB" "mstr_discrete"
					( Origin gPackager )
				)
				( attribute "CDS_LOCATION" "R7D6"
					( Origin gPackager )
				)
				( attribute "CDS_SEC" "1"
					( Origin gPackager )
				)
				( attribute "LOCATION" "R7D6"
					( Origin gFrontEnd )
				)
				( attribute "MATERIAL" "CHIP"
					( Origin gFrontEnd )
				)
				( attribute "PACK_TYPE" "0402"
					( Origin gFrontEnd )
				)
				( attribute "PART_NUMBER" "G21796-072"
					( Origin gFrontEnd )
				)
				( attribute "PHYS_PAGE" "133"
					( Origin gFrontEnd )
				)
				( attribute "ROOM" "SB_PU_PD"
					( Origin gFrontEnd )
				)
				( attribute "ROT" "0"
					( Origin gFrontEnd )
				)
				( attribute "SEC" "1"
					( Origin gFrontEnd )
				)
				( attribute "SEC_TYPE" "0402"
					( Origin gFrontEnd )
				)
				( attribute "TOLERANCE" "1%"
					( Origin gFrontEnd )
				)
				( attribute "VALUE" "4.75K"
					( Origin gFrontEnd )
				)
				( attribute "VER" "1"
					( Origin gFrontEnd )
				)
				( attribute "WATTAGE" "1/16W"
					( Origin gFrontEnd )
				)
				( attribute "XY" "(-4700,3700)"
					( Origin gFrontEnd )
				)
				( attribute "CHIPS_PART_NAME" "RES"
					( Origin gPackager )
				)
				( attribute "CDS_PART_NAME" "RES_0402-4.75K,1%,1/16W,CHIP,GA"
					( Origin gPackager )
				)
				( objectStatus "R7D6" )
				( pin "a"
					( attribute "PN" "1"
						( Origin gPackager )
					)
					( objectStatus "R7D6.1" )
				)
				( pin "b"
					( attribute "PN" "2"
						( Origin gPackager )
					)
					( objectStatus "R7D6.2" )
				)
			)
			( gate "@baseboard_fab2_lib.baseboard_fab2(sch_1):page133_i307"
				( attribute "CDS_LIB" "mstr_discrete"
					( Origin gPackager )
				)
				( attribute "CDS_LOCATION" "R8B31"
					( Origin gPackager )
				)
				( attribute "CDS_SEC" "1"
					( Origin gPackager )
				)
				( attribute "LOCATION" "R8B31"
					( Origin gFrontEnd )
				)
				( attribute "MATERIAL" "CHIP"
					( Origin gFrontEnd )
				)
				( attribute "PACK_TYPE" "0402"
					( Origin gFrontEnd )
				)
				( attribute "PART_NUMBER" "G21796-072"
					( Origin gFrontEnd )
				)
				( attribute "PHYS_PAGE" "133"
					( Origin gFrontEnd )
				)
				( attribute "ROOM" "SB_PU_PD"
					( Origin gFrontEnd )
				)
				( attribute "ROT" "0"
					( Origin gFrontEnd )
				)
				( attribute "SEC" "1"
					( Origin gFrontEnd )
				)
				( attribute "SEC_TYPE" "0402"
					( Origin gFrontEnd )
				)
				( attribute "TOLERANCE" "1%"
					( Origin gFrontEnd )
				)
				( attribute "VALUE" "4.75K"
					( Origin gFrontEnd )
				)
				( attribute "VER" "1"
					( Origin gFrontEnd )
				)
				( attribute "WATTAGE" "1/16W"
					( Origin gFrontEnd )
				)
				( attribute "XY" "(-4800,1650)"
					( Origin gFrontEnd )
				)
				( attribute "CHIPS_PART_NAME" "RES"
					( Origin gPackager )
				)
				( attribute "CDS_PART_NAME" "RES_0402-4.75K,1%,1/16W,CHIP,GA"
					( Origin gPackager )
				)
				( objectStatus "R8B31" )
				( pin "a"
					( attribute "PN" "1"
						( Origin gPackager )
					)
					( objectStatus "R8B31.1" )
				)
				( pin "b"
					( attribute "PN" "2"
						( Origin gPackager )
					)
					( objectStatus "R8B31.2" )
				)
			)
			( gate "@baseboard_fab2_lib.baseboard_fab2(sch_1):page133_i309"
				( attribute "CDS_LIB" "mstr_discrete"
					( Origin gPackager )
				)
				( attribute "CDS_LOCATION" "R2N7"
					( Origin gPackager )
				)
				( attribute "CDS_SEC" "1"
					( Origin gPackager )
				)
				( attribute "LOCATION" "R2N7"
					( Origin gFrontEnd )
				)
				( attribute "MATERIAL" "CHIP"
					( Origin gFrontEnd )
				)
				( attribute "PACK_TYPE" "0402"
					( Origin gFrontEnd )
				)
				( attribute "PART_NUMBER" "G21796-072"
					( Origin gFrontEnd )
				)
				( attribute "PHYS_PAGE" "133"
					( Origin gFrontEnd )
				)
				( attribute "ROOM" "SB_PU_PD"
					( Origin gFrontEnd )
				)
				( attribute "ROT" "0"
					( Origin gFrontEnd )
				)
				( attribute "SEC" "1"
					( Origin gFrontEnd )
				)
				( attribute "SEC_TYPE" "0402"
					( Origin gFrontEnd )
				)
				( attribute "TOLERANCE" "1%"
					( Origin gFrontEnd )
				)
				( attribute "VALUE" "4.75K"
					( Origin gFrontEnd )
				)
				( attribute "VER" "1"
					( Origin gFrontEnd )
				)
				( attribute "WATTAGE" "1/16W"
					( Origin gFrontEnd )
				)
				( attribute "XY" "(-2475,1025)"
					( Origin gFrontEnd )
				)
				( attribute "CHIPS_PART_NAME" "RES"
					( Origin gPackager )
				)
				( attribute "CDS_PART_NAME" "RES_0402-4.75K,1%,1/16W,CHIP,GA"
					( Origin gPackager )
				)
				( objectStatus "R2N7" )
				( pin "a"
					( attribute "PN" "1"
						( Origin gPackager )
					)
					( objectStatus "R2N7.1" )
				)
				( pin "b"
					( attribute "PN" "2"
						( Origin gPackager )
					)
					( objectStatus "R2N7.2" )
				)
			)
			( gate "@baseboard_fab2_lib.baseboard_fab2(sch_1):page133_i315"
				( attribute "BOM_COST" "SB"
					( Origin gFrontEnd )
				)
				( attribute "CDS_LIB" "mstr_discrete"
					( Origin gPackager )
				)
				( attribute "CDS_LOCATION" "R3P7"
					( Origin gPackager )
				)
				( attribute "CDS_SEC" "1"
					( Origin gPackager )
				)
				( attribute "LOCATION" "R3P7"
					( Origin gFrontEnd )
				)
				( attribute "MATERIAL" "CHIP"
					( Origin gFrontEnd )
				)
				( attribute "PACK_TYPE" "0402"
					( Origin gFrontEnd )
				)
				( attribute "PART_NUMBER" "G21796-026"
					( Origin gFrontEnd )
				)
				( attribute "PHYS_PAGE" "133"
					( Origin gFrontEnd )
				)
				( attribute "ROOM" "SB"
					( Origin gFrontEnd )
				)
				( attribute "ROT" "0"
					( Origin gFrontEnd )
				)
				( attribute "SEC" "1"
					( Origin gFrontEnd )
				)
				( attribute "SEC_TYPE" "0402"
					( Origin gFrontEnd )
				)
				( attribute "TOLERANCE" "1%"
					( Origin gFrontEnd )
				)
				( attribute "VALUE" "1.00K"
					( Origin gFrontEnd )
				)
				( attribute "VER" "1"
					( Origin gFrontEnd )
				)
				( attribute "WATTAGE" "1/16W"
					( Origin gFrontEnd )
				)
				( attribute "XY" "(-400,5100)"
					( Origin gFrontEnd )
				)
				( attribute "CHIPS_PART_NAME" "RES"
					( Origin gPackager )
				)
				( attribute "CDS_PART_NAME" "RES_0402-1.00K,1%,1/16W,CHIP,GA"
					( Origin gPackager )
				)
				( objectStatus "R3P7" )
				( pin "a"
					( attribute "PN" "1"
						( Origin gPackager )
					)
					( objectStatus "R3P7.1" )
				)
				( pin "b"
					( attribute "PN" "2"
						( Origin gPackager )
					)
					( objectStatus "R3P7.2" )
				)
			)
			( gate "@baseboard_fab2_lib.baseboard_fab2(sch_1):page133_i316"
				( attribute "BOM_COST" "SB"
					( Origin gFrontEnd )
				)
				( attribute "CDS_LIB" "mstr_discrete"
					( Origin gPackager )
				)
				( attribute "CDS_LOCATION" "R3P5"
					( Origin gPackager )
				)
				( attribute "CDS_SEC" "1"
					( Origin gPackager )
				)
				( attribute "LOCATION" "R3P5"
					( Origin gFrontEnd )
				)
				( attribute "MATERIAL" "CHIP"
					( Origin gFrontEnd )
				)
				( attribute "PACK_TYPE" "0402"
					( Origin gFrontEnd )
				)
				( attribute "PART_NUMBER" "G21796-026"
					( Origin gFrontEnd )
				)
				( attribute "PHYS_PAGE" "133"
					( Origin gFrontEnd )
				)
				( attribute "ROOM" "SB"
					( Origin gFrontEnd )
				)
				( attribute "ROT" "0"
					( Origin gFrontEnd )
				)
				( attribute "SEC" "1"
					( Origin gFrontEnd )
				)
				( attribute "SEC_TYPE" "0402"
					( Origin gFrontEnd )
				)
				( attribute "TOLERANCE" "1%"
					( Origin gFrontEnd )
				)
				( attribute "VALUE" "1.00K"
					( Origin gFrontEnd )
				)
				( attribute "VER" "1"
					( Origin gFrontEnd )
				)
				( attribute "WATTAGE" "1/16W"
					( Origin gFrontEnd )
				)
				( attribute "XY" "(-400,4875)"
					( Origin gFrontEnd )
				)
				( attribute "CHIPS_PART_NAME" "RES"
					( Origin gPackager )
				)
				( attribute "CDS_PART_NAME" "RES_0402-1.00K,1%,1/16W,CHIP,GA"
					( Origin gPackager )
				)
				( objectStatus "R3P5" )
				( pin "a"
					( attribute "PN" "1"
						( Origin gPackager )
					)
					( objectStatus "R3P5.1" )
				)
				( pin "b"
					( attribute "PN" "2"
						( Origin gPackager )
					)
					( objectStatus "R3P5.2" )
				)
			)
			( gate "@baseboard_fab2_lib.baseboard_fab2(sch_1):page133_i317"
				( attribute "BOM_COST" "SB"
					( Origin gFrontEnd )
				)
				( attribute "CDS_LIB" "mstr_discrete"
					( Origin gPackager )
				)
				( attribute "CDS_LOCATION" "R3P6"
					( Origin gPackager )
				)
				( attribute "CDS_SEC" "1"
					( Origin gPackager )
				)
				( attribute "LOCATION" "R3P6"
					( Origin gFrontEnd )
				)
				( attribute "MATERIAL" "CHIP"
					( Origin gFrontEnd )
				)
				( attribute "PACK_TYPE" "0402"
					( Origin gFrontEnd )
				)
				( attribute "PART_NUMBER" "G21796-026"
					( Origin gFrontEnd )
				)
				( attribute "PHYS_PAGE" "133"
					( Origin gFrontEnd )
				)
				( attribute "ROOM" "SB"
					( Origin gFrontEnd )
				)
				( attribute "ROT" "0"
					( Origin gFrontEnd )
				)
				( attribute "SEC" "1"
					( Origin gFrontEnd )
				)
				( attribute "SEC_TYPE" "0402"
					( Origin gFrontEnd )
				)
				( attribute "TOLERANCE" "1%"
					( Origin gFrontEnd )
				)
				( attribute "VALUE" "1.00K"
					( Origin gFrontEnd )
				)
				( attribute "VER" "1"
					( Origin gFrontEnd )
				)
				( attribute "WATTAGE" "1/16W"
					( Origin gFrontEnd )
				)
				( attribute "XY" "(-375,4650)"
					( Origin gFrontEnd )
				)
				( attribute "CHIPS_PART_NAME" "RES"
					( Origin gPackager )
				)
				( attribute "CDS_PART_NAME" "RES_0402-1.00K,1%,1/16W,CHIP,GA"
					( Origin gPackager )
				)
				( objectStatus "R3P6" )
				( pin "a"
					( attribute "PN" "1"
						( Origin gPackager )
					)
					( objectStatus "R3P6.1" )
				)
				( pin "b"
					( attribute "PN" "2"
						( Origin gPackager )
					)
					( objectStatus "R3P6.2" )
				)
			)
			( gate "@baseboard_fab2_lib.baseboard_fab2(sch_1):page133_i318"
				( attribute "BOM_COST" "SB"
					( Origin gFrontEnd )
				)
				( attribute "CDS_LIB" "mstr_discrete"
					( Origin gPackager )
				)
				( attribute "CDS_LOCATION" "R3N15"
					( Origin gPackager )
				)
				( attribute "CDS_SEC" "1"
					( Origin gPackager )
				)
				( attribute "LOCATION" "R3N15"
					( Origin gFrontEnd )
				)
				( attribute "MATERIAL" "CHIP"
					( Origin gFrontEnd )
				)
				( attribute "PACK_TYPE" "0402"
					( Origin gFrontEnd )
				)
				( attribute "PART_NUMBER" "G21796-026"
					( Origin gFrontEnd )
				)
				( attribute "PHYS_PAGE" "133"
					( Origin gFrontEnd )
				)
				( attribute "ROOM" "SB"
					( Origin gFrontEnd )
				)
				( attribute "ROT" "0"
					( Origin gFrontEnd )
				)
				( attribute "SEC" "1"
					( Origin gFrontEnd )
				)
				( attribute "SEC_TYPE" "0402"
					( Origin gFrontEnd )
				)
				( attribute "TOLERANCE" "1%"
					( Origin gFrontEnd )
				)
				( attribute "VALUE" "1.00K"
					( Origin gFrontEnd )
				)
				( attribute "VER" "1"
					( Origin gFrontEnd )
				)
				( attribute "WATTAGE" "1/16W"
					( Origin gFrontEnd )
				)
				( attribute "XY" "(-375,4400)"
					( Origin gFrontEnd )
				)
				( attribute "CHIPS_PART_NAME" "RES"
					( Origin gPackager )
				)
				( attribute "CDS_PART_NAME" "RES_0402-1.00K,1%,1/16W,CHIP,GA"
					( Origin gPackager )
				)
				( objectStatus "R3N15" )
				( pin "a"
					( attribute "PN" "1"
						( Origin gPackager )
					)
					( objectStatus "R3N15.1" )
				)
				( pin "b"
					( attribute "PN" "2"
						( Origin gPackager )
					)
					( objectStatus "R3N15.2" )
				)
			)
			( gate "@baseboard_fab2_lib.baseboard_fab2(sch_1):page133_i321"
				( attribute "BOM_COST" "SB"
					( Origin gFrontEnd )
				)
				( attribute "CDS_LIB" "mstr_discrete"
					( Origin gPackager )
				)
				( attribute "CDS_LOCATION" "R3N16"
					( Origin gPackager )
				)
				( attribute "CDS_SEC" "1"
					( Origin gPackager )
				)
				( attribute "LOCATION" "R3N16"
					( Origin gFrontEnd )
				)
				( attribute "MATERIAL" "CHIP"
					( Origin gFrontEnd )
				)
				( attribute "PACK_TYPE" "0402"
					( Origin gFrontEnd )
				)
				( attribute "PART_NUMBER" "G21796-026"
					( Origin gFrontEnd )
				)
				( attribute "PHYS_PAGE" "133"
					( Origin gFrontEnd )
				)
				( attribute "ROOM" "SB"
					( Origin gFrontEnd )
				)
				( attribute "ROT" "0"
					( Origin gFrontEnd )
				)
				( attribute "SEC" "1"
					( Origin gFrontEnd )
				)
				( attribute "SEC_TYPE" "0402"
					( Origin gFrontEnd )
				)
				( attribute "TOLERANCE" "1%"
					( Origin gFrontEnd )
				)
				( attribute "VALUE" "1.00K"
					( Origin gFrontEnd )
				)
				( attribute "VER" "1"
					( Origin gFrontEnd )
				)
				( attribute "WATTAGE" "1/16W"
					( Origin gFrontEnd )
				)
				( attribute "XY" "(-375,4175)"
					( Origin gFrontEnd )
				)
				( attribute "CHIPS_PART_NAME" "RES"
					( Origin gPackager )
				)
				( attribute "CDS_PART_NAME" "RES_0402-1.00K,1%,1/16W,CHIP,GA"
					( Origin gPackager )
				)
				( objectStatus "R3N16" )
				( pin "a"
					( attribute "PN" "1"
						( Origin gPackager )
					)
					( objectStatus "R3N16.1" )
				)
				( pin "b"
					( attribute "PN" "2"
						( Origin gPackager )
					)
					( objectStatus "R3N16.2" )
				)
			)
			( gate "@baseboard_fab2_lib.baseboard_fab2(sch_1):page133_i322"
				( attribute "BOM_COST" "SB"
					( Origin gFrontEnd )
				)
				( attribute "CDS_LIB" "mstr_discrete"
					( Origin gPackager )
				)
				( attribute "CDS_LOCATION" "R3P8"
					( Origin gPackager )
				)
				( attribute "CDS_SEC" "1"
					( Origin gPackager )
				)
				( attribute "LOCATION" "R3P8"
					( Origin gFrontEnd )
				)
				( attribute "MATERIAL" "CHIP"
					( Origin gFrontEnd )
				)
				( attribute "PACK_TYPE" "0402"
					( Origin gFrontEnd )
				)
				( attribute "PART_NUMBER" "G21796-026"
					( Origin gFrontEnd )
				)
				( attribute "PHYS_PAGE" "133"
					( Origin gFrontEnd )
				)
				( attribute "ROOM" "SB"
					( Origin gFrontEnd )
				)
				( attribute "ROT" "0"
					( Origin gFrontEnd )
				)
				( attribute "SEC" "1"
					( Origin gFrontEnd )
				)
				( attribute "SEC_TYPE" "0402"
					( Origin gFrontEnd )
				)
				( attribute "TOLERANCE" "1%"
					( Origin gFrontEnd )
				)
				( attribute "VALUE" "1.00K"
					( Origin gFrontEnd )
				)
				( attribute "VER" "1"
					( Origin gFrontEnd )
				)
				( attribute "WATTAGE" "1/16W"
					( Origin gFrontEnd )
				)
				( attribute "XY" "(-375,3925)"
					( Origin gFrontEnd )
				)
				( attribute "CHIPS_PART_NAME" "RES"
					( Origin gPackager )
				)
				( attribute "CDS_PART_NAME" "RES_0402-1.00K,1%,1/16W,CHIP,GA"
					( Origin gPackager )
				)
				( objectStatus "R3P8" )
				( pin "a"
					( attribute "PN" "1"
						( Origin gPackager )
					)
					( objectStatus "R3P8.1" )
				)
				( pin "b"
					( attribute "PN" "2"
						( Origin gPackager )
					)
					( objectStatus "R3P8.2" )
				)
			)
			( gate "@baseboard_fab2_lib.baseboard_fab2(sch_1):page133_i326"
				( attribute "CDS_LIB" "mstr_discrete"
					( Origin gPackager )
				)
				( attribute "CDS_LOCATION" "R8C1"
					( Origin gPackager )
				)
				( attribute "CDS_SEC" "1"
					( Origin gPackager )
				)
				( attribute "LOCATION" "R8C1"
					( Origin gFrontEnd )
				)
				( attribute "MATERIAL" "CHIP"
					( Origin gFrontEnd )
				)
				( attribute "PACK_TYPE" "0402"
					( Origin gFrontEnd )
				)
				( attribute "PART_NUMBER" "G21796-072"
					( Origin gFrontEnd )
				)
				( attribute "PHYS_PAGE" "133"
					( Origin gFrontEnd )
				)
				( attribute "ROOM" "SB_PU_PD"
					( Origin gFrontEnd )
				)
				( attribute "ROT" "0"
					( Origin gFrontEnd )
				)
				( attribute "SEC" "1"
					( Origin gFrontEnd )
				)
				( attribute "SEC_TYPE" "0402"
					( Origin gFrontEnd )
				)
				( attribute "TOLERANCE" "1%"
					( Origin gFrontEnd )
				)
				( attribute "VALUE" "4.75K"
					( Origin gFrontEnd )
				)
				( attribute "VER" "1"
					( Origin gFrontEnd )
				)
				( attribute "WATTAGE" "1/16W"
					( Origin gFrontEnd )
				)
				( attribute "XY" "(-4800,1300)"
					( Origin gFrontEnd )
				)
				( attribute "CHIPS_PART_NAME" "RES"
					( Origin gPackager )
				)
				( attribute "CDS_PART_NAME" "RES_0402-4.75K,1%,1/16W,CHIP,GA"
					( Origin gPackager )
				)
				( objectStatus "R8C1" )
				( pin "a"
					( attribute "PN" "1"
						( Origin gPackager )
					)
					( objectStatus "R8C1.1" )
				)
				( pin "b"
					( attribute "PN" "2"
						( Origin gPackager )
					)
					( objectStatus "R8C1.2" )
				)
			)
			( gate "@baseboard_fab2_lib.baseboard_fab2(sch_1):page133_i327"
				( attribute "BOM_COST" "SB"
					( Origin gFrontEnd )
				)
				( attribute "CDS_LIB" "mstr_discrete"
					( Origin gPackager )
				)
				( attribute "CDS_LOCATION" "R8C7"
					( Origin gPackager )
				)
				( attribute "CDS_SEC" "1"
					( Origin gPackager )
				)
				( attribute "LOCATION" "R8C7"
					( Origin gFrontEnd )
				)
				( attribute "MATERIAL" "CHIP"
					( Origin gFrontEnd )
				)
				( attribute "PACK_TYPE" "0402"
					( Origin gFrontEnd )
				)
				( attribute "PART_NUMBER" "G21796-072"
					( Origin gFrontEnd )
				)
				( attribute "PHYS_PAGE" "133"
					( Origin gFrontEnd )
				)
				( attribute "ROOM" "SB_PU_PD"
					( Origin gFrontEnd )
				)
				( attribute "ROT" "0"
					( Origin gFrontEnd )
				)
				( attribute "SEC" "1"
					( Origin gFrontEnd )
				)
				( attribute "SEC_TYPE" "0402"
					( Origin gFrontEnd )
				)
				( attribute "TOLERANCE" "1%"
					( Origin gFrontEnd )
				)
				( attribute "VALUE" "4.75K"
					( Origin gFrontEnd )
				)
				( attribute "VER" "1"
					( Origin gFrontEnd )
				)
				( attribute "WATTAGE" "1/16W"
					( Origin gFrontEnd )
				)
				( attribute "XY" "(-4800,1125)"
					( Origin gFrontEnd )
				)
				( attribute "CHIPS_PART_NAME" "RES"
					( Origin gPackager )
				)
				( attribute "CDS_PART_NAME" "RES_0402-4.75K,1%,1/16W,CHIP,GA"
					( Origin gPackager )
				)
				( objectStatus "R8C7" )
				( pin "a"
					( attribute "PN" "1"
						( Origin gPackager )
					)
					( objectStatus "R8C7.1" )
				)
				( pin "b"
					( attribute "PN" "2"
						( Origin gPackager )
					)
					( objectStatus "R8C7.2" )
				)
			)
			( gate "@baseboard_fab2_lib.baseboard_fab2(sch_1):page133_i331"
				( attribute "BOM_COST" "SB_PU_PD"
					( Origin gFrontEnd )
				)
				( attribute "CDS_LIB" "mstr_discrete"
					( Origin gPackager )
				)
				( attribute "CDS_LOCATION" "R7D7"
					( Origin gPackager )
				)
				( attribute "CDS_SEC" "1"
					( Origin gPackager )
				)
				( attribute "LOCATION" "R7D7"
					( Origin gFrontEnd )
				)
				( attribute "MATERIAL" "CHIP"
					( Origin gFrontEnd )
				)
				( attribute "PACK_TYPE" "0402"
					( Origin gFrontEnd )
				)
				( attribute "PART_NUMBER" "G21796-026"
					( Origin gFrontEnd )
				)
				( attribute "PHYS_PAGE" "133"
					( Origin gFrontEnd )
				)
				( attribute "ROOM" "SB"
					( Origin gFrontEnd )
				)
				( attribute "ROT" "0"
					( Origin gFrontEnd )
				)
				( attribute "SEC" "1"
					( Origin gFrontEnd )
				)
				( attribute "SEC_TYPE" "0402"
					( Origin gFrontEnd )
				)
				( attribute "TOLERANCE" "1%"
					( Origin gFrontEnd )
				)
				( attribute "VALUE" "1.00K"
					( Origin gFrontEnd )
				)
				( attribute "VER" "1"
					( Origin gFrontEnd )
				)
				( attribute "WATTAGE" "1/16W"
					( Origin gFrontEnd )
				)
				( attribute "XY" "(-4700,4700)"
					( Origin gFrontEnd )
				)
				( attribute "CHIPS_PART_NAME" "RES"
					( Origin gPackager )
				)
				( attribute "CDS_PART_NAME" "RES_0402-1.00K,1%,1/16W,CHIP,GA"
					( Origin gPackager )
				)
				( objectStatus "R7D7" )
				( pin "a"
					( attribute "PN" "1"
						( Origin gPackager )
					)
					( objectStatus "R7D7.1" )
				)
				( pin "b"
					( attribute "PN" "2"
						( Origin gPackager )
					)
					( objectStatus "R7D7.2" )
				)
			)
			( gate "@baseboard_fab2_lib.baseboard_fab2(sch_1):page133_i332"
				( attribute "BOM_COST" "SB_PU_PD"
					( Origin gFrontEnd )
				)
				( attribute "CDS_LIB" "mstr_discrete"
					( Origin gPackager )
				)
				( attribute "CDS_LOCATION" "R7D2"
					( Origin gPackager )
				)
				( attribute "CDS_SEC" "1"
					( Origin gPackager )
				)
				( attribute "LOCATION" "R7D2"
					( Origin gFrontEnd )
				)
				( attribute "MATERIAL" "CHIP"
					( Origin gFrontEnd )
				)
				( attribute "PACK_TYPE" "0402"
					( Origin gFrontEnd )
				)
				( attribute "PART_NUMBER" "G21796-026"
					( Origin gFrontEnd )
				)
				( attribute "PHYS_PAGE" "133"
					( Origin gFrontEnd )
				)
				( attribute "ROOM" "SB"
					( Origin gFrontEnd )
				)
				( attribute "ROT" "0"
					( Origin gFrontEnd )
				)
				( attribute "SEC" "1"
					( Origin gFrontEnd )
				)
				( attribute "SEC_TYPE" "0402"
					( Origin gFrontEnd )
				)
				( attribute "TOLERANCE" "1%"
					( Origin gFrontEnd )
				)
				( attribute "VALUE" "1.00K"
					( Origin gFrontEnd )
				)
				( attribute "VER" "1"
					( Origin gFrontEnd )
				)
				( attribute "WATTAGE" "1/16W"
					( Origin gFrontEnd )
				)
				( attribute "XY" "(-4700,5100)"
					( Origin gFrontEnd )
				)
				( attribute "CHIPS_PART_NAME" "RES"
					( Origin gPackager )
				)
				( attribute "CDS_PART_NAME" "RES_0402-1.00K,1%,1/16W,CHIP,GA"
					( Origin gPackager )
				)
				( objectStatus "R7D2" )
				( pin "a"
					( attribute "PN" "1"
						( Origin gPackager )
					)
					( objectStatus "R7D2.1" )
				)
				( pin "b"
					( attribute "PN" "2"
						( Origin gPackager )
					)
					( objectStatus "R7D2.2" )
				)
			)
			( gate "@baseboard_fab2_lib.baseboard_fab2(sch_1):page133_i333"
				( attribute "CDS_LIB" "mstr_discrete"
					( Origin gPackager )
				)
				( attribute "CDS_LOCATION" "R8C25"
					( Origin gPackager )
				)
				( attribute "CDS_SEC" "1"
					( Origin gPackager )
				)
				( attribute "LOCATION" "R8C25"
					( Origin gFrontEnd )
				)
				( attribute "MATERIAL" "CHIP"
					( Origin gFrontEnd )
				)
				( attribute "PACK_TYPE" "0402"
					( Origin gFrontEnd )
				)
				( attribute "PART_NUMBER" "G21796-072"
					( Origin gFrontEnd )
				)
				( attribute "PHYS_PAGE" "133"
					( Origin gFrontEnd )
				)
				( attribute "ROOM" "SB_PU_PD"
					( Origin gFrontEnd )
				)
				( attribute "ROT" "0"
					( Origin gFrontEnd )
				)
				( attribute "SEC" "1"
					( Origin gFrontEnd )
				)
				( attribute "SEC_TYPE" "0402"
					( Origin gFrontEnd )
				)
				( attribute "TOLERANCE" "1%"
					( Origin gFrontEnd )
				)
				( attribute "VALUE" "4.75K"
					( Origin gFrontEnd )
				)
				( attribute "VER" "1"
					( Origin gFrontEnd )
				)
				( attribute "WATTAGE" "1/16W"
					( Origin gFrontEnd )
				)
				( attribute "XY" "(-2500,3150)"
					( Origin gFrontEnd )
				)
				( attribute "CHIPS_PART_NAME" "RES"
					( Origin gPackager )
				)
				( attribute "CDS_PART_NAME" "RES_0402-4.75K,1%,1/16W,CHIP,GA"
					( Origin gPackager )
				)
				( objectStatus "R8C25" )
				( pin "a"
					( attribute "PN" "1"
						( Origin gPackager )
					)
					( objectStatus "R8C25.1" )
				)
				( pin "b"
					( attribute "PN" "2"
						( Origin gPackager )
					)
					( objectStatus "R8C25.2" )
				)
			)
			( gate "@baseboard_fab2_lib.baseboard_fab2(sch_1):page133_i341"
				( attribute "BOM_COST" "SB"
					( Origin gFrontEnd )
				)
				( attribute "CDS_LIB" "mstr_discrete"
					( Origin gPackager )
				)
				( attribute "CDS_LOCATION" "R2N32"
					( Origin gPackager )
				)
				( attribute "CDS_SEC" "1"
					( Origin gPackager )
				)
				( attribute "LOCATION" "R2N32"
					( Origin gFrontEnd )
				)
				( attribute "MATERIAL" "CHIP"
					( Origin gFrontEnd )
				)
				( attribute "PACK_TYPE" "0402"
					( Origin gFrontEnd )
				)
				( attribute "PART_NUMBER" "G21796-072"
					( Origin gFrontEnd )
				)
				( attribute "PHYS_PAGE" "133"
					( Origin gFrontEnd )
				)
				( attribute "ROOM" "SB"
					( Origin gFrontEnd )
				)
				( attribute "ROT" "0"
					( Origin gFrontEnd )
				)
				( attribute "SEC" "1"
					( Origin gFrontEnd )
				)
				( attribute "SEC_TYPE" "0402"
					( Origin gFrontEnd )
				)
				( attribute "TOLERANCE" "1%"
					( Origin gFrontEnd )
				)
				( attribute "VALUE" "4.75K"
					( Origin gFrontEnd )
				)
				( attribute "VER" "1"
					( Origin gFrontEnd )
				)
				( attribute "WATTAGE" "1/16W"
					( Origin gFrontEnd )
				)
				( attribute "XY" "(-2475,2700)"
					( Origin gFrontEnd )
				)
				( attribute "CHIPS_PART_NAME" "RES"
					( Origin gPackager )
				)
				( attribute "CDS_PART_NAME" "RES_0402-4.75K,1%,1/16W,CHIP,GA"
					( Origin gPackager )
				)
				( objectStatus "R2N32" )
				( pin "a"
					( attribute "PN" "1"
						( Origin gPackager )
					)
					( objectStatus "R2N32.1" )
				)
				( pin "b"
					( attribute "PN" "2"
						( Origin gPackager )
					)
					( objectStatus "R2N32.2" )
				)
			)
			( gate "@baseboard_fab2_lib.baseboard_fab2(sch_1):page133_i349"
				( attribute "BOM_COST" "SB"
					( Origin gFrontEnd )
				)
				( attribute "CDS_LIB" "mstr_discrete"
					( Origin gPackager )
				)
				( attribute "CDS_LOCATION" "R2M8"
					( Origin gPackager )
				)
				( attribute "CDS_SEC" "1"
					( Origin gPackager )
				)
				( attribute "LOCATION" "R2M8"
					( Origin gFrontEnd )
				)
				( attribute "MATERIAL" "CHIP"
					( Origin gFrontEnd )
				)
				( attribute "PACK_TYPE" "0402"
					( Origin gFrontEnd )
				)
				( attribute "PART_NUMBER" "G21796-003"
					( Origin gFrontEnd )
				)
				( attribute "PHYS_PAGE" "133"
					( Origin gFrontEnd )
				)
				( attribute "ROOM" "SB"
					( Origin gFrontEnd )
				)
				( attribute "ROT" "0"
					( Origin gFrontEnd )
				)
				( attribute "SEC" "1"
					( Origin gFrontEnd )
				)
				( attribute "SEC_TYPE" "0402"
					( Origin gFrontEnd )
				)
				( attribute "TOLERANCE" "1%"
					( Origin gFrontEnd )
				)
				( attribute "VALUE" "1.5K"
					( Origin gFrontEnd )
				)
				( attribute "VER" "1"
					( Origin gFrontEnd )
				)
				( attribute "WATTAGE" "1/16W"
					( Origin gFrontEnd )
				)
				( attribute "XY" "(-375,2725)"
					( Origin gFrontEnd )
				)
				( attribute "CHIPS_PART_NAME" "RES"
					( Origin gPackager )
				)
				( attribute "CDS_PART_NAME" "RES_0402-1.5K,1%,1/16W,CHIP,G2A"
					( Origin gPackager )
				)
				( objectStatus "R2M8" )
				( pin "a"
					( attribute "PN" "1"
						( Origin gPackager )
					)
					( objectStatus "R2M8.1" )
				)
				( pin "b"
					( attribute "PN" "2"
						( Origin gPackager )
					)
					( objectStatus "R2M8.2" )
				)
			)
			( gate "@baseboard_fab2_lib.baseboard_fab2(sch_1):page133_i352"
				( attribute "BOM_COST" "SB"
					( Origin gFrontEnd )
				)
				( attribute "CDS_LIB" "mstr_discrete"
					( Origin gPackager )
				)
				( attribute "CDS_LOCATION" "R2N29"
					( Origin gPackager )
				)
				( attribute "CDS_SEC" "1"
					( Origin gPackager )
				)
				( attribute "LOCATION" "R2N29"
					( Origin gFrontEnd )
				)
				( attribute "MATERIAL" "CHIP"
					( Origin gFrontEnd )
				)
				( attribute "PACK_TYPE" "0402"
					( Origin gFrontEnd )
				)
				( attribute "PART_NUMBER" "G21796-003"
					( Origin gFrontEnd )
				)
				( attribute "PHYS_PAGE" "133"
					( Origin gFrontEnd )
				)
				( attribute "ROOM" "SB"
					( Origin gFrontEnd )
				)
				( attribute "ROT" "0"
					( Origin gFrontEnd )
				)
				( attribute "SEC" "1"
					( Origin gFrontEnd )
				)
				( attribute "SEC_TYPE" "0402"
					( Origin gFrontEnd )
				)
				( attribute "TOLERANCE" "1%"
					( Origin gFrontEnd )
				)
				( attribute "VALUE" "1.5K"
					( Origin gFrontEnd )
				)
				( attribute "VER" "1"
					( Origin gFrontEnd )
				)
				( attribute "WATTAGE" "1/16W"
					( Origin gFrontEnd )
				)
				( attribute "XY" "(-375,2475)"
					( Origin gFrontEnd )
				)
				( attribute "CHIPS_PART_NAME" "RES"
					( Origin gPackager )
				)
				( attribute "CDS_PART_NAME" "RES_0402-1.5K,1%,1/16W,CHIP,G2A"
					( Origin gPackager )
				)
				( objectStatus "R2N29" )
				( pin "a"
					( attribute "PN" "1"
						( Origin gPackager )
					)
					( objectStatus "R2N29.1" )
				)
				( pin "b"
					( attribute "PN" "2"
						( Origin gPackager )
					)
					( objectStatus "R2N29.2" )
				)
			)
			( gate "@baseboard_fab2_lib.baseboard_fab2(sch_1):page133_i355"
				( attribute "CDS_LIB" "mstr_discrete"
					( Origin gPackager )
				)
				( attribute "CDS_LOCATION" "R8E3"
					( Origin gPackager )
				)
				( attribute "CDS_SEC" "1"
					( Origin gPackager )
				)
				( attribute "LOCATION" "R8E3"
					( Origin gFrontEnd )
				)
				( attribute "MATERIAL" "CHIP"
					( Origin gFrontEnd )
				)
				( attribute "PACK_TYPE" "0402"
					( Origin gFrontEnd )
				)
				( attribute "PART_NUMBER" "G21796-016"
					( Origin gFrontEnd )
				)
				( attribute "PHYS_PAGE" "133"
					( Origin gFrontEnd )
				)
				( attribute "ROOM" "SB"
					( Origin gFrontEnd )
				)
				( attribute "ROT" "0"
					( Origin gFrontEnd )
				)
				( attribute "SEC" "1"
					( Origin gFrontEnd )
				)
				( attribute "SEC_TYPE" "0402"
					( Origin gFrontEnd )
				)
				( attribute "TOLERANCE" "1%"
					( Origin gFrontEnd )
				)
				( attribute "VALUE" "10.0K"
					( Origin gFrontEnd )
				)
				( attribute "VER" "1"
					( Origin gFrontEnd )
				)
				( attribute "WATTAGE" "1/16W"
					( Origin gFrontEnd )
				)
				( attribute "XY" "(-4700,3475)"
					( Origin gFrontEnd )
				)
				( attribute "CHIPS_PART_NAME" "RES"
					( Origin gPackager )
				)
				( attribute "CDS_PART_NAME" "RES_0402-10.0K,1%,1/16W,CHIP,GA"
					( Origin gPackager )
				)
				( objectStatus "R8E3" )
				( pin "a"
					( attribute "PN" "1"
						( Origin gPackager )
					)
					( objectStatus "R8E3.1" )
				)
				( pin "b"
					( attribute "PN" "2"
						( Origin gPackager )
					)
					( objectStatus "R8E3.2" )
				)
			)
			( gate "@baseboard_fab2_lib.baseboard_fab2(sch_1):page133_i356"
				( attribute "CDS_LIB" "mstr_discrete"
					( Origin gPackager )
				)
				( attribute "CDS_LOCATION" "R7D44"
					( Origin gPackager )
				)
				( attribute "CDS_SEC" "1"
					( Origin gPackager )
				)
				( attribute "LOCATION" "R7D44"
					( Origin gFrontEnd )
				)
				( attribute "MATERIAL" "CHIP"
					( Origin gFrontEnd )
				)
				( attribute "PACK_TYPE" "0402"
					( Origin gFrontEnd )
				)
				( attribute "PART_NUMBER" "G21796-072"
					( Origin gFrontEnd )
				)
				( attribute "PHYS_PAGE" "133"
					( Origin gFrontEnd )
				)
				( attribute "ROOM" "SB_PU_PD"
					( Origin gFrontEnd )
				)
				( attribute "ROT" "0"
					( Origin gFrontEnd )
				)
				( attribute "SEC" "1"
					( Origin gFrontEnd )
				)
				( attribute "SEC_TYPE" "0402"
					( Origin gFrontEnd )
				)
				( attribute "TOLERANCE" "1%"
					( Origin gFrontEnd )
				)
				( attribute "VALUE" "4.75K"
					( Origin gFrontEnd )
				)
				( attribute "VER" "1"
					( Origin gFrontEnd )
				)
				( attribute "WATTAGE" "1/16W"
					( Origin gFrontEnd )
				)
				( attribute "XY" "(-375,3725)"
					( Origin gFrontEnd )
				)
				( attribute "CHIPS_PART_NAME" "RES"
					( Origin gPackager )
				)
				( attribute "CDS_PART_NAME" "RES_0402-4.75K,1%,1/16W,CHIP,GA"
					( Origin gPackager )
				)
				( objectStatus "R7D44" )
				( pin "a"
					( attribute "PN" "1"
						( Origin gPackager )
					)
					( objectStatus "R7D44.1" )
				)
				( pin "b"
					( attribute "PN" "2"
						( Origin gPackager )
					)
					( objectStatus "R7D44.2" )
				)
			)
			( gate "@baseboard_fab2_lib.baseboard_fab2(sch_1):page133_i357"
				( attribute "CDS_LIB" "mstr_discrete"
					( Origin gPackager )
				)
				( attribute "CDS_LOCATION" "R3P53"
					( Origin gPackager )
				)
				( attribute "CDS_SEC" "1"
					( Origin gPackager )
				)
				( attribute "LOCATION" "R3P53"
					( Origin gFrontEnd )
				)
				( attribute "MATERIAL" "CHIP"
					( Origin gFrontEnd )
				)
				( attribute "PACK_TYPE" "0402"
					( Origin gFrontEnd )
				)
				( attribute "PART_NUMBER" "G21796-072"
					( Origin gFrontEnd )
				)
				( attribute "PHYS_PAGE" "133"
					( Origin gFrontEnd )
				)
				( attribute "ROOM" "SB_PU_PD"
					( Origin gFrontEnd )
				)
				( attribute "ROT" "0"
					( Origin gFrontEnd )
				)
				( attribute "SEC" "1"
					( Origin gFrontEnd )
				)
				( attribute "SEC_TYPE" "0402"
					( Origin gFrontEnd )
				)
				( attribute "TOLERANCE" "1%"
					( Origin gFrontEnd )
				)
				( attribute "VALUE" "4.75K"
					( Origin gFrontEnd )
				)
				( attribute "VER" "1"
					( Origin gFrontEnd )
				)
				( attribute "WATTAGE" "1/16W"
					( Origin gFrontEnd )
				)
				( attribute "XY" "(-375,3525)"
					( Origin gFrontEnd )
				)
				( attribute "CHIPS_PART_NAME" "RES"
					( Origin gPackager )
				)
				( attribute "CDS_PART_NAME" "RES_0402-4.75K,1%,1/16W,CHIP,GA"
					( Origin gPackager )
				)
				( objectStatus "R3P53" )
				( pin "a"
					( attribute "PN" "1"
						( Origin gPackager )
					)
					( objectStatus "R3P53.1" )
				)
				( pin "b"
					( attribute "PN" "2"
						( Origin gPackager )
					)
					( objectStatus "R3P53.2" )
				)
			)
			( gate "@baseboard_fab2_lib.baseboard_fab2(sch_1):page133_i360"
				( attribute "BOM_COST" "SB"
					( Origin gFrontEnd )
				)
				( attribute "CDS_LIB" "mstr_discrete"
					( Origin gPackager )
				)
				( attribute "CDS_LOCATION" "R2P22"
					( Origin gPackager )
				)
				( attribute "CDS_SEC" "1"
					( Origin gPackager )
				)
				( attribute "LOCATION" "R2P22"
					( Origin gFrontEnd )
				)
				( attribute "MATERIAL" "CHIP"
					( Origin gFrontEnd )
				)
				( attribute "PACK_TYPE" "0402"
					( Origin gFrontEnd )
				)
				( attribute "PART_NUMBER" "G21796-016"
					( Origin gFrontEnd )
				)
				( attribute "PHYS_PAGE" "133"
					( Origin gFrontEnd )
				)
				( attribute "ROOM" "SB"
					( Origin gFrontEnd )
				)
				( attribute "ROT" "0"
					( Origin gFrontEnd )
				)
				( attribute "SEC" "1"
					( Origin gFrontEnd )
				)
				( attribute "SEC_TYPE" "0402"
					( Origin gFrontEnd )
				)
				( attribute "TOLERANCE" "1%"
					( Origin gFrontEnd )
				)
				( attribute "VALUE" "10.0K"
					( Origin gFrontEnd )
				)
				( attribute "VER" "1"
					( Origin gFrontEnd )
				)
				( attribute "WATTAGE" "1/16W"
					( Origin gFrontEnd )
				)
				( attribute "XY" "(-4800,1500)"
					( Origin gFrontEnd )
				)
				( attribute "CHIPS_PART_NAME" "RES"
					( Origin gPackager )
				)
				( attribute "CDS_PART_NAME" "RES_0402-10.0K,1%,1/16W,CHIP,GA"
					( Origin gPackager )
				)
				( objectStatus "R2P22" )
				( pin "a"
					( attribute "PN" "1"
						( Origin gPackager )
					)
					( objectStatus "R2P22.1" )
				)
				( pin "b"
					( attribute "PN" "2"
						( Origin gPackager )
					)
					( objectStatus "R2P22.2" )
				)
			)
			( gate "@baseboard_fab2_lib.baseboard_fab2(sch_1):page133_i362"
				( attribute "BOM_COST" "SB"
					( Origin gFrontEnd )
				)
				( attribute "CDS_LIB" "mstr_discrete"
					( Origin gPackager )
				)
				( attribute "CDS_LOCATION" "R8D44"
					( Origin gPackager )
				)
				( attribute "CDS_SEC" "1"
					( Origin gPackager )
				)
				( attribute "LOCATION" "R8D44"
					( Origin gFrontEnd )
				)
				( attribute "MATERIAL" "CHIP"
					( Origin gFrontEnd )
				)
				( attribute "PACK_TYPE" "0402"
					( Origin gFrontEnd )
				)
				( attribute "PART_NUMBER" "G21796-016"
					( Origin gFrontEnd )
				)
				( attribute "PHYS_PAGE" "133"
					( Origin gFrontEnd )
				)
				( attribute "ROOM" "SB"
					( Origin gFrontEnd )
				)
				( attribute "ROT" "0"
					( Origin gFrontEnd )
				)
				( attribute "SEC" "1"
					( Origin gFrontEnd )
				)
				( attribute "SEC_TYPE" "0402"
					( Origin gFrontEnd )
				)
				( attribute "TOLERANCE" "1%"
					( Origin gFrontEnd )
				)
				( attribute "VALUE" "10.0K"
					( Origin gFrontEnd )
				)
				( attribute "VER" "1"
					( Origin gFrontEnd )
				)
				( attribute "WATTAGE" "1/16W"
					( Origin gFrontEnd )
				)
				( attribute "XY" "(-2475,2450)"
					( Origin gFrontEnd )
				)
				( attribute "CHIPS_PART_NAME" "RES"
					( Origin gPackager )
				)
				( attribute "CDS_PART_NAME" "RES_0402-10.0K,1%,1/16W,CHIP,GA"
					( Origin gPackager )
				)
				( objectStatus "R8D44" )
				( pin "a"
					( attribute "PN" "1"
						( Origin gPackager )
					)
					( objectStatus "R8D44.1" )
				)
				( pin "b"
					( attribute "PN" "2"
						( Origin gPackager )
					)
					( objectStatus "R8D44.2" )
				)
			)
			( gate "@baseboard_fab2_lib.baseboard_fab2(sch_1):page134_i3"
				( attribute "BOM_COST" "SB"
					( Origin gFrontEnd )
				)
				( attribute "CDS_LIB" "mstr_discrete"
					( Origin gPackager )
				)
				( attribute "CDS_LOCATION" "R2P17"
					( Origin gPackager )
				)
				( attribute "CDS_SEC" "1"
					( Origin gPackager )
				)
				( attribute "LOCATION" "R2P17"
					( Origin gFrontEnd )
				)
				( attribute "MATERIAL" "CHIP"
					( Origin gFrontEnd )
				)
				( attribute "PACK_TYPE" "0402"
					( Origin gFrontEnd )
				)
				( attribute "PART_NUMBER" "G21796-072"
					( Origin gFrontEnd )
				)
				( attribute "PHYS_PAGE" "134"
					( Origin gFrontEnd )
				)
				( attribute "ROOM" "THERMTRIP_PCH"
					( Origin gFrontEnd )
				)
				( attribute "ROT" "0"
					( Origin gFrontEnd )
				)
				( attribute "SEC" "1"
					( Origin gFrontEnd )
				)
				( attribute "SEC_TYPE" "0402"
					( Origin gFrontEnd )
				)
				( attribute "TOLERANCE" "1%"
					( Origin gFrontEnd )
				)
				( attribute "VALUE" "4.75K"
					( Origin gFrontEnd )
				)
				( attribute "VER" "2"
					( Origin gFrontEnd )
				)
				( attribute "WATTAGE" "1/16W"
					( Origin gFrontEnd )
				)
				( attribute "XY" "(700,4925)"
					( Origin gFrontEnd )
				)
				( attribute "CHIPS_PART_NAME" "RES"
					( Origin gPackager )
				)
				( attribute "CDS_PART_NAME" "RES_0402-4.75K,1%,1/16W,CHIP,GA"
					( Origin gPackager )
				)
				( objectStatus "R2P17" )
				( pin "a"
					( attribute "PN" "1"
						( Origin gPackager )
					)
					( objectStatus "R2P17.1" )
				)
				( pin "b"
					( attribute "PN" "2"
						( Origin gPackager )
					)
					( objectStatus "R2P17.2" )
				)
			)
			( gate "@baseboard_fab2_lib.baseboard_fab2(sch_1):page134_i4"
				( attribute "BOM_COST" "SB"
					( Origin gFrontEnd )
				)
				( attribute "CDS_LIB" "mstr_discrete"
					( Origin gPackager )
				)
				( attribute "CDS_LOCATION" "Q8D2"
					( Origin gPackager )
				)
				( attribute "CDS_SEC" "1"
					( Origin gPackager )
				)
				( attribute "LOCATION" "Q8D2"
					( Origin gFrontEnd )
				)
				( attribute "MATERIAL" "FET"
					( Origin gFrontEnd )
				)
				( attribute "PACK_TYPE" "SOT23"
					( Origin gFrontEnd )
				)
				( attribute "PART_NUMBER" "C79254-001"
					( Origin gFrontEnd )
				)
				( attribute "PHYS_PAGE" "134"
					( Origin gFrontEnd )
				)
				( attribute "ROOM" "THERMTRIP_PCH"
					( Origin gFrontEnd )
				)
				( attribute "ROT" "0"
					( Origin gFrontEnd )
				)
				( attribute "SEC" "1"
					( Origin gFrontEnd )
				)
				( attribute "SEC_TYPE" "SOT23"
					( Origin gFrontEnd )
				)
				( attribute "VALUE" "2N7002"
					( Origin gFrontEnd )
				)
				( attribute "VER" "8"
					( Origin gFrontEnd )
				)
				( attribute "XY" "(700,4375)"
					( Origin gFrontEnd )
				)
				( attribute "CHIPS_PART_NAME" "FET_N"
					( Origin gPackager )
				)
				( attribute "CDS_PART_NAME" "FET_N_SOT23-2N7002,FET,C79254-A"
					( Origin gPackager )
				)
				( objectStatus "Q8D2" )
				( pin "drn"
					( attribute "PN" "3"
						( Origin gPackager )
					)
					( objectStatus "Q8D2.3" )
				)
				( pin "gate"
					( attribute "PN" "1"
						( Origin gPackager )
					)
					( objectStatus "Q8D2.1" )
				)
				( pin "src"
					( attribute "PN" "2"
						( Origin gPackager )
					)
					( objectStatus "Q8D2.2" )
				)
			)
			( gate "@baseboard_fab2_lib.baseboard_fab2(sch_1):page134_i9"
				( attribute "BOM_COST" "SB"
					( Origin gFrontEnd )
				)
				( attribute "CDS_LIB" "mstr_discrete"
					( Origin gPackager )
				)
				( attribute "CDS_LOCATION" "R7C21"
					( Origin gPackager )
				)
				( attribute "CDS_SEC" "1"
					( Origin gPackager )
				)
				( attribute "LOCATION" "R7C21"
					( Origin gFrontEnd )
				)
				( attribute "MATERIAL" "CHIP"
					( Origin gFrontEnd )
				)
				( attribute "PACK_TYPE" "0402"
					( Origin gFrontEnd )
				)
				( attribute "PART_NUMBER" "G21796-016"
					( Origin gFrontEnd )
				)
				( attribute "PHYS_PAGE" "134"
					( Origin gFrontEnd )
				)
				( attribute "ROOM" "THERMTRIP_PCH"
					( Origin gFrontEnd )
				)
				( attribute "ROT" "0"
					( Origin gFrontEnd )
				)
				( attribute "SEC" "1"
					( Origin gFrontEnd )
				)
				( attribute "SEC_TYPE" "0402"
					( Origin gFrontEnd )
				)
				( attribute "TOLERANCE" "1%"
					( Origin gFrontEnd )
				)
				( attribute "VALUE" "10.0K"
					( Origin gFrontEnd )
				)
				( attribute "VER" "2"
					( Origin gFrontEnd )
				)
				( attribute "WATTAGE" "1/16W"
					( Origin gFrontEnd )
				)
				( attribute "XY" "(-2875,4875)"
					( Origin gFrontEnd )
				)
				( attribute "CHIPS_PART_NAME" "RES"
					( Origin gPackager )
				)
				( attribute "CDS_PART_NAME" "RES_0402-10.0K,1%,1/16W,CHIP,GA"
					( Origin gPackager )
				)
				( objectStatus "R7C21" )
				( pin "a"
					( attribute "PN" "1"
						( Origin gPackager )
					)
					( objectStatus "R7C21.1" )
				)
				( pin "b"
					( attribute "PN" "2"
						( Origin gPackager )
					)
					( objectStatus "R7C21.2" )
				)
			)
			( gate "@baseboard_fab2_lib.baseboard_fab2(sch_1):page134_i10"
				( attribute "BOM_COST" "SB"
					( Origin gFrontEnd )
				)
				( attribute "CDS_LIB" "mstr_discrete"
					( Origin gPackager )
				)
				( attribute "CDS_LOCATION" "Q7D1"
					( Origin gPackager )
				)
				( attribute "CDS_SEC" "1"
					( Origin gPackager )
				)
				( attribute "LOCATION" "Q7D1"
					( Origin gFrontEnd )
				)
				( attribute "MATERIAL" "FET"
					( Origin gFrontEnd )
				)
				( attribute "PACK_TYPE" "SOT23"
					( Origin gFrontEnd )
				)
				( attribute "PART_NUMBER" "C79254-001"
					( Origin gFrontEnd )
				)
				( attribute "PHYS_PAGE" "134"
					( Origin gFrontEnd )
				)
				( attribute "ROOM" "THERMTRIP_PCH"
					( Origin gFrontEnd )
				)
				( attribute "ROT" "0"
					( Origin gFrontEnd )
				)
				( attribute "SEC" "1"
					( Origin gFrontEnd )
				)
				( attribute "SEC_TYPE" "SOT23"
					( Origin gFrontEnd )
				)
				( attribute "VALUE" "2N7002"
					( Origin gFrontEnd )
				)
				( attribute "VER" "8"
					( Origin gFrontEnd )
				)
				( attribute "XY" "(-2875,4400)"
					( Origin gFrontEnd )
				)
				( attribute "CHIPS_PART_NAME" "FET_N"
					( Origin gPackager )
				)
				( attribute "CDS_PART_NAME" "FET_N_SOT23-2N7002,FET,C79254-A"
					( Origin gPackager )
				)
				( objectStatus "Q7D1" )
				( pin "drn"
					( attribute "PN" "3"
						( Origin gPackager )
					)
					( objectStatus "Q7D1.3" )
				)
				( pin "gate"
					( attribute "PN" "1"
						( Origin gPackager )
					)
					( objectStatus "Q7D1.1" )
				)
				( pin "src"
					( attribute "PN" "2"
						( Origin gPackager )
					)
					( objectStatus "Q7D1.2" )
				)
			)
			( gate "@baseboard_fab2_lib.baseboard_fab2(sch_1):page134_i11"
				( attribute "CDS_LIB" "mstr_discrete"
					( Origin gPackager )
				)
				( attribute "CDS_LOCATION" "R7D18"
					( Origin gPackager )
				)
				( attribute "CDS_SEC" "1"
					( Origin gPackager )
				)
				( attribute "LOCATION" "R7D18"
					( Origin gFrontEnd )
				)
				( attribute "MATERIAL" "CHIP"
					( Origin gFrontEnd )
				)
				( attribute "PACK_TYPE" "0402"
					( Origin gFrontEnd )
				)
				( attribute "PART_NUMBER" "G21796-026"
					( Origin gFrontEnd )
				)
				( attribute "PHYS_PAGE" "134"
					( Origin gFrontEnd )
				)
				( attribute "ROOM" "PROC_SIDEBAND"
					( Origin gFrontEnd )
				)
				( attribute "ROT" "0"
					( Origin gFrontEnd )
				)
				( attribute "SEC" "1"
					( Origin gFrontEnd )
				)
				( attribute "SEC_TYPE" "0402"
					( Origin gFrontEnd )
				)
				( attribute "TOLERANCE" "1%"
					( Origin gFrontEnd )
				)
				( attribute "VALUE" "1.00K"
					( Origin gFrontEnd )
				)
				( attribute "VER" "1"
					( Origin gFrontEnd )
				)
				( attribute "WATTAGE" "1/16W"
					( Origin gFrontEnd )
				)
				( attribute "XY" "(-3950,4300)"
					( Origin gFrontEnd )
				)
				( attribute "CHIPS_PART_NAME" "RES"
					( Origin gPackager )
				)
				( attribute "CDS_PART_NAME" "RES_0402-1.00K,1%,1/16W,CHIP,GA"
					( Origin gPackager )
				)
				( objectStatus "R7D18" )
				( pin "a"
					( attribute "PN" "1"
						( Origin gPackager )
					)
					( objectStatus "R7D18.1" )
				)
				( pin "b"
					( attribute "PN" "2"
						( Origin gPackager )
					)
					( objectStatus "R7D18.2" )
				)
			)
			( gate "@baseboard_fab2_lib.baseboard_fab2(sch_1):page135_i107"
				( attribute "BOM_COST" "CPLD"
					( Origin gFrontEnd )
				)
				( attribute "CDS_LIB" "mstr_discrete"
					( Origin gPackager )
				)
				( attribute "CDS_LOCATION" "R2P19"
					( Origin gPackager )
				)
				( attribute "CDS_SEC" "1"
					( Origin gPackager )
				)
				( attribute "LOCATION" "R2P19"
					( Origin gFrontEnd )
				)
				( attribute "MATERIAL" "CHIP"
					( Origin gFrontEnd )
				)
				( attribute "PACK_TYPE" "0402"
					( Origin gFrontEnd )
				)
				( attribute "PART_NUMBER" "G21796-016"
					( Origin gFrontEnd )
				)
				( attribute "PHYS_PAGE" "135"
					( Origin gFrontEnd )
				)
				( attribute "ROOM" "CPLD"
					( Origin gFrontEnd )
				)
				( attribute "ROT" "0"
					( Origin gFrontEnd )
				)
				( attribute "SEC" "1"
					( Origin gFrontEnd )
				)
				( attribute "SEC_TYPE" "0402"
					( Origin gFrontEnd )
				)
				( attribute "TOLERANCE" "1%"
					( Origin gFrontEnd )
				)
				( attribute "VALUE" "10.0K"
					( Origin gFrontEnd )
				)
				( attribute "VER" "2"
					( Origin gFrontEnd )
				)
				( attribute "WATTAGE" "1/16W"
					( Origin gFrontEnd )
				)
				( attribute "XY" "(200,2225)"
					( Origin gFrontEnd )
				)
				( attribute "CHIPS_PART_NAME" "RES"
					( Origin gPackager )
				)
				( attribute "CDS_PART_NAME" "RES_0402-10.0K,1%,1/16W,CHIP,GA"
					( Origin gPackager )
				)
				( objectStatus "R2P19" )
				( pin "a"
					( attribute "PN" "1"
						( Origin gPackager )
					)
					( objectStatus "R2P19.1" )
				)
				( pin "b"
					( attribute "PN" "2"
						( Origin gPackager )
					)
					( objectStatus "R2P19.2" )
				)
			)
			( gate "@baseboard_fab2_lib.baseboard_fab2(sch_1):page135_i112"
				( attribute "CDS_LIB" "mstr_discrete"
					( Origin gPackager )
				)
				( attribute "CDS_LOCATION" "R2N23"
					( Origin gPackager )
				)
				( attribute "CDS_SEC" "1"
					( Origin gPackager )
				)
				( attribute "LOCATION" "R2N23"
					( Origin gFrontEnd )
				)
				( attribute "MATERIAL" "CHIP"
					( Origin gFrontEnd )
				)
				( attribute "PACK_TYPE" "0402"
					( Origin gFrontEnd )
				)
				( attribute "PART_NUMBER" "G21796-016"
					( Origin gFrontEnd )
				)
				( attribute "PHYS_PAGE" "135"
					( Origin gFrontEnd )
				)
				( attribute "ROOM" "SB"
					( Origin gFrontEnd )
				)
				( attribute "ROT" "0"
					( Origin gFrontEnd )
				)
				( attribute "SEC" "1"
					( Origin gPackager )
				)
				( attribute "TOLERANCE" "1%"
					( Origin gFrontEnd )
				)
				( attribute "VALUE" "10.0K"
					( Origin gFrontEnd )
				)
				( attribute "VER" "2"
					( Origin gFrontEnd )
				)
				( attribute "WATTAGE" "1/16W"
					( Origin gFrontEnd )
				)
				( attribute "XY" "(-2150,4775)"
					( Origin gFrontEnd )
				)
				( attribute "CHIPS_PART_NAME" "RES"
					( Origin gPackager )
				)
				( attribute "CDS_PART_NAME" "RES_0402-10.0K,1%,1/16W,CHIP,GA"
					( Origin gPackager )
				)
				( objectStatus "R2N23" )
				( pin "a"
					( attribute "PN" "1"
						( Origin gPackager )
					)
					( objectStatus "R2N23.1" )
				)
				( pin "b"
					( attribute "PN" "2"
						( Origin gPackager )
					)
					( objectStatus "R2N23.2" )
				)
			)
			( gate "@baseboard_fab2_lib.baseboard_fab2(sch_1):page135_i113"
				( attribute "CDS_LIB" "mstr_discrete"
					( Origin gPackager )
				)
				( attribute "CDS_LOCATION" "R2N24"
					( Origin gPackager )
				)
				( attribute "CDS_SEC" "1"
					( Origin gPackager )
				)
				( attribute "LOCATION" "R2N24"
					( Origin gFrontEnd )
				)
				( attribute "MATERIAL" "EMPTY"
					( Origin gFrontEnd )
				)
				( attribute "PACK_TYPE" "0402"
					( Origin gFrontEnd )
				)
				( attribute "PART_NUMBER" "G21796-026"
					( Origin gFrontEnd )
				)
				( attribute "PHYS_PAGE" "135"
					( Origin gFrontEnd )
				)
				( attribute "ROOM" "SB"
					( Origin gFrontEnd )
				)
				( attribute "ROT" "0"
					( Origin gFrontEnd )
				)
				( attribute "SEC" "1"
					( Origin gFrontEnd )
				)
				( attribute "SEC_TYPE" "0402"
					( Origin gFrontEnd )
				)
				( attribute "TOLERANCE" "1%"
					( Origin gFrontEnd )
				)
				( attribute "VALUE" "1.00K"
					( Origin gFrontEnd )
				)
				( attribute "VER" "2"
					( Origin gFrontEnd )
				)
				( attribute "WATTAGE" "1/16W"
					( Origin gFrontEnd )
				)
				( attribute "XY" "(-2150,4325)"
					( Origin gFrontEnd )
				)
				( attribute "CHIPS_PART_NAME" "RES"
					( Origin gPackager )
				)
				( attribute "CDS_PART_NAME" "RES_0402-1.00K,1%,1/16W,EMPTY,A"
					( Origin gPackager )
				)
				( objectStatus "R2N24" )
				( pin "a"
					( attribute "PN" "1"
						( Origin gPackager )
					)
					( objectStatus "R2N24.1" )
				)
				( pin "b"
					( attribute "PN" "2"
						( Origin gPackager )
					)
					( objectStatus "R2N24.2" )
				)
			)
			( gate "@baseboard_fab2_lib.baseboard_fab2(sch_1):page135_i117"
				( attribute "BOM_COST" "SB"
					( Origin gFrontEnd )
				)
				( attribute "CDS_LIB" "mstr_discrete"
					( Origin gPackager )
				)
				( attribute "CDS_LOCATION" "R9A12"
					( Origin gPackager )
				)
				( attribute "CDS_SEC" "1"
					( Origin gPackager )
				)
				( attribute "LOCATION" "R9A12"
					( Origin gFrontEnd )
				)
				( attribute "MATERIAL" "CHIP"
					( Origin gFrontEnd )
				)
				( attribute "PACK_TYPE" "0402"
					( Origin gFrontEnd )
				)
				( attribute "PART_NUMBER" "G21796-112"
					( Origin gFrontEnd )
				)
				( attribute "PHYS_PAGE" "135"
					( Origin gFrontEnd )
				)
				( attribute "ROOM" "SB"
					( Origin gFrontEnd )
				)
				( attribute "ROT" "1"
					( Origin gFrontEnd )
				)
				( attribute "SEC" "1"
					( Origin gPackager )
				)
				( attribute "TOLERANCE" "1%"
					( Origin gFrontEnd )
				)
				( attribute "VALUE" "2.21K"
					( Origin gFrontEnd )
				)
				( attribute "VER" "1"
					( Origin gFrontEnd )
				)
				( attribute "WATTAGE" "1/16W"
					( Origin gFrontEnd )
				)
				( attribute "XY" "(-3875,4900)"
					( Origin gFrontEnd )
				)
				( attribute "CHIPS_PART_NAME" "RES"
					( Origin gPackager )
				)
				( attribute "CDS_PART_NAME" "RES_0402-2.21K,1%,1/16W,CHIP,GA"
					( Origin gPackager )
				)
				( objectStatus "R9A12" )
				( pin "a"
					( attribute "PN" "1"
						( Origin gPackager )
					)
					( objectStatus "R9A12.1" )
				)
				( pin "b"
					( attribute "PN" "2"
						( Origin gPackager )
					)
					( objectStatus "R9A12.2" )
				)
			)
			( gate "@baseboard_fab2_lib.baseboard_fab2(sch_1):page135_i118"
				( attribute "BOM_COST" "SB"
					( Origin gFrontEnd )
				)
				( attribute "CDS_LIB" "mstr_discrete"
					( Origin gPackager )
				)
				( attribute "CDS_LOCATION" "R9A13"
					( Origin gPackager )
				)
				( attribute "CDS_SEC" "1"
					( Origin gPackager )
				)
				( attribute "LOCATION" "R9A13"
					( Origin gFrontEnd )
				)
				( attribute "MATERIAL" "CHIP"
					( Origin gFrontEnd )
				)
				( attribute "PACK_TYPE" "0402"
					( Origin gFrontEnd )
				)
				( attribute "PART_NUMBER" "G21796-074"
					( Origin gFrontEnd )
				)
				( attribute "PHYS_PAGE" "135"
					( Origin gFrontEnd )
				)
				( attribute "ROOM" "SB"
					( Origin gFrontEnd )
				)
				( attribute "ROT" "0"
					( Origin gFrontEnd )
				)
				( attribute "SEC" "1"
					( Origin gPackager )
				)
				( attribute "TOLERANCE" "1%"
					( Origin gFrontEnd )
				)
				( attribute "VALUE" "33.2"
					( Origin gFrontEnd )
				)
				( attribute "VER" "1"
					( Origin gFrontEnd )
				)
				( attribute "WATTAGE" "1/16W"
					( Origin gFrontEnd )
				)
				( attribute "XY" "(-3650,4500)"
					( Origin gFrontEnd )
				)
				( attribute "CHIPS_PART_NAME" "RES"
					( Origin gPackager )
				)
				( attribute "CDS_PART_NAME" "RES_0402-33.2,1%,1/16W,CHIP,G2A"
					( Origin gPackager )
				)
				( objectStatus "R9A13" )
				( pin "a"
					( attribute "PN" "1"
						( Origin gPackager )
					)
					( objectStatus "R9A13.1" )
				)
				( pin "b"
					( attribute "PN" "2"
						( Origin gPackager )
					)
					( objectStatus "R9A13.2" )
				)
			)
			( gate "@baseboard_fab2_lib.baseboard_fab2(sch_1):page135_i120"
				( attribute "BOM_COST" "SB"
					( Origin gFrontEnd )
				)
				( attribute "CDS_LIB" "mstr_discrete"
					( Origin gPackager )
				)
				( attribute "CDS_LOCATION" "R8D21"
					( Origin gPackager )
				)
				( attribute "CDS_SEC" "1"
					( Origin gPackager )
				)
				( attribute "LOCATION" "R8D21"
					( Origin gFrontEnd )
				)
				( attribute "MATERIAL" "CHIP"
					( Origin gFrontEnd )
				)
				( attribute "PACK_TYPE" "0402"
					( Origin gFrontEnd )
				)
				( attribute "PART_NUMBER" "G21796-026"
					( Origin gFrontEnd )
				)
				( attribute "PHYS_PAGE" "135"
					( Origin gFrontEnd )
				)
				( attribute "ROOM" "SB"
					( Origin gFrontEnd )
				)
				( attribute "ROT" "0"
					( Origin gFrontEnd )
				)
				( attribute "SEC" "1"
					( Origin gFrontEnd )
				)
				( attribute "SEC_TYPE" "0402"
					( Origin gFrontEnd )
				)
				( attribute "TOLERANCE" "1%"
					( Origin gFrontEnd )
				)
				( attribute "VALUE" "1.00K"
					( Origin gFrontEnd )
				)
				( attribute "VER" "2"
					( Origin gFrontEnd )
				)
				( attribute "WATTAGE" "1/16W"
					( Origin gFrontEnd )
				)
				( attribute "XY" "(-225,2250)"
					( Origin gFrontEnd )
				)
				( attribute "CHIPS_PART_NAME" "RES"
					( Origin gPackager )
				)
				( attribute "CDS_PART_NAME" "RES_0402-1.00K,1%,1/16W,CHIP,GA"
					( Origin gPackager )
				)
				( objectStatus "R8D21" )
				( pin "a"
					( attribute "PN" "1"
						( Origin gPackager )
					)
					( objectStatus "R8D21.1" )
				)
				( pin "b"
					( attribute "PN" "2"
						( Origin gPackager )
					)
					( objectStatus "R8D21.2" )
				)
			)
			( gate "@baseboard_fab2_lib.baseboard_fab2(sch_1):page135_i121"
				( attribute "BOM_COST" "DEBUG"
					( Origin gFrontEnd )
				)
				( attribute "CDS_LIB" "mstr_discrete"
					( Origin gPackager )
				)
				( attribute "CDS_LOCATION" "R7D30"
					( Origin gPackager )
				)
				( attribute "CDS_SEC" "1"
					( Origin gPackager )
				)
				( attribute "LOCATION" "R7D30"
					( Origin gFrontEnd )
				)
				( attribute "MATERIAL" "CHIP"
					( Origin gFrontEnd )
				)
				( attribute "PACK_TYPE" "0402"
					( Origin gFrontEnd )
				)
				( attribute "PART_NUMBER" "G21796-072"
					( Origin gFrontEnd )
				)
				( attribute "PHYS_PAGE" "135"
					( Origin gFrontEnd )
				)
				( attribute "ROOM" "UART_MUX"
					( Origin gFrontEnd )
				)
				( attribute "ROT" "0"
					( Origin gFrontEnd )
				)
				( attribute "SEC" "1"
					( Origin gFrontEnd )
				)
				( attribute "SEC_TYPE" "0402"
					( Origin gFrontEnd )
				)
				( attribute "TOLERANCE" "1%"
					( Origin gFrontEnd )
				)
				( attribute "VALUE" "4.75K"
					( Origin gFrontEnd )
				)
				( attribute "VER" "2"
					( Origin gFrontEnd )
				)
				( attribute "WATTAGE" "1/16W"
					( Origin gFrontEnd )
				)
				( attribute "XY" "(-1525,2250)"
					( Origin gFrontEnd )
				)
				( attribute "CHIPS_PART_NAME" "RES"
					( Origin gPackager )
				)
				( attribute "CDS_PART_NAME" "RES_0402-4.75K,1%,1/16W,CHIP,GA"
					( Origin gPackager )
				)
				( objectStatus "R7D30" )
				( pin "a"
					( attribute "PN" "1"
						( Origin gPackager )
					)
					( objectStatus "R7D30.1" )
				)
				( pin "b"
					( attribute "PN" "2"
						( Origin gPackager )
					)
					( objectStatus "R7D30.2" )
				)
			)
			( gate "@baseboard_fab2_lib.baseboard_fab2(sch_1):page135_i124"
				( attribute "BOM_COST" "SB"
					( Origin gFrontEnd )
				)
				( attribute "CDS_LIB" "mstr_conn"
					( Origin gPackager )
				)
				( attribute "CDS_LOCATION" "J8G2"
					( Origin gPackager )
				)
				( attribute "CDS_SEC" "1"
					( Origin gPackager )
				)
				( attribute "LOCATION" "J8G2"
					( Origin gFrontEnd )
				)
				( attribute "MATERIAL" "CONN"
					( Origin gFrontEnd )
				)
				( attribute "PACK_TYPE" "PIP"
					( Origin gFrontEnd )
				)
				( attribute "PART_NUMBER" "C73564-003"
					( Origin gFrontEnd )
				)
				( attribute "PHYS_PAGE" "135"
					( Origin gFrontEnd )
				)
				( attribute "ROOM" "SB"
					( Origin gFrontEnd )
				)
				( attribute "ROT" "0"
					( Origin gFrontEnd )
				)
				( attribute "SEC" "1"
					( Origin gFrontEnd )
				)
				( attribute "SEC_TYPE" "PIP"
					( Origin gFrontEnd )
				)
				( attribute "VER" "1"
					( Origin gFrontEnd )
				)
				( attribute "XY" "(-775,1900)"
					( Origin gFrontEnd )
				)
				( attribute "CHIPS_PART_NAME" "CONN12_C73564003"
					( Origin gPackager )
				)
				( attribute "CDS_PART_NAME" "CONN12_C73564003_PIP-CONN,C735A"
					( Origin gPackager )
				)
				( objectStatus "J8G2" )
				( pin "io1"
					( attribute "PN" "1"
						( Origin gPackager )
					)
					( objectStatus "J8G2.1" )
				)
				( pin "io2"
					( attribute "PN" "2"
						( Origin gPackager )
					)
					( objectStatus "J8G2.2" )
				)
				( pin "io3"
					( attribute "PN" "3"
						( Origin gPackager )
					)
					( objectStatus "J8G2.3" )
				)
				( pin "io4"
					( attribute "PN" "4"
						( Origin gPackager )
					)
					( objectStatus "J8G2.4" )
				)
				( pin "io5"
					( attribute "PN" "5"
						( Origin gPackager )
					)
					( objectStatus "J8G2.5" )
				)
				( pin "io6"
					( attribute "PN" "6"
						( Origin gPackager )
					)
					( objectStatus "J8G2.6" )
				)
				( pin "io7"
					( attribute "PN" "7"
						( Origin gPackager )
					)
					( objectStatus "J8G2.7" )
				)
				( pin "io8"
					( attribute "PN" "8"
						( Origin gPackager )
					)
					( objectStatus "J8G2.8" )
				)
				( pin "io9"
					( attribute "PN" "9"
						( Origin gPackager )
					)
					( objectStatus "J8G2.9" )
				)
				( pin "io10"
					( attribute "PN" "10"
						( Origin gPackager )
					)
					( objectStatus "J8G2.10" )
				)
				( pin "io11"
					( attribute "PN" "11"
						( Origin gPackager )
					)
					( objectStatus "J8G2.11" )
				)
				( pin "io12"
					( attribute "PN" "12"
						( Origin gPackager )
					)
					( objectStatus "J8G2.12" )
				)
			)
			( gate "@baseboard_fab2_lib.baseboard_fab2(sch_1):page135_i129"
				( attribute "BOM_COST" "SB"
					( Origin gFrontEnd )
				)
				( attribute "CDS_LIB" "mstr_discrete"
					( Origin gPackager )
				)
				( attribute "CDS_LOCATION" "R9A16"
					( Origin gPackager )
				)
				( attribute "CDS_SEC" "1"
					( Origin gPackager )
				)
				( attribute "LOCATION" "R9A16"
					( Origin gFrontEnd )
				)
				( attribute "MATERIAL" "CHIP"
					( Origin gFrontEnd )
				)
				( attribute "PACK_TYPE" "0402"
					( Origin gFrontEnd )
				)
				( attribute "PART_NUMBER" "G21796-112"
					( Origin gFrontEnd )
				)
				( attribute "PHYS_PAGE" "135"
					( Origin gFrontEnd )
				)
				( attribute "ROOM" "SB"
					( Origin gFrontEnd )
				)
				( attribute "ROT" "1"
					( Origin gFrontEnd )
				)
				( attribute "SEC" "1"
					( Origin gPackager )
				)
				( attribute "TOLERANCE" "1%"
					( Origin gFrontEnd )
				)
				( attribute "VALUE" "2.21K"
					( Origin gFrontEnd )
				)
				( attribute "VER" "1"
					( Origin gFrontEnd )
				)
				( attribute "WATTAGE" "1/16W"
					( Origin gFrontEnd )
				)
				( attribute "XY" "(-4275,4900)"
					( Origin gFrontEnd )
				)
				( attribute "CHIPS_PART_NAME" "RES"
					( Origin gPackager )
				)
				( attribute "CDS_PART_NAME" "RES_0402-2.21K,1%,1/16W,CHIP,GA"
					( Origin gPackager )
				)
				( objectStatus "R9A16" )
				( pin "a"
					( attribute "PN" "1"
						( Origin gPackager )
					)
					( objectStatus "R9A16.1" )
				)
				( pin "b"
					( attribute "PN" "2"
						( Origin gPackager )
					)
					( objectStatus "R9A16.2" )
				)
			)
			( gate "@baseboard_fab2_lib.baseboard_fab2(sch_1):page135_i131"
				( attribute "BOM_COST" "SB"
					( Origin gFrontEnd )
				)
				( attribute "CDS_LIB" "mstr_conn"
					( Origin gPackager )
				)
				( attribute "CDS_LOCATION" "J9A1"
					( Origin gPackager )
				)
				( attribute "CDS_SEC" "1"
					( Origin gPackager )
				)
				( attribute "LOCATION" "J9A1"
					( Origin gFrontEnd )
				)
				( attribute "MATERIAL" "CONN"
					( Origin gFrontEnd )
				)
				( attribute "PACK_TYPE" "PIP"
					( Origin gFrontEnd )
				)
				( attribute "PART_NUMBER" "D42317-002"
					( Origin gFrontEnd )
				)
				( attribute "PHYS_PAGE" "135"
					( Origin gFrontEnd )
				)
				( attribute "ROOM" "SB"
					( Origin gFrontEnd )
				)
				( attribute "ROT" "2"
					( Origin gFrontEnd )
				)
				( attribute "SEC" "1"
					( Origin gPackager )
				)
				( attribute "VER" "1"
					( Origin gFrontEnd )
				)
				( attribute "XY" "(-5075,4600)"
					( Origin gFrontEnd )
				)
				( attribute "CHIPS_PART_NAME" "CONN4_D42317002"
					( Origin gPackager )
				)
				( attribute "CDS_PART_NAME" "CONN4_D42317002_PIP-CONN,D4231A"
					( Origin gPackager )
				)
				( objectStatus "J9A1" )
				( pin "io1"
					( attribute "PN" "1"
						( Origin gPackager )
					)
					( objectStatus "J9A1.1" )
				)
				( pin "io2"
					( attribute "PN" "2"
						( Origin gPackager )
					)
					( objectStatus "J9A1.2" )
				)
				( pin "io3"
					( attribute "PN" "3"
						( Origin gPackager )
					)
					( objectStatus "J9A1.3" )
				)
				( pin "io4"
					( attribute "PN" "4"
						( Origin gPackager )
					)
					( objectStatus "J9A1.4" )
				)
			)
			( gate "@baseboard_fab2_lib.baseboard_fab2(sch_1):page136_i101"
				( attribute "CDS_LIB" "mstr_discrete"
					( Origin gPackager )
				)
				( attribute "CDS_LOCATION" "R7G26"
					( Origin gPackager )
				)
				( attribute "CDS_SEC" "1"
					( Origin gPackager )
				)
				( attribute "LOCATION" "R7G26"
					( Origin gFrontEnd )
				)
				( attribute "MATERIAL" "CHIP"
					( Origin gFrontEnd )
				)
				( attribute "PACK_TYPE" "0402"
					( Origin gFrontEnd )
				)
				( attribute "PART_NUMBER" "G21796-016"
					( Origin gFrontEnd )
				)
				( attribute "PHYS_PAGE" "136"
					( Origin gFrontEnd )
				)
				( attribute "ROOM" "SB"
					( Origin gFrontEnd )
				)
				( attribute "ROT" "0"
					( Origin gFrontEnd )
				)
				( attribute "SEC" "1"
					( Origin gFrontEnd )
				)
				( attribute "SEC_TYPE" "0402"
					( Origin gFrontEnd )
				)
				( attribute "TOLERANCE" "1%"
					( Origin gFrontEnd )
				)
				( attribute "VALUE" "10.0K"
					( Origin gFrontEnd )
				)
				( attribute "VER" "2"
					( Origin gFrontEnd )
				)
				( attribute "WATTAGE" "1/16W"
					( Origin gFrontEnd )
				)
				( attribute "XY" "(-2250,4800)"
					( Origin gFrontEnd )
				)
				( attribute "CHIPS_PART_NAME" "RES"
					( Origin gPackager )
				)
				( attribute "CDS_PART_NAME" "RES_0402-10.0K,1%,1/16W,CHIP,GA"
					( Origin gPackager )
				)
				( objectStatus "R7G26" )
				( pin "a"
					( attribute "PN" "1"
						( Origin gPackager )
					)
					( objectStatus "R7G26.1" )
				)
				( pin "b"
					( attribute "PN" "2"
						( Origin gPackager )
					)
					( objectStatus "R7G26.2" )
				)
			)
			( gate "@baseboard_fab2_lib.baseboard_fab2(sch_1):page136_i102"
				( attribute "BOM_COST" "SB"
					( Origin gFrontEnd )
				)
				( attribute "CDS_LIB" "mstr_discrete"
					( Origin gPackager )
				)
				( attribute "CDS_LOCATION" "R7G28"
					( Origin gPackager )
				)
				( attribute "CDS_SEC" "1"
					( Origin gPackager )
				)
				( attribute "LOCATION" "R7G28"
					( Origin gFrontEnd )
				)
				( attribute "MATERIAL" "CHIP"
					( Origin gFrontEnd )
				)
				( attribute "PACK_TYPE" "0402"
					( Origin gFrontEnd )
				)
				( attribute "PART_NUMBER" "G21796-026"
					( Origin gFrontEnd )
				)
				( attribute "PHYS_PAGE" "136"
					( Origin gFrontEnd )
				)
				( attribute "ROOM" "SB"
					( Origin gFrontEnd )
				)
				( attribute "ROT" "0"
					( Origin gFrontEnd )
				)
				( attribute "SEC" "1"
					( Origin gFrontEnd )
				)
				( attribute "SEC_TYPE" "0402"
					( Origin gFrontEnd )
				)
				( attribute "TOLERANCE" "1%"
					( Origin gFrontEnd )
				)
				( attribute "VALUE" "1.00K"
					( Origin gFrontEnd )
				)
				( attribute "VER" "2"
					( Origin gFrontEnd )
				)
				( attribute "WATTAGE" "1/16W"
					( Origin gFrontEnd )
				)
				( attribute "XY" "(-2250,3825)"
					( Origin gFrontEnd )
				)
				( attribute "CHIPS_PART_NAME" "RES"
					( Origin gPackager )
				)
				( attribute "CDS_PART_NAME" "RES_0402-1.00K,1%,1/16W,CHIP,GA"
					( Origin gPackager )
				)
				( objectStatus "R7G28" )
				( pin "a"
					( attribute "PN" "1"
						( Origin gPackager )
					)
					( objectStatus "R7G28.1" )
				)
				( pin "b"
					( attribute "PN" "2"
						( Origin gPackager )
					)
					( objectStatus "R7G28.2" )
				)
			)
			( gate "@baseboard_fab2_lib.baseboard_fab2(sch_1):page136_i126"
				( attribute "BOM_COST" "SB"
					( Origin gFrontEnd )
				)
				( attribute "CDS_LIB" "mstr_discrete"
					( Origin gPackager )
				)
				( attribute "CDS_LOCATION" "R8E20"
					( Origin gPackager )
				)
				( attribute "CDS_SEC" "1"
					( Origin gPackager )
				)
				( attribute "LOCATION" "R8E20"
					( Origin gFrontEnd )
				)
				( attribute "MATERIAL" "CHIP"
					( Origin gFrontEnd )
				)
				( attribute "PACK_TYPE" "0402"
					( Origin gFrontEnd )
				)
				( attribute "PART_NUMBER" "G21796-074"
					( Origin gFrontEnd )
				)
				( attribute "PHYS_PAGE" "136"
					( Origin gFrontEnd )
				)
				( attribute "ROOM" "SB"
					( Origin gFrontEnd )
				)
				( attribute "ROT" "0"
					( Origin gFrontEnd )
				)
				( attribute "SEC" "1"
					( Origin gFrontEnd )
				)
				( attribute "SEC_TYPE" "0402"
					( Origin gFrontEnd )
				)
				( attribute "TOLERANCE" "1%"
					( Origin gFrontEnd )
				)
				( attribute "VALUE" "33.2"
					( Origin gFrontEnd )
				)
				( attribute "VER" "1"
					( Origin gFrontEnd )
				)
				( attribute "WATTAGE" "1/16W"
					( Origin gFrontEnd )
				)
				( attribute "XY" "(1000,2300)"
					( Origin gFrontEnd )
				)
				( attribute "CHIPS_PART_NAME" "RES"
					( Origin gPackager )
				)
				( attribute "CDS_PART_NAME" "RES_0402-33.2,1%,1/16W,CHIP,G2A"
					( Origin gPackager )
				)
				( objectStatus "R8E20" )
				( pin "a"
					( attribute "PN" "1"
						( Origin gPackager )
					)
					( objectStatus "R8E20.1" )
				)
				( pin "b"
					( attribute "PN" "2"
						( Origin gPackager )
					)
					( objectStatus "R8E20.2" )
				)
			)
			( gate "@baseboard_fab2_lib.baseboard_fab2(sch_1):page136_i128"
				( attribute "BOM_COST" "SB"
					( Origin gFrontEnd )
				)
				( attribute "CDS_LIB" "dev_discrete"
					( Origin gPackager )
				)
				( attribute "CDS_LOCATION" "C8E8"
					( Origin gPackager )
				)
				( attribute "CDS_SEC" "1"
					( Origin gPackager )
				)
				( attribute "LOCATION" "C8E8"
					( Origin gFrontEnd )
				)
				( attribute "MATERIAL" "X7R"
					( Origin gFrontEnd )
				)
				( attribute "PACK_TYPE" "0402V"
					( Origin gFrontEnd )
				)
				( attribute "PART_NUMBER" "A36096-030"
					( Origin gFrontEnd )
				)
				( attribute "PHYS_PAGE" "136"
					( Origin gFrontEnd )
				)
				( attribute "ROOM" "SB"
					( Origin gFrontEnd )
				)
				( attribute "ROT" "0"
					( Origin gFrontEnd )
				)
				( attribute "SEC" "1"
					( Origin gFrontEnd )
				)
				( attribute "SEC_TYPE" "0402V"
					( Origin gFrontEnd )
				)
				( attribute "TOLERANCE" "10%"
					( Origin gFrontEnd )
				)
				( attribute "VALUE" "0.1UF"
					( Origin gFrontEnd )
				)
				( attribute "VER" "1"
					( Origin gFrontEnd )
				)
				( attribute "VOLTAGE" "16V"
					( Units "uVoltage" "V" 1.000000)
					( Origin gFrontEnd )
				)
				( attribute "XY" "(575,1575)"
					( Origin gFrontEnd )
				)
				( attribute "CHIPS_PART_NAME" "CAP_A"
					( Origin gPackager )
				)
				( attribute "CDS_PART_NAME" "CAP_A_0402V-0.1UF,16V,10%,X7R,A"
					( Origin gPackager )
				)
				( objectStatus "C8E8" )
				( pin "a"
					( attribute "PN" "1"
						( Origin gPackager )
					)
					( objectStatus "C8E8.1" )
				)
				( pin "b"
					( attribute "PN" "2"
						( Origin gPackager )
					)
					( objectStatus "C8E8.2" )
				)
			)
			( gate "@baseboard_fab2_lib.baseboard_fab2(sch_1):page136_i130"
				( attribute "BOM_COST" "SB"
					( Origin gFrontEnd )
				)
				( attribute "CDS_LIB" "mstr_ttl"
					( Origin gPackager )
				)
				( attribute "CDS_LOCATION" "U8E3"
					( Origin gPackager )
				)
				( attribute "CDS_SEC" "1"
					( Origin gPackager )
				)
				( attribute "LOCATION" "U8E3"
					( Origin gFrontEnd )
				)
				( attribute "MATERIAL" "IC"
					( Origin gFrontEnd )
				)
				( attribute "PACK_TYPE" "SOT"
					( Origin gFrontEnd )
				)
				( attribute "PART_NUMBER" "A79322-001"
					( Origin gFrontEnd )
				)
				( attribute "PHYS_PAGE" "136"
					( Origin gFrontEnd )
				)
				( attribute "ROOM" "SB"
					( Origin gFrontEnd )
				)
				( attribute "ROT" "0"
					( Origin gFrontEnd )
				)
				( attribute "SEC" "1"
					( Origin gFrontEnd )
				)
				( attribute "SEC_TYPE" "SOT"
					( Origin gFrontEnd )
				)
				( attribute "VALUE" "74HC1G126"
					( Origin gFrontEnd )
				)
				( attribute "VER" "1"
					( Origin gFrontEnd )
				)
				( attribute "XY" "(0,2300)"
					( Origin gFrontEnd )
				)
				( attribute "CHIPS_PART_NAME" "TTL1G126_A"
					( Origin gPackager )
				)
				( attribute "CDS_PART_NAME" "TTL1G126_A_SOT-74HC1G126,IC,A7B"
					( Origin gPackager )
				)
				( objectStatus "U8E3" )
				( pin "a"
					( attribute "PN" "2"
						( Origin gPackager )
					)
					( objectStatus "U8E3.2" )
				)
				( pin "oe"
					( attribute "PN" "1"
						( Origin gPackager )
					)
					( objectStatus "U8E3.1" )
				)
				( pin "y"
					( attribute "PN" "4"
						( Origin gPackager )
					)
					( objectStatus "U8E3.4" )
				)
			)
			( gate "@baseboard_fab2_lib.baseboard_fab2(sch_1):page136_i133"
				( attribute "CDS_LIB" "mstr_discrete"
					( Origin gPackager )
				)
				( attribute "CDS_LOCATION" "R8E14"
					( Origin gPackager )
				)
				( attribute "CDS_SEC" "1"
					( Origin gPackager )
				)
				( attribute "LOCATION" "R8E14"
					( Origin gFrontEnd )
				)
				( attribute "MATERIAL" "CHIP"
					( Origin gFrontEnd )
				)
				( attribute "PACK_TYPE" "0402"
					( Origin gFrontEnd )
				)
				( attribute "PART_NUMBER" "G21796-072"
					( Origin gFrontEnd )
				)
				( attribute "PHYS_PAGE" "136"
					( Origin gFrontEnd )
				)
				( attribute "ROOM" "SB"
					( Origin gFrontEnd )
				)
				( attribute "ROT" "0"
					( Origin gFrontEnd )
				)
				( attribute "SEC" "1"
					( Origin gFrontEnd )
				)
				( attribute "SEC_TYPE" "0402"
					( Origin gFrontEnd )
				)
				( attribute "TOLERANCE" "1%"
					( Origin gFrontEnd )
				)
				( attribute "VALUE" "4.75K"
					( Origin gFrontEnd )
				)
				( attribute "VER" "2"
					( Origin gFrontEnd )
				)
				( attribute "WATTAGE" "1/16W"
					( Origin gFrontEnd )
				)
				( attribute "XY" "(-550,1900)"
					( Origin gFrontEnd )
				)
				( attribute "CHIPS_PART_NAME" "RES"
					( Origin gPackager )
				)
				( attribute "CDS_PART_NAME" "RES_0402-4.75K,1%,1/16W,CHIP,GA"
					( Origin gPackager )
				)
				( objectStatus "R8E14" )
				( pin "a"
					( attribute "PN" "1"
						( Origin gPackager )
					)
					( objectStatus "R8E14.1" )
				)
				( pin "b"
					( attribute "PN" "2"
						( Origin gPackager )
					)
					( objectStatus "R8E14.2" )
				)
			)
			( gate "@baseboard_fab2_lib.baseboard_fab2(sch_1):page136_i134"
				( attribute "CDS_LIB" "mstr_discrete"
					( Origin gPackager )
				)
				( attribute "CDS_LOCATION" "Q8E1"
					( Origin gPackager )
				)
				( attribute "CDS_SEC" "1"
					( Origin gPackager )
				)
				( attribute "LOCATION" "Q8E1"
					( Origin gFrontEnd )
				)
				( attribute "MATERIAL" "FET"
					( Origin gFrontEnd )
				)
				( attribute "PACK_TYPE" "SOT23LF"
					( Origin gFrontEnd )
				)
				( attribute "PART_NUMBER" "C79254-001"
					( Origin gFrontEnd )
				)
				( attribute "PHYS_PAGE" "136"
					( Origin gFrontEnd )
				)
				( attribute "ROOM" "SB"
					( Origin gFrontEnd )
				)
				( attribute "ROT" "0"
					( Origin gFrontEnd )
				)
				( attribute "SEC" "1"
					( Origin gFrontEnd )
				)
				( attribute "SEC_TYPE" "SOT23LF"
					( Origin gFrontEnd )
				)
				( attribute "VALUE" "2N7002"
					( Origin gFrontEnd )
				)
				( attribute "VER" "8"
					( Origin gFrontEnd )
				)
				( attribute "XY" "(-550,1375)"
					( Origin gFrontEnd )
				)
				( attribute "CHIPS_PART_NAME" "FET_N"
					( Origin gPackager )
				)
				( attribute "CDS_PART_NAME" "FET_N_SOT23LF-2N7002,FET,C7925A"
					( Origin gPackager )
				)
				( objectStatus "Q8E1" )
				( pin "drn"
					( attribute "PN" "3"
						( Origin gPackager )
					)
					( objectStatus "Q8E1.3" )
				)
				( pin "gate"
					( attribute "PN" "1"
						( Origin gPackager )
					)
					( objectStatus "Q8E1.1" )
				)
				( pin "src"
					( attribute "PN" "2"
						( Origin gPackager )
					)
					( objectStatus "Q8E1.2" )
				)
			)
			( gate "@baseboard_fab2_lib.baseboard_fab2(sch_1):page136_i139"
				( attribute "BOM_COST" "SB"
					( Origin gFrontEnd )
				)
				( attribute "CDS_LIB" "mstr_discrete"
					( Origin gPackager )
				)
				( attribute "CDS_LOCATION" "R7G31"
					( Origin gPackager )
				)
				( attribute "CDS_SEC" "1"
					( Origin gPackager )
				)
				( attribute "LOCATION" "R7G31"
					( Origin gFrontEnd )
				)
				( attribute "MATERIAL" "CHIP"
					( Origin gFrontEnd )
				)
				( attribute "PACK_TYPE" "0402"
					( Origin gFrontEnd )
				)
				( attribute "PART_NUMBER" "G21796-026"
					( Origin gFrontEnd )
				)
				( attribute "PHYS_PAGE" "136"
					( Origin gFrontEnd )
				)
				( attribute "ROOM" "SB"
					( Origin gFrontEnd )
				)
				( attribute "ROT" "0"
					( Origin gFrontEnd )
				)
				( attribute "SEC" "1"
					( Origin gFrontEnd )
				)
				( attribute "SEC_TYPE" "0402"
					( Origin gFrontEnd )
				)
				( attribute "TOLERANCE" "1%"
					( Origin gFrontEnd )
				)
				( attribute "VALUE" "1.00K"
					( Origin gFrontEnd )
				)
				( attribute "VER" "2"
					( Origin gFrontEnd )
				)
				( attribute "WATTAGE" "1/16W"
					( Origin gFrontEnd )
				)
				( attribute "XY" "(-775,4800)"
					( Origin gFrontEnd )
				)
				( attribute "CHIPS_PART_NAME" "RES"
					( Origin gPackager )
				)
				( attribute "CDS_PART_NAME" "RES_0402-1.00K,1%,1/16W,CHIP,GA"
					( Origin gPackager )
				)
				( objectStatus "R7G31" )
				( pin "a"
					( attribute "PN" "1"
						( Origin gPackager )
					)
					( objectStatus "R7G31.1" )
				)
				( pin "b"
					( attribute "PN" "2"
						( Origin gPackager )
					)
					( objectStatus "R7G31.2" )
				)
			)
			( gate "@baseboard_fab2_lib.baseboard_fab2(sch_1):page136_i140"
				( attribute "BOM_COST" "SB"
					( Origin gFrontEnd )
				)
				( attribute "CDS_LIB" "mstr_discrete"
					( Origin gPackager )
				)
				( attribute "CDS_LOCATION" "R8E16"
					( Origin gPackager )
				)
				( attribute "CDS_SEC" "1"
					( Origin gPackager )
				)
				( attribute "LOCATION" "R8E16"
					( Origin gFrontEnd )
				)
				( attribute "MATERIAL" "CHIP"
					( Origin gFrontEnd )
				)
				( attribute "PACK_TYPE" "0402"
					( Origin gFrontEnd )
				)
				( attribute "PART_NUMBER" "G21796-040"
					( Origin gFrontEnd )
				)
				( attribute "PHYS_PAGE" "136"
					( Origin gFrontEnd )
				)
				( attribute "ROOM" "SB"
					( Origin gFrontEnd )
				)
				( attribute "ROT" "0"
					( Origin gFrontEnd )
				)
				( attribute "SEC" "1"
					( Origin gFrontEnd )
				)
				( attribute "SEC_TYPE" "0402"
					( Origin gFrontEnd )
				)
				( attribute "TOLERANCE" "1%"
					( Origin gFrontEnd )
				)
				( attribute "VALUE" "20.0K"
					( Origin gFrontEnd )
				)
				( attribute "VER" "2"
					( Origin gFrontEnd )
				)
				( attribute "WATTAGE" "1/16W"
					( Origin gFrontEnd )
				)
				( attribute "XY" "(-425,3825)"
					( Origin gFrontEnd )
				)
				( attribute "CHIPS_PART_NAME" "RES"
					( Origin gPackager )
				)
				( attribute "CDS_PART_NAME" "RES_0402-20.0K,1%,1/16W,CHIP,GA"
					( Origin gPackager )
				)
				( objectStatus "R8E16" )
				( pin "a"
					( attribute "PN" "1"
						( Origin gPackager )
					)
					( objectStatus "R8E16.1" )
				)
				( pin "b"
					( attribute "PN" "2"
						( Origin gPackager )
					)
					( objectStatus "R8E16.2" )
				)
			)
			( gate "@baseboard_fab2_lib.baseboard_fab2(sch_1):page136_i147"
				( attribute "BOM_COST" "SB"
					( Origin gFrontEnd )
				)
				( attribute "CDS_LIB" "mstr_discrete"
					( Origin gPackager )
				)
				( attribute "CDS_LOCATION" "R2N28"
					( Origin gPackager )
				)
				( attribute "CDS_SEC" "1"
					( Origin gPackager )
				)
				( attribute "LOCATION" "R2N28"
					( Origin gFrontEnd )
				)
				( attribute "MATERIAL" "CHIP"
					( Origin gFrontEnd )
				)
				( attribute "PACK_TYPE" "0402"
					( Origin gFrontEnd )
				)
				( attribute "PART_NUMBER" "G21796-016"
					( Origin gFrontEnd )
				)
				( attribute "PHYS_PAGE" "136"
					( Origin gFrontEnd )
				)
				( attribute "ROOM" "SB"
					( Origin gFrontEnd )
				)
				( attribute "ROT" "2"
					( Origin gFrontEnd )
				)
				( attribute "SEC" "1"
					( Origin gFrontEnd )
				)
				( attribute "SEC_TYPE" "0402"
					( Origin gFrontEnd )
				)
				( attribute "TOLERANCE" "1%"
					( Origin gFrontEnd )
				)
				( attribute "VALUE" "10.0K"
					( Origin gFrontEnd )
				)
				( attribute "VER" "2"
					( Origin gFrontEnd )
				)
				( attribute "WATTAGE" "1/16W"
					( Origin gFrontEnd )
				)
				( attribute "XY" "(-2650,4800)"
					( Origin gFrontEnd )
				)
				( attribute "CHIPS_PART_NAME" "RES"
					( Origin gPackager )
				)
				( attribute "CDS_PART_NAME" "RES_0402-10.0K,1%,1/16W,CHIP,GA"
					( Origin gPackager )
				)
				( objectStatus "R2N28" )
				( pin "a"
					( attribute "PN" "1"
						( Origin gPackager )
					)
					( objectStatus "R2N28.1" )
				)
				( pin "b"
					( attribute "PN" "2"
						( Origin gPackager )
					)
					( objectStatus "R2N28.2" )
				)
			)
			( gate "@baseboard_fab2_lib.baseboard_fab2(sch_1):page136_i148"
				( attribute "BOM_COST" "SB"
					( Origin gFrontEnd )
				)
				( attribute "CDS_LIB" "mstr_discrete"
					( Origin gPackager )
				)
				( attribute "CDS_LOCATION" "R7G29"
					( Origin gPackager )
				)
				( attribute "CDS_SEC" "1"
					( Origin gPackager )
				)
				( attribute "LOCATION" "R7G29"
					( Origin gFrontEnd )
				)
				( attribute "MATERIAL" "CHIP"
					( Origin gFrontEnd )
				)
				( attribute "PACK_TYPE" "0402"
					( Origin gFrontEnd )
				)
				( attribute "PART_NUMBER" "G21796-026"
					( Origin gFrontEnd )
				)
				( attribute "PHYS_PAGE" "136"
					( Origin gFrontEnd )
				)
				( attribute "ROOM" "SB"
					( Origin gFrontEnd )
				)
				( attribute "ROT" "0"
					( Origin gFrontEnd )
				)
				( attribute "SEC" "1"
					( Origin gFrontEnd )
				)
				( attribute "SEC_TYPE" "0402"
					( Origin gFrontEnd )
				)
				( attribute "TOLERANCE" "1%"
					( Origin gFrontEnd )
				)
				( attribute "VALUE" "1.00K"
					( Origin gFrontEnd )
				)
				( attribute "VER" "2"
					( Origin gFrontEnd )
				)
				( attribute "WATTAGE" "1/16W"
					( Origin gFrontEnd )
				)
				( attribute "XY" "(-2650,3825)"
					( Origin gFrontEnd )
				)
				( attribute "CHIPS_PART_NAME" "RES"
					( Origin gPackager )
				)
				( attribute "CDS_PART_NAME" "RES_0402-1.00K,1%,1/16W,CHIP,GA"
					( Origin gPackager )
				)
				( objectStatus "R7G29" )
				( pin "a"
					( attribute "PN" "1"
						( Origin gPackager )
					)
					( objectStatus "R7G29.1" )
				)
				( pin "b"
					( attribute "PN" "2"
						( Origin gPackager )
					)
					( objectStatus "R7G29.2" )
				)
			)
			( gate "@baseboard_fab2_lib.baseboard_fab2(sch_1):page136_i155"
				( attribute "BOM_COST" "SB"
					( Origin gFrontEnd )
				)
				( attribute "CDS_LIB" "mstr_discrete"
					( Origin gPackager )
				)
				( attribute "CDS_LOCATION" "R7G27"
					( Origin gPackager )
				)
				( attribute "CDS_SEC" "1"
					( Origin gPackager )
				)
				( attribute "LOCATION" "R7G27"
					( Origin gFrontEnd )
				)
				( attribute "MATERIAL" "CHIP"
					( Origin gFrontEnd )
				)
				( attribute "PACK_TYPE" "0402"
					( Origin gFrontEnd )
				)
				( attribute "PART_NUMBER" "G21796-026"
					( Origin gFrontEnd )
				)
				( attribute "PHYS_PAGE" "136"
					( Origin gFrontEnd )
				)
				( attribute "ROOM" "SB"
					( Origin gFrontEnd )
				)
				( attribute "ROT" "2"
					( Origin gFrontEnd )
				)
				( attribute "SEC" "1"
					( Origin gFrontEnd )
				)
				( attribute "SEC_TYPE" "0402"
					( Origin gFrontEnd )
				)
				( attribute "TOLERANCE" "1%"
					( Origin gFrontEnd )
				)
				( attribute "VALUE" "1.00K"
					( Origin gFrontEnd )
				)
				( attribute "VER" "2"
					( Origin gFrontEnd )
				)
				( attribute "WATTAGE" "1/16W"
					( Origin gFrontEnd )
				)
				( attribute "XY" "(-1075,4800)"
					( Origin gFrontEnd )
				)
				( attribute "CHIPS_PART_NAME" "RES"
					( Origin gPackager )
				)
				( attribute "CDS_PART_NAME" "RES_0402-1.00K,1%,1/16W,CHIP,GA"
					( Origin gPackager )
				)
				( objectStatus "R7G27" )
				( pin "a"
					( attribute "PN" "1"
						( Origin gPackager )
					)
					( objectStatus "R7G27.1" )
				)
				( pin "b"
					( attribute "PN" "2"
						( Origin gPackager )
					)
					( objectStatus "R7G27.2" )
				)
			)
			( gate "@baseboard_fab2_lib.baseboard_fab2(sch_1):page136_i156"
				( attribute "BOM_COST" "SB"
					( Origin gFrontEnd )
				)
				( attribute "CDS_LIB" "mstr_discrete"
					( Origin gPackager )
				)
				( attribute "CDS_LOCATION" "R3T14"
					( Origin gPackager )
				)
				( attribute "CDS_SEC" "1"
					( Origin gPackager )
				)
				( attribute "LOCATION" "R3T14"
					( Origin gFrontEnd )
				)
				( attribute "MATERIAL" "CHIP"
					( Origin gFrontEnd )
				)
				( attribute "PACK_TYPE" "0402"
					( Origin gFrontEnd )
				)
				( attribute "PART_NUMBER" "G21796-016"
					( Origin gFrontEnd )
				)
				( attribute "PHYS_PAGE" "136"
					( Origin gFrontEnd )
				)
				( attribute "ROOM" "SB"
					( Origin gFrontEnd )
				)
				( attribute "ROT" "0"
					( Origin gFrontEnd )
				)
				( attribute "SEC" "1"
					( Origin gFrontEnd )
				)
				( attribute "SEC_TYPE" "0402"
					( Origin gFrontEnd )
				)
				( attribute "TOLERANCE" "1%"
					( Origin gFrontEnd )
				)
				( attribute "VALUE" "10.0K"
					( Origin gFrontEnd )
				)
				( attribute "VER" "2"
					( Origin gFrontEnd )
				)
				( attribute "WATTAGE" "1/16W"
					( Origin gFrontEnd )
				)
				( attribute "XY" "(-725,3825)"
					( Origin gFrontEnd )
				)
				( attribute "CHIPS_PART_NAME" "RES"
					( Origin gPackager )
				)
				( attribute "CDS_PART_NAME" "RES_0402-10.0K,1%,1/16W,CHIP,GA"
					( Origin gPackager )
				)
				( objectStatus "R3T14" )
				( pin "a"
					( attribute "PN" "1"
						( Origin gPackager )
					)
					( objectStatus "R3T14.1" )
				)
				( pin "b"
					( attribute "PN" "2"
						( Origin gPackager )
					)
					( objectStatus "R3T14.2" )
				)
			)
			( gate "@baseboard_fab2_lib.baseboard_fab2(sch_1):page136_i174"
				( attribute "BOM_COST" "SB"
					( Origin gFrontEnd )
				)
				( attribute "CDS_LIB" "mstr_conn"
					( Origin gPackager )
				)
				( attribute "CDS_LOCATION" "J7G3"
					( Origin gPackager )
				)
				( attribute "CDS_SEC" "1"
					( Origin gPackager )
				)
				( attribute "LOCATION" "J7G3"
					( Origin gFrontEnd )
				)
				( attribute "MATERIAL" "CONN"
					( Origin gFrontEnd )
				)
				( attribute "PACK_TYPE" "PIP"
					( Origin gFrontEnd )
				)
				( attribute "PART_NUMBER" "C73564-003"
					( Origin gFrontEnd )
				)
				( attribute "PHYS_PAGE" "136"
					( Origin gFrontEnd )
				)
				( attribute "ROOM" "SB"
					( Origin gFrontEnd )
				)
				( attribute "ROT" "0"
					( Origin gFrontEnd )
				)
				( attribute "SEC" "1"
					( Origin gFrontEnd )
				)
				( attribute "SEC_TYPE" "PIP"
					( Origin gFrontEnd )
				)
				( attribute "VER" "1"
					( Origin gFrontEnd )
				)
				( attribute "XY" "(-1650,4250)"
					( Origin gFrontEnd )
				)
				( attribute "CHIPS_PART_NAME" "CONN12_C73564003"
					( Origin gPackager )
				)
				( attribute "CDS_PART_NAME" "CONN12_C73564003_PIP-CONN,C735A"
					( Origin gPackager )
				)
				( objectStatus "J7G3" )
				( pin "io1"
					( attribute "PN" "1"
						( Origin gPackager )
					)
					( objectStatus "J7G3.1" )
				)
				( pin "io2"
					( attribute "PN" "2"
						( Origin gPackager )
					)
					( objectStatus "J7G3.2" )
				)
				( pin "io3"
					( attribute "PN" "3"
						( Origin gPackager )
					)
					( objectStatus "J7G3.3" )
				)
				( pin "io4"
					( attribute "PN" "4"
						( Origin gPackager )
					)
					( objectStatus "J7G3.4" )
				)
				( pin "io5"
					( attribute "PN" "5"
						( Origin gPackager )
					)
					( objectStatus "J7G3.5" )
				)
				( pin "io6"
					( attribute "PN" "6"
						( Origin gPackager )
					)
					( objectStatus "J7G3.6" )
				)
				( pin "io7"
					( attribute "PN" "7"
						( Origin gPackager )
					)
					( objectStatus "J7G3.7" )
				)
				( pin "io8"
					( attribute "PN" "8"
						( Origin gPackager )
					)
					( objectStatus "J7G3.8" )
				)
				( pin "io9"
					( attribute "PN" "9"
						( Origin gPackager )
					)
					( objectStatus "J7G3.9" )
				)
				( pin "io10"
					( attribute "PN" "10"
						( Origin gPackager )
					)
					( objectStatus "J7G3.10" )
				)
				( pin "io11"
					( attribute "PN" "11"
						( Origin gPackager )
					)
					( objectStatus "J7G3.11" )
				)
				( pin "io12"
					( attribute "PN" "12"
						( Origin gPackager )
					)
					( objectStatus "J7G3.12" )
				)
			)
			( gate "@baseboard_fab2_lib.baseboard_fab2(sch_1):page137_i11"
				( attribute "BOM_COST" "SB"
					( Origin gFrontEnd )
				)
				( attribute "CDS_LIB" "mstr_discrete"
					( Origin gPackager )
				)
				( attribute "CDS_LOCATION" "R7C11"
					( Origin gPackager )
				)
				( attribute "CDS_SEC" "1"
					( Origin gPackager )
				)
				( attribute "LOCATION" "R7C11"
					( Origin gFrontEnd )
				)
				( attribute "MATERIAL" "EMPTY"
					( Origin gFrontEnd )
				)
				( attribute "PACK_TYPE" "0402"
					( Origin gFrontEnd )
				)
				( attribute "PART_NUMBER" "G21796-021"
					( Origin gFrontEnd )
				)
				( attribute "PHYS_PAGE" "137"
					( Origin gFrontEnd )
				)
				( attribute "ROOM" "SB"
					( Origin gFrontEnd )
				)
				( attribute "ROT" "1"
					( Origin gFrontEnd )
				)
				( attribute "SEC" "1"
					( Origin gPackager )
				)
				( attribute "TOLERANCE" "1%"
					( Origin gFrontEnd )
				)
				( attribute "VALUE" "1.0M"
					( Origin gFrontEnd )
				)
				( attribute "VER" "1"
					( Origin gFrontEnd )
				)
				( attribute "WATTAGE" "1/16W"
					( Origin gFrontEnd )
				)
				( attribute "XY" "(325,3450)"
					( Origin gFrontEnd )
				)
				( attribute "CHIPS_PART_NAME" "RES"
					( Origin gPackager )
				)
				( attribute "CDS_PART_NAME" "RES_0402-1.0M,1%,1/16W,EMPTY,GA"
					( Origin gPackager )
				)
				( objectStatus "R7C11" )
				( pin "a"
					( attribute "PN" "1"
						( Origin gPackager )
					)
					( objectStatus "R7C11.1" )
				)
				( pin "b"
					( attribute "PN" "2"
						( Origin gPackager )
					)
					( objectStatus "R7C11.2" )
				)
			)
			( gate "@baseboard_fab2_lib.baseboard_fab2(sch_1):page137_i13"
				( attribute "BOM_COST" "SB"
					( Origin gFrontEnd )
				)
				( attribute "CDS_LIB" "mstr_discrete"
					( Origin gPackager )
				)
				( attribute "CDS_LOCATION" "R7C10"
					( Origin gPackager )
				)
				( attribute "CDS_SEC" "1"
					( Origin gPackager )
				)
				( attribute "LOCATION" "R7C10"
					( Origin gFrontEnd )
				)
				( attribute "MATERIAL" "CHIP"
					( Origin gFrontEnd )
				)
				( attribute "NO_XNET_CONNECTION" "1"
					( Origin gFrontEnd )
				)
				( attribute "PACK_TYPE" "0402"
					( Origin gFrontEnd )
				)
				( attribute "PART_NUMBER" "G21796-040"
					( Origin gFrontEnd )
				)
				( attribute "PHYS_PAGE" "137"
					( Origin gFrontEnd )
				)
				( attribute "ROOM" "SB"
					( Origin gFrontEnd )
				)
				( attribute "ROT" "0"
					( Origin gFrontEnd )
				)
				( attribute "SEC" "1"
					( Origin gFrontEnd )
				)
				( attribute "SEC_TYPE" "0402"
					( Origin gFrontEnd )
				)
				( attribute "TOLERANCE" "1%"
					( Origin gFrontEnd )
				)
				( attribute "VALUE" "20.0K"
					( Origin gFrontEnd )
				)
				( attribute "VER" "2"
					( Origin gFrontEnd )
				)
				( attribute "WATTAGE" "1/16W"
					( Origin gFrontEnd )
				)
				( attribute "XY" "(-200,4025)"
					( Origin gFrontEnd )
				)
				( attribute "CHIPS_PART_NAME" "RES"
					( Origin gPackager )
				)
				( attribute "CDS_PART_NAME" "RES_0402-20.0K,1%,1/16W,CHIP,GA"
					( Origin gPackager )
				)
				( objectStatus "R7C10" )
				( pin "a"
					( attribute "PN" "1"
						( Origin gPackager )
					)
					( objectStatus "R7C10.1" )
				)
				( pin "b"
					( attribute "PN" "2"
						( Origin gPackager )
					)
					( objectStatus "R7C10.2" )
				)
			)
			( gate "@baseboard_fab2_lib.baseboard_fab2(sch_1):page137_i14"
				( attribute "BOM_COST" "SB"
					( Origin gFrontEnd )
				)
				( attribute "CDS_LIB" "dev_discrete"
					( Origin gPackager )
				)
				( attribute "CDS_LOCATION" "C7C19"
					( Origin gPackager )
				)
				( attribute "CDS_SEC" "1"
					( Origin gPackager )
				)
				( attribute "LOCATION" "C7C19"
					( Origin gFrontEnd )
				)
				( attribute "MATERIAL" "X6S"
					( Origin gFrontEnd )
				)
				( attribute "PACK_TYPE" "0402V"
					( Origin gFrontEnd )
				)
				( attribute "PART_NUMBER" "D97712-004"
					( Origin gFrontEnd )
				)
				( attribute "PHYS_PAGE" "137"
					( Origin gFrontEnd )
				)
				( attribute "ROOM" "SB"
					( Origin gFrontEnd )
				)
				( attribute "ROT" "0"
					( Origin gFrontEnd )
				)
				( attribute "SEC" "1"
					( Origin gFrontEnd )
				)
				( attribute "SEC_TYPE" "0402V"
					( Origin gFrontEnd )
				)
				( attribute "TOLERANCE" "10%"
					( Origin gFrontEnd )
				)
				( attribute "VALUE" "1.0UF"
					( Origin gFrontEnd )
				)
				( attribute "VER" "1"
					( Origin gFrontEnd )
				)
				( attribute "VOLTAGE" "6.3V"
					( Units "uVoltage" "V" 1.000000)
					( Origin gFrontEnd )
				)
				( attribute "XY" "(-125,3450)"
					( Origin gFrontEnd )
				)
				( attribute "CHIPS_PART_NAME" "CAP_A"
					( Origin gPackager )
				)
				( attribute "CDS_PART_NAME" "CAP_A_0402V-1.0UF,6.3V,10%,X6SA"
					( Origin gPackager )
				)
				( objectStatus "C7C19" )
				( pin "a"
					( attribute "PN" "1"
						( Origin gPackager )
					)
					( objectStatus "C7C19.1" )
				)
				( pin "b"
					( attribute "PN" "2"
						( Origin gPackager )
					)
					( objectStatus "C7C19.2" )
				)
			)
			( gate "@baseboard_fab2_lib.baseboard_fab2(sch_1):page137_i15"
				( attribute "BOM_COST" "SB"
					( Origin gFrontEnd )
				)
				( attribute "CDS_LIB" "mstr_discrete"
					( Origin gPackager )
				)
				( attribute "CDS_LOCATION" "R1U63"
					( Origin gPackager )
				)
				( attribute "CDS_SEC" "1"
					( Origin gPackager )
				)
				( attribute "LOCATION" "R1U63"
					( Origin gFrontEnd )
				)
				( attribute "MATERIAL" "CHIP"
					( Origin gFrontEnd )
				)
				( attribute "PACK_TYPE" "0402"
					( Origin gFrontEnd )
				)
				( attribute "PART_NUMBER" "G21796-026"
					( Origin gFrontEnd )
				)
				( attribute "PHYS_PAGE" "137"
					( Origin gFrontEnd )
				)
				( attribute "ROOM" "SB"
					( Origin gFrontEnd )
				)
				( attribute "ROT" "2"
					( Origin gFrontEnd )
				)
				( attribute "SEC" "1"
					( Origin gFrontEnd )
				)
				( attribute "SEC_TYPE" "0402"
					( Origin gFrontEnd )
				)
				( attribute "TOLERANCE" "1%"
					( Origin gFrontEnd )
				)
				( attribute "VALUE" "1.00K"
					( Origin gFrontEnd )
				)
				( attribute "VER" "2"
					( Origin gFrontEnd )
				)
				( attribute "WATTAGE" "1/16W"
					( Origin gFrontEnd )
				)
				( attribute "XY" "(-275,3450)"
					( Origin gFrontEnd )
				)
				( attribute "CHIPS_PART_NAME" "RES"
					( Origin gPackager )
				)
				( attribute "CDS_PART_NAME" "RES_0402-1.00K,1%,1/16W,CHIP,GA"
					( Origin gPackager )
				)
				( objectStatus "R1U63" )
				( pin "a"
					( attribute "PN" "1"
						( Origin gPackager )
					)
					( objectStatus "R1U63.1" )
				)
				( pin "b"
					( attribute "PN" "2"
						( Origin gPackager )
					)
					( objectStatus "R1U63.2" )
				)
			)
			( gate "@baseboard_fab2_lib.baseboard_fab2(sch_1):page137_i19"
				( attribute "BOM_COST" "SB"
					( Origin gFrontEnd )
				)
				( attribute "CDS_LIB" "mstr_discrete"
					( Origin gPackager )
				)
				( attribute "CDS_LOCATION" "R3N4"
					( Origin gPackager )
				)
				( attribute "CDS_SEC" "1"
					( Origin gPackager )
				)
				( attribute "LOCATION" "R3N4"
					( Origin gFrontEnd )
				)
				( attribute "MATERIAL" "CHIP"
					( Origin gFrontEnd )
				)
				( attribute "NO_XNET_CONNECTION" "1"
					( Origin gFrontEnd )
				)
				( attribute "PACK_TYPE" "0402"
					( Origin gFrontEnd )
				)
				( attribute "PART_NUMBER" "G21796-040"
					( Origin gFrontEnd )
				)
				( attribute "PHYS_PAGE" "137"
					( Origin gFrontEnd )
				)
				( attribute "ROOM" "SB"
					( Origin gFrontEnd )
				)
				( attribute "ROT" "0"
					( Origin gFrontEnd )
				)
				( attribute "SEC" "1"
					( Origin gPackager )
				)
				( attribute "TOLERANCE" "1%"
					( Origin gFrontEnd )
				)
				( attribute "VALUE" "20.0K"
					( Origin gFrontEnd )
				)
				( attribute "VER" "2"
					( Origin gFrontEnd )
				)
				( attribute "WATTAGE" "1/16W"
					( Origin gFrontEnd )
				)
				( attribute "XY" "(-275,2425)"
					( Origin gFrontEnd )
				)
				( attribute "CHIPS_PART_NAME" "RES"
					( Origin gPackager )
				)
				( attribute "CDS_PART_NAME" "RES_0402-20.0K,1%,1/16W,CHIP,GA"
					( Origin gPackager )
				)
				( objectStatus "R3N4" )
				( pin "a"
					( attribute "PN" "1"
						( Origin gPackager )
					)
					( objectStatus "R3N4.1" )
				)
				( pin "b"
					( attribute "PN" "2"
						( Origin gPackager )
					)
					( objectStatus "R3N4.2" )
				)
			)
			( gate "@baseboard_fab2_lib.baseboard_fab2(sch_1):page137_i20"
				( attribute "BOM_COST" "SB"
					( Origin gFrontEnd )
				)
				( attribute "CDS_LIB" "dev_discrete"
					( Origin gPackager )
				)
				( attribute "CDS_LOCATION" "C3N32"
					( Origin gPackager )
				)
				( attribute "CDS_SEC" "1"
					( Origin gPackager )
				)
				( attribute "LOCATION" "C3N32"
					( Origin gFrontEnd )
				)
				( attribute "MATERIAL" "X6S"
					( Origin gFrontEnd )
				)
				( attribute "PACK_TYPE" "0402V"
					( Origin gFrontEnd )
				)
				( attribute "PART_NUMBER" "D97712-004"
					( Origin gFrontEnd )
				)
				( attribute "PHYS_PAGE" "137"
					( Origin gFrontEnd )
				)
				( attribute "ROOM" "SB"
					( Origin gFrontEnd )
				)
				( attribute "ROT" "0"
					( Origin gFrontEnd )
				)
				( attribute "SEC" "1"
					( Origin gFrontEnd )
				)
				( attribute "SEC_TYPE" "0402V"
					( Origin gFrontEnd )
				)
				( attribute "TOLERANCE" "10%"
					( Origin gFrontEnd )
				)
				( attribute "VALUE" "1.0UF"
					( Origin gFrontEnd )
				)
				( attribute "VER" "1"
					( Origin gFrontEnd )
				)
				( attribute "VOLTAGE" "6.3V"
					( Units "uVoltage" "V" 1.000000)
					( Origin gFrontEnd )
				)
				( attribute "XY" "(-275,1975)"
					( Origin gFrontEnd )
				)
				( attribute "CHIPS_PART_NAME" "CAP_A"
					( Origin gPackager )
				)
				( attribute "CDS_PART_NAME" "CAP_A_0402V-1.0UF,6.3V,10%,X6SA"
					( Origin gPackager )
				)
				( objectStatus "C3N32" )
				( pin "a"
					( attribute "PN" "1"
						( Origin gPackager )
					)
					( objectStatus "C3N32.1" )
				)
				( pin "b"
					( attribute "PN" "2"
						( Origin gPackager )
					)
					( objectStatus "C3N32.2" )
				)
			)
			( gate "@baseboard_fab2_lib.baseboard_fab2(sch_1):page137_i67"
				( attribute "BOM_COST" "SB"
					( Origin gFrontEnd )
				)
				( attribute "CDS_LIB" "mstr_discrete"
					( Origin gPackager )
				)
				( attribute "CDS_LOCATION" "R7C13"
					( Origin gPackager )
				)
				( attribute "CDS_SEC" "1"
					( Origin gPackager )
				)
				( attribute "LOCATION" "R7C13"
					( Origin gFrontEnd )
				)
				( attribute "MATERIAL" "CHIP"
					( Origin gFrontEnd )
				)
				( attribute "PACK_TYPE" "0402"
					( Origin gFrontEnd )
				)
				( attribute "PART_NUMBER" "G21796-016"
					( Origin gFrontEnd )
				)
				( attribute "PHYS_PAGE" "137"
					( Origin gFrontEnd )
				)
				( attribute "ROOM" "SB"
					( Origin gFrontEnd )
				)
				( attribute "ROT" "0"
					( Origin gFrontEnd )
				)
				( attribute "SEC" "1"
					( Origin gFrontEnd )
				)
				( attribute "SEC_TYPE" "0402"
					( Origin gFrontEnd )
				)
				( attribute "TOLERANCE" "1%"
					( Origin gFrontEnd )
				)
				( attribute "VALUE" "10.0K"
					( Origin gFrontEnd )
				)
				( attribute "VER" "2"
					( Origin gFrontEnd )
				)
				( attribute "WATTAGE" "1/16W"
					( Origin gFrontEnd )
				)
				( attribute "XY" "(-2875,4225)"
					( Origin gFrontEnd )
				)
				( attribute "CHIPS_PART_NAME" "RES"
					( Origin gPackager )
				)
				( attribute "CDS_PART_NAME" "RES_0402-10.0K,1%,1/16W,CHIP,GA"
					( Origin gPackager )
				)
				( objectStatus "R7C13" )
				( pin "a"
					( attribute "PN" "1"
						( Origin gPackager )
					)
					( objectStatus "R7C13.1" )
				)
				( pin "b"
					( attribute "PN" "2"
						( Origin gPackager )
					)
					( objectStatus "R7C13.2" )
				)
			)
			( gate "@baseboard_fab2_lib.baseboard_fab2(sch_1):page137_i69"
				( attribute "BOM_COST" "SB"
					( Origin gFrontEnd )
				)
				( attribute "CDS_LIB" "mstr_discrete"
					( Origin gPackager )
				)
				( attribute "CDS_LOCATION" "R1U64"
					( Origin gPackager )
				)
				( attribute "CDS_SEC" "1"
					( Origin gPackager )
				)
				( attribute "LOCATION" "R1U64"
					( Origin gFrontEnd )
				)
				( attribute "MATERIAL" "CHIP"
					( Origin gFrontEnd )
				)
				( attribute "PACK_TYPE" "0402"
					( Origin gFrontEnd )
				)
				( attribute "PART_NUMBER" "G21796-026"
					( Origin gFrontEnd )
				)
				( attribute "PHYS_PAGE" "137"
					( Origin gFrontEnd )
				)
				( attribute "ROOM" "SB"
					( Origin gFrontEnd )
				)
				( attribute "ROT" "0"
					( Origin gFrontEnd )
				)
				( attribute "SEC" "1"
					( Origin gFrontEnd )
				)
				( attribute "SEC_TYPE" "0402"
					( Origin gFrontEnd )
				)
				( attribute "TOLERANCE" "1%"
					( Origin gFrontEnd )
				)
				( attribute "VALUE" "1.00K"
					( Origin gFrontEnd )
				)
				( attribute "VER" "2"
					( Origin gFrontEnd )
				)
				( attribute "WATTAGE" "1/16W"
					( Origin gFrontEnd )
				)
				( attribute "XY" "(-2875,3300)"
					( Origin gFrontEnd )
				)
				( attribute "CHIPS_PART_NAME" "RES"
					( Origin gPackager )
				)
				( attribute "CDS_PART_NAME" "RES_0402-1.00K,1%,1/16W,CHIP,GA"
					( Origin gPackager )
				)
				( objectStatus "R1U64" )
				( pin "a"
					( attribute "PN" "1"
						( Origin gPackager )
					)
					( objectStatus "R1U64.1" )
				)
				( pin "b"
					( attribute "PN" "2"
						( Origin gPackager )
					)
					( objectStatus "R1U64.2" )
				)
			)
			( gate "@baseboard_fab2_lib.baseboard_fab2(sch_1):page137_i128"
				( attribute "BOM_COST" "SB"
					( Origin gFrontEnd )
				)
				( attribute "CDS_LIB" "mstr_conn"
					( Origin gPackager )
				)
				( attribute "CDS_LOCATION" "J9G1"
					( Origin gPackager )
				)
				( attribute "CDS_SEC" "1"
					( Origin gPackager )
				)
				( attribute "LOCATION" "J9G1"
					( Origin gFrontEnd )
				)
				( attribute "MATERIAL" "CONN"
					( Origin gFrontEnd )
				)
				( attribute "PACK_TYPE" "PIP"
					( Origin gFrontEnd )
				)
				( attribute "PART_NUMBER" "C73564-003"
					( Origin gFrontEnd )
				)
				( attribute "PHYS_PAGE" "137"
					( Origin gFrontEnd )
				)
				( attribute "ROOM" "SB"
					( Origin gFrontEnd )
				)
				( attribute "ROT" "0"
					( Origin gFrontEnd )
				)
				( attribute "SEC" "1"
					( Origin gFrontEnd )
				)
				( attribute "SEC_TYPE" "PIP"
					( Origin gFrontEnd )
				)
				( attribute "VER" "1"
					( Origin gFrontEnd )
				)
				( attribute "XY" "(-2175,3675)"
					( Origin gFrontEnd )
				)
				( attribute "CHIPS_PART_NAME" "CONN12_C73564003"
					( Origin gPackager )
				)
				( attribute "CDS_PART_NAME" "CONN12_C73564003_PIP-CONN,C735A"
					( Origin gPackager )
				)
				( objectStatus "J9G1" )
				( pin "io1"
					( attribute "PN" "1"
						( Origin gPackager )
					)
					( objectStatus "J9G1.1" )
				)
				( pin "io2"
					( attribute "PN" "2"
						( Origin gPackager )
					)
					( objectStatus "J9G1.2" )
				)
				( pin "io3"
					( attribute "PN" "3"
						( Origin gPackager )
					)
					( objectStatus "J9G1.3" )
				)
				( pin "io4"
					( attribute "PN" "4"
						( Origin gPackager )
					)
					( objectStatus "J9G1.4" )
				)
				( pin "io5"
					( attribute "PN" "5"
						( Origin gPackager )
					)
					( objectStatus "J9G1.5" )
				)
				( pin "io6"
					( attribute "PN" "6"
						( Origin gPackager )
					)
					( objectStatus "J9G1.6" )
				)
				( pin "io7"
					( attribute "PN" "7"
						( Origin gPackager )
					)
					( objectStatus "J9G1.7" )
				)
				( pin "io8"
					( attribute "PN" "8"
						( Origin gPackager )
					)
					( objectStatus "J9G1.8" )
				)
				( pin "io9"
					( attribute "PN" "9"
						( Origin gPackager )
					)
					( objectStatus "J9G1.9" )
				)
				( pin "io10"
					( attribute "PN" "10"
						( Origin gPackager )
					)
					( objectStatus "J9G1.10" )
				)
				( pin "io11"
					( attribute "PN" "11"
						( Origin gPackager )
					)
					( objectStatus "J9G1.11" )
				)
				( pin "io12"
					( attribute "PN" "12"
						( Origin gPackager )
					)
					( objectStatus "J9G1.12" )
				)
			)
			( gate "@baseboard_fab2_lib.baseboard_fab2(sch_1):page138_i83"
				( attribute "BOM_COST" "SM_CONTROLLER"
					( Origin gFrontEnd )
				)
				( attribute "CDS_LIB" "mstr_discrete"
					( Origin gPackager )
				)
				( attribute "CDS_LOCATION" "R2T53"
					( Origin gPackager )
				)
				( attribute "CDS_SEC" "1"
					( Origin gPackager )
				)
				( attribute "LOCATION" "R2T53"
					( Origin gFrontEnd )
				)
				( attribute "MATERIAL" "CHIP"
					( Origin gFrontEnd )
				)
				( attribute "PACK_TYPE" "0402"
					( Origin gFrontEnd )
				)
				( attribute "PART_NUMBER" "G21796-235"
					( Origin gFrontEnd )
				)
				( attribute "PHYS_PAGE" "138"
					( Origin gFrontEnd )
				)
				( attribute "ROOM" "SMBUS"
					( Origin gFrontEnd )
				)
				( attribute "ROT" "0"
					( Origin gFrontEnd )
				)
				( attribute "SEC" "1"
					( Origin gFrontEnd )
				)
				( attribute "SEC_TYPE" "0402"
					( Origin gFrontEnd )
				)
				( attribute "TOLERANCE" "1.0%"
					( Origin gFrontEnd )
				)
				( attribute "VALUE" "665"
					( Origin gFrontEnd )
				)
				( attribute "VER" "2"
					( Origin gFrontEnd )
				)
				( attribute "WATTAGE" "1/16W"
					( Origin gFrontEnd )
				)
				( attribute "XY" "(500,4450)"
					( Origin gFrontEnd )
				)
				( attribute "CHIPS_PART_NAME" "RES"
					( Origin gPackager )
				)
				( attribute "CDS_PART_NAME" "RES_0402-665,1.0%,1/16W,CHIP,GA"
					( Origin gPackager )
				)
				( objectStatus "R2T53" )
				( pin "a"
					( attribute "PN" "1"
						( Origin gPackager )
					)
					( objectStatus "R2T53.1" )
				)
				( pin "b"
					( attribute "PN" "2"
						( Origin gPackager )
					)
					( objectStatus "R2T53.2" )
				)
			)
			( gate "@baseboard_fab2_lib.baseboard_fab2(sch_1):page138_i84"
				( attribute "BOM_COST" "SM_CONTROLLER"
					( Origin gFrontEnd )
				)
				( attribute "CDS_LIB" "mstr_discrete"
					( Origin gPackager )
				)
				( attribute "CDS_LOCATION" "R2T54"
					( Origin gPackager )
				)
				( attribute "CDS_SEC" "1"
					( Origin gPackager )
				)
				( attribute "LOCATION" "R2T54"
					( Origin gFrontEnd )
				)
				( attribute "MATERIAL" "CHIP"
					( Origin gFrontEnd )
				)
				( attribute "PACK_TYPE" "0402"
					( Origin gFrontEnd )
				)
				( attribute "PART_NUMBER" "G21796-235"
					( Origin gFrontEnd )
				)
				( attribute "PHYS_PAGE" "138"
					( Origin gFrontEnd )
				)
				( attribute "ROOM" "SMBUS"
					( Origin gFrontEnd )
				)
				( attribute "ROT" "0"
					( Origin gFrontEnd )
				)
				( attribute "SEC" "1"
					( Origin gFrontEnd )
				)
				( attribute "SEC_TYPE" "0402"
					( Origin gFrontEnd )
				)
				( attribute "TOLERANCE" "1.0%"
					( Origin gFrontEnd )
				)
				( attribute "VALUE" "665"
					( Origin gFrontEnd )
				)
				( attribute "VER" "2"
					( Origin gFrontEnd )
				)
				( attribute "WATTAGE" "1/16W"
					( Origin gFrontEnd )
				)
				( attribute "XY" "(850,4400)"
					( Origin gFrontEnd )
				)
				( attribute "CHIPS_PART_NAME" "RES"
					( Origin gPackager )
				)
				( attribute "CDS_PART_NAME" "RES_0402-665,1.0%,1/16W,CHIP,GA"
					( Origin gPackager )
				)
				( objectStatus "R2T54" )
				( pin "a"
					( attribute "PN" "1"
						( Origin gPackager )
					)
					( objectStatus "R2T54.1" )
				)
				( pin "b"
					( attribute "PN" "2"
						( Origin gPackager )
					)
					( objectStatus "R2T54.2" )
				)
			)
			( gate "@baseboard_fab2_lib.baseboard_fab2(sch_1):page138_i87"
				( attribute "BOM_COST" "SM_CONTROLLER"
					( Origin gFrontEnd )
				)
				( attribute "CDS_LIB" "mstr_discrete"
					( Origin gPackager )
				)
				( attribute "CDS_LOCATION" "R8D17"
					( Origin gPackager )
				)
				( attribute "CDS_SEC" "1"
					( Origin gPackager )
				)
				( attribute "LOCATION" "R8D17"
					( Origin gFrontEnd )
				)
				( attribute "MATERIAL" "CHIP"
					( Origin gFrontEnd )
				)
				( attribute "PACK_TYPE" "0402"
					( Origin gFrontEnd )
				)
				( attribute "PART_NUMBER" "G21796-095"
					( Origin gFrontEnd )
				)
				( attribute "PHYS_PAGE" "138"
					( Origin gFrontEnd )
				)
				( attribute "ROOM" "SMBUS"
					( Origin gFrontEnd )
				)
				( attribute "ROT" "0"
					( Origin gFrontEnd )
				)
				( attribute "SEC" "1"
					( Origin gPackager )
				)
				( attribute "TOLERANCE" "1%"
					( Origin gFrontEnd )
				)
				( attribute "VALUE" "1.37K"
					( Origin gFrontEnd )
				)
				( attribute "VER" "2"
					( Origin gFrontEnd )
				)
				( attribute "WATTAGE" "1/16W"
					( Origin gFrontEnd )
				)
				( attribute "XY" "(500,2575)"
					( Origin gFrontEnd )
				)
				( attribute "CHIPS_PART_NAME" "RES"
					( Origin gPackager )
				)
				( attribute "CDS_PART_NAME" "RES_0402-1.37K,1%,1/16W,CHIP,GA"
					( Origin gPackager )
				)
				( objectStatus "R8D17" )
				( pin "a"
					( attribute "PN" "1"
						( Origin gPackager )
					)
					( objectStatus "R8D17.1" )
				)
				( pin "b"
					( attribute "PN" "2"
						( Origin gPackager )
					)
					( objectStatus "R8D17.2" )
				)
			)
			( gate "@baseboard_fab2_lib.baseboard_fab2(sch_1):page138_i88"
				( attribute "BOM_COST" "SM_CONTROLLER"
					( Origin gFrontEnd )
				)
				( attribute "CDS_LIB" "mstr_discrete"
					( Origin gPackager )
				)
				( attribute "CDS_LOCATION" "R8D15"
					( Origin gPackager )
				)
				( attribute "CDS_SEC" "1"
					( Origin gPackager )
				)
				( attribute "LOCATION" "R8D15"
					( Origin gFrontEnd )
				)
				( attribute "MATERIAL" "CHIP"
					( Origin gFrontEnd )
				)
				( attribute "PACK_TYPE" "0402"
					( Origin gFrontEnd )
				)
				( attribute "PART_NUMBER" "G21796-095"
					( Origin gFrontEnd )
				)
				( attribute "PHYS_PAGE" "138"
					( Origin gFrontEnd )
				)
				( attribute "ROOM" "SMBUS"
					( Origin gFrontEnd )
				)
				( attribute "ROT" "0"
					( Origin gFrontEnd )
				)
				( attribute "SEC" "1"
					( Origin gPackager )
				)
				( attribute "TOLERANCE" "1%"
					( Origin gFrontEnd )
				)
				( attribute "VALUE" "1.37K"
					( Origin gFrontEnd )
				)
				( attribute "VER" "2"
					( Origin gFrontEnd )
				)
				( attribute "WATTAGE" "1/16W"
					( Origin gFrontEnd )
				)
				( attribute "XY" "(875,2525)"
					( Origin gFrontEnd )
				)
				( attribute "CHIPS_PART_NAME" "RES"
					( Origin gPackager )
				)
				( attribute "CDS_PART_NAME" "RES_0402-1.37K,1%,1/16W,CHIP,GA"
					( Origin gPackager )
				)
				( objectStatus "R8D15" )
				( pin "a"
					( attribute "PN" "1"
						( Origin gPackager )
					)
					( objectStatus "R8D15.1" )
				)
				( pin "b"
					( attribute "PN" "2"
						( Origin gPackager )
					)
					( objectStatus "R8D15.2" )
				)
			)
			( gate "@baseboard_fab2_lib.baseboard_fab2(sch_1):page138_i89"
				( attribute "BOM_COST" "SM_CONTROLLER"
					( Origin gFrontEnd )
				)
				( attribute "CDS_LIB" "mstr_discrete"
					( Origin gPackager )
				)
				( attribute "CDS_LOCATION" "R2N8"
					( Origin gPackager )
				)
				( attribute "CDS_SEC" "1"
					( Origin gPackager )
				)
				( attribute "LOCATION" "R2N8"
					( Origin gFrontEnd )
				)
				( attribute "MATERIAL" "CHIP"
					( Origin gFrontEnd )
				)
				( attribute "PACK_TYPE" "0402"
					( Origin gFrontEnd )
				)
				( attribute "PART_NUMBER" "G21796-235"
					( Origin gFrontEnd )
				)
				( attribute "PHYS_PAGE" "138"
					( Origin gFrontEnd )
				)
				( attribute "ROOM" "SMBUS"
					( Origin gFrontEnd )
				)
				( attribute "ROT" "0"
					( Origin gFrontEnd )
				)
				( attribute "SEC" "1"
					( Origin gFrontEnd )
				)
				( attribute "SEC_TYPE" "0402"
					( Origin gFrontEnd )
				)
				( attribute "TOLERANCE" "1.0%"
					( Origin gFrontEnd )
				)
				( attribute "VALUE" "665"
					( Origin gFrontEnd )
				)
				( attribute "VER" "2"
					( Origin gFrontEnd )
				)
				( attribute "WATTAGE" "1/16W"
					( Origin gFrontEnd )
				)
				( attribute "XY" "(-3175,4950)"
					( Origin gFrontEnd )
				)
				( attribute "CHIPS_PART_NAME" "RES"
					( Origin gPackager )
				)
				( attribute "CDS_PART_NAME" "RES_0402-665,1.0%,1/16W,CHIP,GA"
					( Origin gPackager )
				)
				( objectStatus "R2N8" )
				( pin "a"
					( attribute "PN" "1"
						( Origin gPackager )
					)
					( objectStatus "R2N8.1" )
				)
				( pin "b"
					( attribute "PN" "2"
						( Origin gPackager )
					)
					( objectStatus "R2N8.2" )
				)
			)
			( gate "@baseboard_fab2_lib.baseboard_fab2(sch_1):page138_i90"
				( attribute "BOM_COST" "SM_CONTROLLER"
					( Origin gFrontEnd )
				)
				( attribute "CDS_LIB" "mstr_discrete"
					( Origin gPackager )
				)
				( attribute "CDS_LOCATION" "R2N5"
					( Origin gPackager )
				)
				( attribute "CDS_SEC" "1"
					( Origin gPackager )
				)
				( attribute "LOCATION" "R2N5"
					( Origin gFrontEnd )
				)
				( attribute "MATERIAL" "CHIP"
					( Origin gFrontEnd )
				)
				( attribute "PACK_TYPE" "0402"
					( Origin gFrontEnd )
				)
				( attribute "PART_NUMBER" "G21796-235"
					( Origin gFrontEnd )
				)
				( attribute "PHYS_PAGE" "138"
					( Origin gFrontEnd )
				)
				( attribute "ROOM" "SMBUS"
					( Origin gFrontEnd )
				)
				( attribute "ROT" "0"
					( Origin gFrontEnd )
				)
				( attribute "SEC" "1"
					( Origin gFrontEnd )
				)
				( attribute "SEC_TYPE" "0402"
					( Origin gFrontEnd )
				)
				( attribute "TOLERANCE" "1.0%"
					( Origin gFrontEnd )
				)
				( attribute "VALUE" "665"
					( Origin gFrontEnd )
				)
				( attribute "VER" "2"
					( Origin gFrontEnd )
				)
				( attribute "WATTAGE" "1/16W"
					( Origin gFrontEnd )
				)
				( attribute "XY" "(-2775,4900)"
					( Origin gFrontEnd )
				)
				( attribute "CHIPS_PART_NAME" "RES"
					( Origin gPackager )
				)
				( attribute "CDS_PART_NAME" "RES_0402-665,1.0%,1/16W,CHIP,GA"
					( Origin gPackager )
				)
				( objectStatus "R2N5" )
				( pin "a"
					( attribute "PN" "1"
						( Origin gPackager )
					)
					( objectStatus "R2N5.1" )
				)
				( pin "b"
					( attribute "PN" "2"
						( Origin gPackager )
					)
					( objectStatus "R2N5.2" )
				)
			)
			( gate "@baseboard_fab2_lib.baseboard_fab2(sch_1):page138_i91"
				( attribute "BOM_COST" "SM_CONTROLLER"
					( Origin gFrontEnd )
				)
				( attribute "CDS_LIB" "mstr_discrete"
					( Origin gPackager )
				)
				( attribute "CDS_LOCATION" "R8C16"
					( Origin gPackager )
				)
				( attribute "CDS_SEC" "1"
					( Origin gPackager )
				)
				( attribute "LOCATION" "R8C16"
					( Origin gFrontEnd )
				)
				( attribute "MATERIAL" "CHIP"
					( Origin gFrontEnd )
				)
				( attribute "PACK_TYPE" "0402"
					( Origin gFrontEnd )
				)
				( attribute "PART_NUMBER" "G21796-001"
					( Origin gFrontEnd )
				)
				( attribute "PHYS_PAGE" "138"
					( Origin gFrontEnd )
				)
				( attribute "ROOM" "SMBUS"
					( Origin gFrontEnd )
				)
				( attribute "ROT" "0"
					( Origin gFrontEnd )
				)
				( attribute "SEC" "1"
					( Origin gPackager )
				)
				( attribute "TOLERANCE" "1%"
					( Origin gFrontEnd )
				)
				( attribute "VALUE" "2.0K"
					( Origin gFrontEnd )
				)
				( attribute "VER" "2"
					( Origin gFrontEnd )
				)
				( attribute "WATTAGE" "1/16W"
					( Origin gFrontEnd )
				)
				( attribute "XY" "(-3175,4025)"
					( Origin gFrontEnd )
				)
				( attribute "CHIPS_PART_NAME" "RES"
					( Origin gPackager )
				)
				( attribute "CDS_PART_NAME" "RES_0402-2.0K,1%,1/16W,CHIP,G2A"
					( Origin gPackager )
				)
				( objectStatus "R8C16" )
				( pin "a"
					( attribute "PN" "1"
						( Origin gPackager )
					)
					( objectStatus "R8C16.1" )
				)
				( pin "b"
					( attribute "PN" "2"
						( Origin gPackager )
					)
					( objectStatus "R8C16.2" )
				)
			)
			( gate "@baseboard_fab2_lib.baseboard_fab2(sch_1):page138_i92"
				( attribute "BOM_COST" "SM_CONTROLLER"
					( Origin gFrontEnd )
				)
				( attribute "CDS_LIB" "mstr_discrete"
					( Origin gPackager )
				)
				( attribute "CDS_LOCATION" "R8C15"
					( Origin gPackager )
				)
				( attribute "CDS_SEC" "1"
					( Origin gPackager )
				)
				( attribute "LOCATION" "R8C15"
					( Origin gFrontEnd )
				)
				( attribute "MATERIAL" "CHIP"
					( Origin gFrontEnd )
				)
				( attribute "PACK_TYPE" "0402"
					( Origin gFrontEnd )
				)
				( attribute "PART_NUMBER" "G21796-001"
					( Origin gFrontEnd )
				)
				( attribute "PHYS_PAGE" "138"
					( Origin gFrontEnd )
				)
				( attribute "ROOM" "SMBUS"
					( Origin gFrontEnd )
				)
				( attribute "ROT" "0"
					( Origin gFrontEnd )
				)
				( attribute "SEC" "1"
					( Origin gPackager )
				)
				( attribute "TOLERANCE" "1%"
					( Origin gFrontEnd )
				)
				( attribute "VALUE" "2.0K"
					( Origin gFrontEnd )
				)
				( attribute "VER" "2"
					( Origin gFrontEnd )
				)
				( attribute "WATTAGE" "1/16W"
					( Origin gFrontEnd )
				)
				( attribute "XY" "(-2775,3975)"
					( Origin gFrontEnd )
				)
				( attribute "CHIPS_PART_NAME" "RES"
					( Origin gPackager )
				)
				( attribute "CDS_PART_NAME" "RES_0402-2.0K,1%,1/16W,CHIP,G2A"
					( Origin gPackager )
				)
				( objectStatus "R8C15" )
				( pin "a"
					( attribute "PN" "1"
						( Origin gPackager )
					)
					( objectStatus "R8C15.1" )
				)
				( pin "b"
					( attribute "PN" "2"
						( Origin gPackager )
					)
					( objectStatus "R8C15.2" )
				)
			)
			( gate "@baseboard_fab2_lib.baseboard_fab2(sch_1):page138_i95"
				( attribute "BOM_COST" "SM_CONTROLLER"
					( Origin gFrontEnd )
				)
				( attribute "CDS_LIB" "mstr_discrete"
					( Origin gPackager )
				)
				( attribute "CDS_LOCATION" "R8B24"
					( Origin gPackager )
				)
				( attribute "CDS_SEC" "1"
					( Origin gPackager )
				)
				( attribute "LOCATION" "R8B24"
					( Origin gFrontEnd )
				)
				( attribute "MATERIAL" "CHIP"
					( Origin gFrontEnd )
				)
				( attribute "PACK_TYPE" "0402"
					( Origin gFrontEnd )
				)
				( attribute "PART_NUMBER" "G21497-013"
					( Origin gFrontEnd )
				)
				( attribute "PHYS_PAGE" "138"
					( Origin gFrontEnd )
				)
				( attribute "ROOM" "SMBUS"
					( Origin gFrontEnd )
				)
				( attribute "ROT" "0"
					( Origin gFrontEnd )
				)
				( attribute "SEC" "1"
					( Origin gFrontEnd )
				)
				( attribute "SEC_TYPE" "0402"
					( Origin gFrontEnd )
				)
				( attribute "TOLERANCE" "5%"
					( Origin gFrontEnd )
				)
				( attribute "VALUE" "3.3K"
					( Origin gFrontEnd )
				)
				( attribute "VER" "2"
					( Origin gFrontEnd )
				)
				( attribute "WATTAGE" "1/16W"
					( Origin gFrontEnd )
				)
				( attribute "XY" "(-3150,2950)"
					( Origin gFrontEnd )
				)
				( attribute "CHIPS_PART_NAME" "RES"
					( Origin gPackager )
				)
				( attribute "CDS_PART_NAME" "RES_0402-3.3K,5%,1/16W,CHIP,G2A"
					( Origin gPackager )
				)
				( objectStatus "R8B24" )
				( pin "a"
					( attribute "PN" "1"
						( Origin gPackager )
					)
					( objectStatus "R8B24.1" )
				)
				( pin "b"
					( attribute "PN" "2"
						( Origin gPackager )
					)
					( objectStatus "R8B24.2" )
				)
			)
			( gate "@baseboard_fab2_lib.baseboard_fab2(sch_1):page138_i96"
				( attribute "BOM_COST" "SM_CONTROLLER"
					( Origin gFrontEnd )
				)
				( attribute "CDS_LIB" "mstr_discrete"
					( Origin gPackager )
				)
				( attribute "CDS_LOCATION" "R8B26"
					( Origin gPackager )
				)
				( attribute "CDS_SEC" "1"
					( Origin gPackager )
				)
				( attribute "LOCATION" "R8B26"
					( Origin gFrontEnd )
				)
				( attribute "MATERIAL" "CHIP"
					( Origin gFrontEnd )
				)
				( attribute "PACK_TYPE" "0402"
					( Origin gFrontEnd )
				)
				( attribute "PART_NUMBER" "G21497-013"
					( Origin gFrontEnd )
				)
				( attribute "PHYS_PAGE" "138"
					( Origin gFrontEnd )
				)
				( attribute "ROOM" "SMBUS"
					( Origin gFrontEnd )
				)
				( attribute "ROT" "0"
					( Origin gFrontEnd )
				)
				( attribute "SEC" "1"
					( Origin gFrontEnd )
				)
				( attribute "SEC_TYPE" "0402"
					( Origin gFrontEnd )
				)
				( attribute "TOLERANCE" "5%"
					( Origin gFrontEnd )
				)
				( attribute "VALUE" "3.3K"
					( Origin gFrontEnd )
				)
				( attribute "VER" "2"
					( Origin gFrontEnd )
				)
				( attribute "WATTAGE" "1/16W"
					( Origin gFrontEnd )
				)
				( attribute "XY" "(-2750,2925)"
					( Origin gFrontEnd )
				)
				( attribute "CHIPS_PART_NAME" "RES"
					( Origin gPackager )
				)
				( attribute "CDS_PART_NAME" "RES_0402-3.3K,5%,1/16W,CHIP,G2A"
					( Origin gPackager )
				)
				( objectStatus "R8B26" )
				( pin "a"
					( attribute "PN" "1"
						( Origin gPackager )
					)
					( objectStatus "R8B26.1" )
				)
				( pin "b"
					( attribute "PN" "2"
						( Origin gPackager )
					)
					( objectStatus "R8B26.2" )
				)
			)
			( gate "@baseboard_fab2_lib.baseboard_fab2(sch_1):page138_i97"
				( attribute "BOM_COST" "SM_CONTROLLER"
					( Origin gFrontEnd )
				)
				( attribute "CDS_LIB" "mstr_discrete"
					( Origin gPackager )
				)
				( attribute "CDS_LOCATION" "R2U11"
					( Origin gPackager )
				)
				( attribute "CDS_SEC" "1"
					( Origin gPackager )
				)
				( attribute "LOCATION" "R2U11"
					( Origin gFrontEnd )
				)
				( attribute "MATERIAL" "CHIP"
					( Origin gFrontEnd )
				)
				( attribute "PACK_TYPE" "0402"
					( Origin gFrontEnd )
				)
				( attribute "PART_NUMBER" "G21796-235"
					( Origin gFrontEnd )
				)
				( attribute "PHYS_PAGE" "138"
					( Origin gFrontEnd )
				)
				( attribute "ROOM" "SMBUS"
					( Origin gFrontEnd )
				)
				( attribute "ROT" "0"
					( Origin gFrontEnd )
				)
				( attribute "SEC" "1"
					( Origin gFrontEnd )
				)
				( attribute "SEC_TYPE" "0402"
					( Origin gFrontEnd )
				)
				( attribute "TOLERANCE" "1.0%"
					( Origin gFrontEnd )
				)
				( attribute "VALUE" "665"
					( Origin gFrontEnd )
				)
				( attribute "VER" "2"
					( Origin gFrontEnd )
				)
				( attribute "WATTAGE" "1/16W"
					( Origin gFrontEnd )
				)
				( attribute "XY" "(-3150,2100)"
					( Origin gFrontEnd )
				)
				( attribute "CHIPS_PART_NAME" "RES"
					( Origin gPackager )
				)
				( attribute "CDS_PART_NAME" "RES_0402-665,1.0%,1/16W,CHIP,GA"
					( Origin gPackager )
				)
				( objectStatus "R2U11" )
				( pin "a"
					( attribute "PN" "1"
						( Origin gPackager )
					)
					( objectStatus "R2U11.1" )
				)
				( pin "b"
					( attribute "PN" "2"
						( Origin gPackager )
					)
					( objectStatus "R2U11.2" )
				)
			)
			( gate "@baseboard_fab2_lib.baseboard_fab2(sch_1):page138_i98"
				( attribute "BOM_COST" "SM_CONTROLLER"
					( Origin gFrontEnd )
				)
				( attribute "CDS_LIB" "mstr_discrete"
					( Origin gPackager )
				)
				( attribute "CDS_LOCATION" "R2U3"
					( Origin gPackager )
				)
				( attribute "CDS_SEC" "1"
					( Origin gPackager )
				)
				( attribute "LOCATION" "R2U3"
					( Origin gFrontEnd )
				)
				( attribute "MATERIAL" "CHIP"
					( Origin gFrontEnd )
				)
				( attribute "PACK_TYPE" "0402"
					( Origin gFrontEnd )
				)
				( attribute "PART_NUMBER" "G21796-235"
					( Origin gFrontEnd )
				)
				( attribute "PHYS_PAGE" "138"
					( Origin gFrontEnd )
				)
				( attribute "ROOM" "SMBUS"
					( Origin gFrontEnd )
				)
				( attribute "ROT" "0"
					( Origin gFrontEnd )
				)
				( attribute "SEC" "1"
					( Origin gFrontEnd )
				)
				( attribute "SEC_TYPE" "0402"
					( Origin gFrontEnd )
				)
				( attribute "TOLERANCE" "1.0%"
					( Origin gFrontEnd )
				)
				( attribute "VALUE" "665"
					( Origin gFrontEnd )
				)
				( attribute "VER" "2"
					( Origin gFrontEnd )
				)
				( attribute "WATTAGE" "1/16W"
					( Origin gFrontEnd )
				)
				( attribute "XY" "(-2750,2025)"
					( Origin gFrontEnd )
				)
				( attribute "CHIPS_PART_NAME" "RES"
					( Origin gPackager )
				)
				( attribute "CDS_PART_NAME" "RES_0402-665,1.0%,1/16W,CHIP,GA"
					( Origin gPackager )
				)
				( objectStatus "R2U3" )
				( pin "a"
					( attribute "PN" "1"
						( Origin gPackager )
					)
					( objectStatus "R2U3.1" )
				)
				( pin "b"
					( attribute "PN" "2"
						( Origin gPackager )
					)
					( objectStatus "R2U3.2" )
				)
			)
			( gate "@baseboard_fab2_lib.baseboard_fab2(sch_1):page168_i41"
				( attribute "CDS_LIB" "mstr_discrete"
					( Origin gPackager )
				)
				( attribute "LOCATION" "Q6W2"
					( Origin gFrontEnd )
				)
				( attribute "MATERIAL" "FET"
					( Origin gFrontEnd )
				)
				( attribute "PACK_TYPE" "SOT23"
					( Origin gFrontEnd )
				)
				( attribute "PART_NUMBER" "C79254-001"
					( Origin gFrontEnd )
				)
				( attribute "PHYS_PAGE" "168"
					( Origin gFrontEnd )
				)
				( attribute "ROOM" "V_SUPER"
					( Origin gFrontEnd )
				)
				( attribute "ROT" "0"
					( Origin gFrontEnd )
				)
				( attribute "VALUE" "2N7002"
					( Origin gFrontEnd )
				)
				( attribute "VER" "8"
					( Origin gFrontEnd )
				)
				( attribute "XY" "(-3950,1550)"
					( Origin gFrontEnd )
				)
				( attribute "CHIPS_PART_NAME" "FET_N"
					( Origin gPackager )
				)
				( attribute "CDS_PART_NAME" "FET_N_SOT23-2N7002,FET,C79254-A"
					( Origin gPackager )
				)
				( objectStatus "PAGE168_I41" )
				( pin "drn"
				)
				( pin "gate"
				)
				( pin "src"
				)
			)
			( gate "@baseboard_fab2_lib.baseboard_fab2(sch_1):page138_i158"
				( attribute "BOM_COST" "SM_CONTROLLER"
					( Origin gFrontEnd )
				)
				( attribute "CDS_LIB" "mstr_discrete"
					( Origin gPackager )
				)
				( attribute "CDS_LOCATION" "R2U8"
					( Origin gPackager )
				)
				( attribute "CDS_SEC" "1"
					( Origin gPackager )
				)
				( attribute "LOCATION" "R2U8"
					( Origin gFrontEnd )
				)
				( attribute "MATERIAL" "EMPTY"
					( Origin gFrontEnd )
				)
				( attribute "PACK_TYPE" "0402"
					( Origin gFrontEnd )
				)
				( attribute "PART_NUMBER" "G21796-173"
					( Origin gFrontEnd )
				)
				( attribute "PHYS_PAGE" "138"
					( Origin gFrontEnd )
				)
				( attribute "ROOM" "SMBUS"
					( Origin gFrontEnd )
				)
				( attribute "ROT" "0"
					( Origin gFrontEnd )
				)
				( attribute "SEC" "1"
					( Origin gPackager )
				)
				( attribute "SKU" "A"
					( Origin gFrontEnd )
				)
				( attribute "TOLERANCE" "1%"
					( Origin gFrontEnd )
				)
				( attribute "VALUE" "20.0"
					( Origin gFrontEnd )
				)
				( attribute "VER" "1"
					( Origin gFrontEnd )
				)
				( attribute "WATTAGE" "1/16W"
					( Origin gFrontEnd )
				)
				( attribute "XY" "(-3100,1325)"
					( Origin gFrontEnd )
				)
				( attribute "CHIPS_PART_NAME" "RES"
					( Origin gPackager )
				)
				( attribute "CDS_PART_NAME" "RES_0402-20.0,1%,1/16W,EMPTY,GA"
					( Origin gPackager )
				)
				( objectStatus "R2U8" )
				( pin "a"
					( attribute "PN" "1"
						( Origin gPackager )
					)
					( objectStatus "R2U8.1" )
				)
				( pin "b"
					( attribute "PN" "2"
						( Origin gPackager )
					)
					( objectStatus "R2U8.2" )
				)
			)
			( gate "@baseboard_fab2_lib.baseboard_fab2(sch_1):page138_i159"
				( attribute "BOM_COST" "SM_CONTROLLER"
					( Origin gFrontEnd )
				)
				( attribute "CDS_LIB" "mstr_discrete"
					( Origin gPackager )
				)
				( attribute "CDS_LOCATION" "R2U12"
					( Origin gPackager )
				)
				( attribute "CDS_SEC" "1"
					( Origin gPackager )
				)
				( attribute "LOCATION" "R2U12"
					( Origin gFrontEnd )
				)
				( attribute "MATERIAL" "EMPTY"
					( Origin gFrontEnd )
				)
				( attribute "PACK_TYPE" "0402"
					( Origin gFrontEnd )
				)
				( attribute "PART_NUMBER" "G21796-173"
					( Origin gFrontEnd )
				)
				( attribute "PHYS_PAGE" "138"
					( Origin gFrontEnd )
				)
				( attribute "ROOM" "SMBUS"
					( Origin gFrontEnd )
				)
				( attribute "ROT" "0"
					( Origin gFrontEnd )
				)
				( attribute "SEC" "1"
					( Origin gPackager )
				)
				( attribute "SKU" "A"
					( Origin gFrontEnd )
				)
				( attribute "TOLERANCE" "1%"
					( Origin gFrontEnd )
				)
				( attribute "VALUE" "20.0"
					( Origin gFrontEnd )
				)
				( attribute "VER" "1"
					( Origin gFrontEnd )
				)
				( attribute "WATTAGE" "1/16W"
					( Origin gFrontEnd )
				)
				( attribute "XY" "(-3100,1425)"
					( Origin gFrontEnd )
				)
				( attribute "CHIPS_PART_NAME" "RES"
					( Origin gPackager )
				)
				( attribute "CDS_PART_NAME" "RES_0402-20.0,1%,1/16W,EMPTY,GA"
					( Origin gPackager )
				)
				( objectStatus "R2U12" )
				( pin "a"
					( attribute "PN" "1"
						( Origin gPackager )
					)
					( objectStatus "R2U12.1" )
				)
				( pin "b"
					( attribute "PN" "2"
						( Origin gPackager )
					)
					( objectStatus "R2U12.2" )
				)
			)
			( gate "@baseboard_fab2_lib.baseboard_fab2(sch_1):page155_i198"
				( attribute "BOM_COST" "SM_CONTROLLER"
					( Origin gFrontEnd )
				)
				( attribute "CDS_LIB" "mstr_conn"
					( Origin gPackager )
				)
				( attribute "LOCATION" "J1W1"
					( Origin gFrontEnd )
				)
				( attribute "MATERIAL" "CONN"
					( Origin gFrontEnd )
				)
				( attribute "PACK_TYPE" "PIP"
					( Origin gFrontEnd )
				)
				( attribute "PART_NUMBER" "C95678-002"
					( Origin gFrontEnd )
				)
				( attribute "PHYS_PAGE" "155"
					( Origin gFrontEnd )
				)
				( attribute "ROOM" "SMBUS"
					( Origin gFrontEnd )
				)
				( attribute "ROT" "2"
					( Origin gFrontEnd )
				)
				( attribute "VER" "1"
					( Origin gFrontEnd )
				)
				( attribute "XY" "(-5250,3050)"
					( Origin gFrontEnd )
				)
				( attribute "CHIPS_PART_NAME" "CONN3_C95678002"
					( Origin gPackager )
				)
				( attribute "CDS_PART_NAME" "CONN3_C95678002_PIP-CONN,C9567A"
					( Origin gPackager )
				)
				( objectStatus "PAGE155_I198" )
				( pin "io1"
				)
				( pin "io2"
				)
				( pin "io3"
				)
			)
			( gate "@baseboard_fab2_lib.baseboard_fab2(sch_1):page138_i161"
				( attribute "BOM_COST" "SM_CONTROLLER"
					( Origin gFrontEnd )
				)
				( attribute "CDS_LIB" "mstr_discrete"
					( Origin gPackager )
				)
				( attribute "CDS_LOCATION" "R8D3"
					( Origin gPackager )
				)
				( attribute "CDS_SEC" "1"
					( Origin gPackager )
				)
				( attribute "LOCATION" "R8D3"
					( Origin gFrontEnd )
				)
				( attribute "MATERIAL" "CHIP"
					( Origin gFrontEnd )
				)
				( attribute "PACK_TYPE" "0402"
					( Origin gFrontEnd )
				)
				( attribute "PART_NUMBER" "G21796-173"
					( Origin gFrontEnd )
				)
				( attribute "PHYS_PAGE" "138"
					( Origin gFrontEnd )
				)
				( attribute "ROOM" "SMBUS"
					( Origin gFrontEnd )
				)
				( attribute "ROT" "0"
					( Origin gFrontEnd )
				)
				( attribute "SEC" "1"
					( Origin gFrontEnd )
				)
				( attribute "SEC_TYPE" "0402"
					( Origin gFrontEnd )
				)
				( attribute "TOLERANCE" "1%"
					( Origin gFrontEnd )
				)
				( attribute "VALUE" "20.0"
					( Origin gFrontEnd )
				)
				( attribute "VER" "1"
					( Origin gFrontEnd )
				)
				( attribute "WATTAGE" "1/16W"
					( Origin gFrontEnd )
				)
				( attribute "XY" "(-275,3050)"
					( Origin gFrontEnd )
				)
				( attribute "CHIPS_PART_NAME" "RES"
					( Origin gPackager )
				)
				( attribute "CDS_PART_NAME" "RES_0402-20.0,1%,1/16W,CHIP,G2A"
					( Origin gPackager )
				)
				( objectStatus "R8D3" )
				( pin "a"
					( attribute "PN" "1"
						( Origin gPackager )
					)
					( objectStatus "R8D3.1" )
				)
				( pin "b"
					( attribute "PN" "2"
						( Origin gPackager )
					)
					( objectStatus "R8D3.2" )
				)
			)
			( gate "@baseboard_fab2_lib.baseboard_fab2(sch_1):page138_i162"
				( attribute "BOM_COST" "SM_CONTROLLER"
					( Origin gFrontEnd )
				)
				( attribute "CDS_LIB" "mstr_discrete"
					( Origin gPackager )
				)
				( attribute "CDS_LOCATION" "R8D6"
					( Origin gPackager )
				)
				( attribute "CDS_SEC" "1"
					( Origin gPackager )
				)
				( attribute "LOCATION" "R8D6"
					( Origin gFrontEnd )
				)
				( attribute "MATERIAL" "CHIP"
					( Origin gFrontEnd )
				)
				( attribute "PACK_TYPE" "0402"
					( Origin gFrontEnd )
				)
				( attribute "PART_NUMBER" "G21796-173"
					( Origin gFrontEnd )
				)
				( attribute "PHYS_PAGE" "138"
					( Origin gFrontEnd )
				)
				( attribute "ROOM" "SMBUS"
					( Origin gFrontEnd )
				)
				( attribute "ROT" "0"
					( Origin gFrontEnd )
				)
				( attribute "SEC" "1"
					( Origin gFrontEnd )
				)
				( attribute "SEC_TYPE" "0402"
					( Origin gFrontEnd )
				)
				( attribute "TOLERANCE" "1%"
					( Origin gFrontEnd )
				)
				( attribute "VALUE" "20.0"
					( Origin gFrontEnd )
				)
				( attribute "VER" "1"
					( Origin gFrontEnd )
				)
				( attribute "WATTAGE" "1/16W"
					( Origin gFrontEnd )
				)
				( attribute "XY" "(-275,3225)"
					( Origin gFrontEnd )
				)
				( attribute "CHIPS_PART_NAME" "RES"
					( Origin gPackager )
				)
				( attribute "CDS_PART_NAME" "RES_0402-20.0,1%,1/16W,CHIP,G2A"
					( Origin gPackager )
				)
				( objectStatus "R8D6" )
				( pin "a"
					( attribute "PN" "1"
						( Origin gPackager )
					)
					( objectStatus "R8D6.1" )
				)
				( pin "b"
					( attribute "PN" "2"
						( Origin gPackager )
					)
					( objectStatus "R8D6.2" )
				)
			)
			( gate "@baseboard_fab2_lib.baseboard_fab2(sch_1):page138_i163"
				( attribute "BOM_COST" "SM_CONTROLLER"
					( Origin gFrontEnd )
				)
				( attribute "CDS_LIB" "mstr_discrete"
					( Origin gPackager )
				)
				( attribute "CDS_LOCATION" "R8D7"
					( Origin gPackager )
				)
				( attribute "CDS_SEC" "1"
					( Origin gPackager )
				)
				( attribute "LOCATION" "R8D7"
					( Origin gFrontEnd )
				)
				( attribute "MATERIAL" "CHIP"
					( Origin gFrontEnd )
				)
				( attribute "PACK_TYPE" "0402"
					( Origin gFrontEnd )
				)
				( attribute "PART_NUMBER" "G21796-173"
					( Origin gFrontEnd )
				)
				( attribute "PHYS_PAGE" "138"
					( Origin gFrontEnd )
				)
				( attribute "ROOM" "SMBUS"
					( Origin gFrontEnd )
				)
				( attribute "ROT" "0"
					( Origin gFrontEnd )
				)
				( attribute "SEC" "1"
					( Origin gFrontEnd )
				)
				( attribute "SEC_TYPE" "0402"
					( Origin gFrontEnd )
				)
				( attribute "TOLERANCE" "1%"
					( Origin gFrontEnd )
				)
				( attribute "VALUE" "20.0"
					( Origin gFrontEnd )
				)
				( attribute "VER" "1"
					( Origin gFrontEnd )
				)
				( attribute "WATTAGE" "1/16W"
					( Origin gFrontEnd )
				)
				( attribute "XY" "(-275,2275)"
					( Origin gFrontEnd )
				)
				( attribute "CHIPS_PART_NAME" "RES"
					( Origin gPackager )
				)
				( attribute "CDS_PART_NAME" "RES_0402-20.0,1%,1/16W,CHIP,G2A"
					( Origin gPackager )
				)
				( objectStatus "R8D7" )
				( pin "a"
					( attribute "PN" "1"
						( Origin gPackager )
					)
					( objectStatus "R8D7.1" )
				)
				( pin "b"
					( attribute "PN" "2"
						( Origin gPackager )
					)
					( objectStatus "R8D7.2" )
				)
			)
			( gate "@baseboard_fab2_lib.baseboard_fab2(sch_1):page138_i164"
				( attribute "BOM_COST" "SM_CONTROLLER"
					( Origin gFrontEnd )
				)
				( attribute "CDS_LIB" "mstr_discrete"
					( Origin gPackager )
				)
				( attribute "CDS_LOCATION" "R8D4"
					( Origin gPackager )
				)
				( attribute "CDS_SEC" "1"
					( Origin gPackager )
				)
				( attribute "LOCATION" "R8D4"
					( Origin gFrontEnd )
				)
				( attribute "MATERIAL" "CHIP"
					( Origin gFrontEnd )
				)
				( attribute "PACK_TYPE" "0402"
					( Origin gFrontEnd )
				)
				( attribute "PART_NUMBER" "G21796-173"
					( Origin gFrontEnd )
				)
				( attribute "PHYS_PAGE" "138"
					( Origin gFrontEnd )
				)
				( attribute "ROOM" "SMBUS"
					( Origin gFrontEnd )
				)
				( attribute "ROT" "0"
					( Origin gFrontEnd )
				)
				( attribute "SEC" "1"
					( Origin gFrontEnd )
				)
				( attribute "SEC_TYPE" "0402"
					( Origin gFrontEnd )
				)
				( attribute "TOLERANCE" "1%"
					( Origin gFrontEnd )
				)
				( attribute "VALUE" "20.0"
					( Origin gFrontEnd )
				)
				( attribute "VER" "1"
					( Origin gFrontEnd )
				)
				( attribute "WATTAGE" "1/16W"
					( Origin gFrontEnd )
				)
				( attribute "XY" "(-275,2125)"
					( Origin gFrontEnd )
				)
				( attribute "CHIPS_PART_NAME" "RES"
					( Origin gPackager )
				)
				( attribute "CDS_PART_NAME" "RES_0402-20.0,1%,1/16W,CHIP,G2A"
					( Origin gPackager )
				)
				( objectStatus "R8D4" )
				( pin "a"
					( attribute "PN" "1"
						( Origin gPackager )
					)
					( objectStatus "R8D4.1" )
				)
				( pin "b"
					( attribute "PN" "2"
						( Origin gPackager )
					)
					( objectStatus "R8D4.2" )
				)
			)
			( gate "@baseboard_fab2_lib.baseboard_fab2(sch_1):page138_i165"
				( attribute "BOM_COST" "SM_CONTROLLER"
					( Origin gFrontEnd )
				)
				( attribute "CDS_LIB" "mstr_discrete"
					( Origin gPackager )
				)
				( attribute "CDS_LOCATION" "R2U9"
					( Origin gPackager )
				)
				( attribute "CDS_SEC" "1"
					( Origin gPackager )
				)
				( attribute "LOCATION" "R2U9"
					( Origin gFrontEnd )
				)
				( attribute "MATERIAL" "CHIP"
					( Origin gFrontEnd )
				)
				( attribute "PACK_TYPE" "0402"
					( Origin gFrontEnd )
				)
				( attribute "PART_NUMBER" "G21796-173"
					( Origin gFrontEnd )
				)
				( attribute "PHYS_PAGE" "138"
					( Origin gFrontEnd )
				)
				( attribute "ROOM" "SMBUS"
					( Origin gFrontEnd )
				)
				( attribute "ROT" "0"
					( Origin gFrontEnd )
				)
				( attribute "SEC" "1"
					( Origin gFrontEnd )
				)
				( attribute "SEC_TYPE" "0402"
					( Origin gFrontEnd )
				)
				( attribute "TOLERANCE" "1%"
					( Origin gFrontEnd )
				)
				( attribute "VALUE" "20.0"
					( Origin gFrontEnd )
				)
				( attribute "VER" "1"
					( Origin gFrontEnd )
				)
				( attribute "WATTAGE" "1/16W"
					( Origin gFrontEnd )
				)
				( attribute "XY" "(-3950,1775)"
					( Origin gFrontEnd )
				)
				( attribute "CHIPS_PART_NAME" "RES"
					( Origin gPackager )
				)
				( attribute "CDS_PART_NAME" "RES_0402-20.0,1%,1/16W,CHIP,G2A"
					( Origin gPackager )
				)
				( objectStatus "R2U9" )
				( pin "a"
					( attribute "PN" "1"
						( Origin gPackager )
					)
					( objectStatus "R2U9.1" )
				)
				( pin "b"
					( attribute "PN" "2"
						( Origin gPackager )
					)
					( objectStatus "R2U9.2" )
				)
			)
			( gate "@baseboard_fab2_lib.baseboard_fab2(sch_1):page138_i166"
				( attribute "BOM_COST" "SM_CONTROLLER"
					( Origin gFrontEnd )
				)
				( attribute "CDS_LIB" "mstr_discrete"
					( Origin gPackager )
				)
				( attribute "CDS_LOCATION" "R2U6"
					( Origin gPackager )
				)
				( attribute "CDS_SEC" "1"
					( Origin gPackager )
				)
				( attribute "LOCATION" "R2U6"
					( Origin gFrontEnd )
				)
				( attribute "MATERIAL" "CHIP"
					( Origin gFrontEnd )
				)
				( attribute "PACK_TYPE" "0402"
					( Origin gFrontEnd )
				)
				( attribute "PART_NUMBER" "G21796-173"
					( Origin gFrontEnd )
				)
				( attribute "PHYS_PAGE" "138"
					( Origin gFrontEnd )
				)
				( attribute "ROOM" "SMBUS"
					( Origin gFrontEnd )
				)
				( attribute "ROT" "0"
					( Origin gFrontEnd )
				)
				( attribute "SEC" "1"
					( Origin gFrontEnd )
				)
				( attribute "SEC_TYPE" "0402"
					( Origin gFrontEnd )
				)
				( attribute "TOLERANCE" "1%"
					( Origin gFrontEnd )
				)
				( attribute "VALUE" "20.0"
					( Origin gFrontEnd )
				)
				( attribute "VER" "1"
					( Origin gFrontEnd )
				)
				( attribute "WATTAGE" "1/16W"
					( Origin gFrontEnd )
				)
				( attribute "XY" "(-3950,1625)"
					( Origin gFrontEnd )
				)
				( attribute "CHIPS_PART_NAME" "RES"
					( Origin gPackager )
				)
				( attribute "CDS_PART_NAME" "RES_0402-20.0,1%,1/16W,CHIP,G2A"
					( Origin gPackager )
				)
				( objectStatus "R2U6" )
				( pin "a"
					( attribute "PN" "1"
						( Origin gPackager )
					)
					( objectStatus "R2U6.1" )
				)
				( pin "b"
					( attribute "PN" "2"
						( Origin gPackager )
					)
					( objectStatus "R2U6.2" )
				)
			)
			( gate "@baseboard_fab2_lib.baseboard_fab2(sch_1):page138_i167"
				( attribute "BOM_COST" "SM_CONTROLLER"
					( Origin gFrontEnd )
				)
				( attribute "CDS_LIB" "mstr_discrete"
					( Origin gPackager )
				)
				( attribute "CDS_LOCATION" "R8C20"
					( Origin gPackager )
				)
				( attribute "CDS_SEC" "1"
					( Origin gPackager )
				)
				( attribute "LOCATION" "R8C20"
					( Origin gFrontEnd )
				)
				( attribute "MATERIAL" "CHIP"
					( Origin gFrontEnd )
				)
				( attribute "PACK_TYPE" "0402"
					( Origin gFrontEnd )
				)
				( attribute "PART_NUMBER" "G21796-173"
					( Origin gFrontEnd )
				)
				( attribute "PHYS_PAGE" "138"
					( Origin gFrontEnd )
				)
				( attribute "ROOM" "SMBUS"
					( Origin gFrontEnd )
				)
				( attribute "ROT" "0"
					( Origin gFrontEnd )
				)
				( attribute "SEC" "1"
					( Origin gFrontEnd )
				)
				( attribute "SEC_TYPE" "0402"
					( Origin gFrontEnd )
				)
				( attribute "TOLERANCE" "1%"
					( Origin gFrontEnd )
				)
				( attribute "VALUE" "20.0"
					( Origin gFrontEnd )
				)
				( attribute "VER" "1"
					( Origin gFrontEnd )
				)
				( attribute "WATTAGE" "1/16W"
					( Origin gFrontEnd )
				)
				( attribute "XY" "(-3975,3700)"
					( Origin gFrontEnd )
				)
				( attribute "CHIPS_PART_NAME" "RES"
					( Origin gPackager )
				)
				( attribute "CDS_PART_NAME" "RES_0402-20.0,1%,1/16W,CHIP,G2A"
					( Origin gPackager )
				)
				( objectStatus "R8C20" )
				( pin "a"
					( attribute "PN" "1"
						( Origin gPackager )
					)
					( objectStatus "R8C20.1" )
				)
				( pin "b"
					( attribute "PN" "2"
						( Origin gPackager )
					)
					( objectStatus "R8C20.2" )
				)
			)
			( gate "@baseboard_fab2_lib.baseboard_fab2(sch_1):page138_i168"
				( attribute "BOM_COST" "SM_CONTROLLER"
					( Origin gFrontEnd )
				)
				( attribute "CDS_LIB" "mstr_discrete"
					( Origin gPackager )
				)
				( attribute "CDS_LOCATION" "R8C14"
					( Origin gPackager )
				)
				( attribute "CDS_SEC" "1"
					( Origin gPackager )
				)
				( attribute "LOCATION" "R8C14"
					( Origin gFrontEnd )
				)
				( attribute "MATERIAL" "CHIP"
					( Origin gFrontEnd )
				)
				( attribute "PACK_TYPE" "0402"
					( Origin gFrontEnd )
				)
				( attribute "PART_NUMBER" "G21796-173"
					( Origin gFrontEnd )
				)
				( attribute "PHYS_PAGE" "138"
					( Origin gFrontEnd )
				)
				( attribute "ROOM" "SMBUS"
					( Origin gFrontEnd )
				)
				( attribute "ROT" "0"
					( Origin gFrontEnd )
				)
				( attribute "SEC" "1"
					( Origin gFrontEnd )
				)
				( attribute "SEC_TYPE" "0402"
					( Origin gFrontEnd )
				)
				( attribute "TOLERANCE" "1%"
					( Origin gFrontEnd )
				)
				( attribute "VALUE" "20.0"
					( Origin gFrontEnd )
				)
				( attribute "VER" "1"
					( Origin gFrontEnd )
				)
				( attribute "WATTAGE" "1/16W"
					( Origin gFrontEnd )
				)
				( attribute "XY" "(-3975,3550)"
					( Origin gFrontEnd )
				)
				( attribute "CHIPS_PART_NAME" "RES"
					( Origin gPackager )
				)
				( attribute "CDS_PART_NAME" "RES_0402-20.0,1%,1/16W,CHIP,G2A"
					( Origin gPackager )
				)
				( objectStatus "R8C14" )
				( pin "a"
					( attribute "PN" "1"
						( Origin gPackager )
					)
					( objectStatus "R8C14.1" )
				)
				( pin "b"
					( attribute "PN" "2"
						( Origin gPackager )
					)
					( objectStatus "R8C14.2" )
				)
			)
			( gate "@baseboard_fab2_lib.baseboard_fab2(sch_1):page138_i169"
				( attribute "BOM_COST" "SM_CONTROLLER"
					( Origin gFrontEnd )
				)
				( attribute "CDS_LIB" "mstr_discrete"
					( Origin gPackager )
				)
				( attribute "CDS_LOCATION" "R8C11"
					( Origin gPackager )
				)
				( attribute "CDS_SEC" "1"
					( Origin gPackager )
				)
				( attribute "LOCATION" "R8C11"
					( Origin gFrontEnd )
				)
				( attribute "MATERIAL" "CHIP"
					( Origin gFrontEnd )
				)
				( attribute "PACK_TYPE" "0402"
					( Origin gFrontEnd )
				)
				( attribute "PART_NUMBER" "G21796-173"
					( Origin gFrontEnd )
				)
				( attribute "PHYS_PAGE" "138"
					( Origin gFrontEnd )
				)
				( attribute "ROOM" "SMBUS"
					( Origin gFrontEnd )
				)
				( attribute "ROT" "0"
					( Origin gFrontEnd )
				)
				( attribute "SEC" "1"
					( Origin gFrontEnd )
				)
				( attribute "SEC_TYPE" "0402"
					( Origin gFrontEnd )
				)
				( attribute "TOLERANCE" "1%"
					( Origin gFrontEnd )
				)
				( attribute "VALUE" "20.0"
					( Origin gFrontEnd )
				)
				( attribute "VER" "1"
					( Origin gFrontEnd )
				)
				( attribute "WATTAGE" "1/16W"
					( Origin gFrontEnd )
				)
				( attribute "XY" "(-3975,4625)"
					( Origin gFrontEnd )
				)
				( attribute "CHIPS_PART_NAME" "RES"
					( Origin gPackager )
				)
				( attribute "CDS_PART_NAME" "RES_0402-20.0,1%,1/16W,CHIP,G2A"
					( Origin gPackager )
				)
				( objectStatus "R8C11" )
				( pin "a"
					( attribute "PN" "1"
						( Origin gPackager )
					)
					( objectStatus "R8C11.1" )
				)
				( pin "b"
					( attribute "PN" "2"
						( Origin gPackager )
					)
					( objectStatus "R8C11.2" )
				)
			)
			( gate "@baseboard_fab2_lib.baseboard_fab2(sch_1):page138_i170"
				( attribute "BOM_COST" "SM_CONTROLLER"
					( Origin gFrontEnd )
				)
				( attribute "CDS_LIB" "mstr_discrete"
					( Origin gPackager )
				)
				( attribute "CDS_LOCATION" "R8C12"
					( Origin gPackager )
				)
				( attribute "CDS_SEC" "1"
					( Origin gPackager )
				)
				( attribute "LOCATION" "R8C12"
					( Origin gFrontEnd )
				)
				( attribute "MATERIAL" "CHIP"
					( Origin gFrontEnd )
				)
				( attribute "PACK_TYPE" "0402"
					( Origin gFrontEnd )
				)
				( attribute "PART_NUMBER" "G21796-173"
					( Origin gFrontEnd )
				)
				( attribute "PHYS_PAGE" "138"
					( Origin gFrontEnd )
				)
				( attribute "ROOM" "SMBUS"
					( Origin gFrontEnd )
				)
				( attribute "ROT" "0"
					( Origin gFrontEnd )
				)
				( attribute "SEC" "1"
					( Origin gFrontEnd )
				)
				( attribute "SEC_TYPE" "0402"
					( Origin gFrontEnd )
				)
				( attribute "TOLERANCE" "1%"
					( Origin gFrontEnd )
				)
				( attribute "VALUE" "20.0"
					( Origin gFrontEnd )
				)
				( attribute "VER" "1"
					( Origin gFrontEnd )
				)
				( attribute "WATTAGE" "1/16W"
					( Origin gFrontEnd )
				)
				( attribute "XY" "(-3975,4475)"
					( Origin gFrontEnd )
				)
				( attribute "CHIPS_PART_NAME" "RES"
					( Origin gPackager )
				)
				( attribute "CDS_PART_NAME" "RES_0402-20.0,1%,1/16W,CHIP,G2A"
					( Origin gPackager )
				)
				( objectStatus "R8C12" )
				( pin "a"
					( attribute "PN" "1"
						( Origin gPackager )
					)
					( objectStatus "R8C12.1" )
				)
				( pin "b"
					( attribute "PN" "2"
						( Origin gPackager )
					)
					( objectStatus "R8C12.2" )
				)
			)
			( gate "@baseboard_fab2_lib.baseboard_fab2(sch_1):page138_i171"
				( attribute "BOM_COST" "SM_CONTROLLER"
					( Origin gFrontEnd )
				)
				( attribute "CDS_LIB" "mstr_discrete"
					( Origin gPackager )
				)
				( attribute "CDS_LOCATION" "R2N20"
					( Origin gPackager )
				)
				( attribute "CDS_SEC" "1"
					( Origin gPackager )
				)
				( attribute "LOCATION" "R2N20"
					( Origin gFrontEnd )
				)
				( attribute "MATERIAL" "CHIP"
					( Origin gFrontEnd )
				)
				( attribute "PACK_TYPE" "0402"
					( Origin gFrontEnd )
				)
				( attribute "PART_NUMBER" "G21497-005"
					( Origin gFrontEnd )
				)
				( attribute "PHYS_PAGE" "138"
					( Origin gFrontEnd )
				)
				( attribute "ROOM" "SMBUS"
					( Origin gFrontEnd )
				)
				( attribute "ROT" "0"
					( Origin gFrontEnd )
				)
				( attribute "SEC" "1"
					( Origin gFrontEnd )
				)
				( attribute "SEC_TYPE" "0402"
					( Origin gFrontEnd )
				)
				( attribute "TOLERANCE" "5%"
					( Origin gFrontEnd )
				)
				( attribute "VALUE" "0.0"
					( Origin gFrontEnd )
				)
				( attribute "VER" "1"
					( Origin gFrontEnd )
				)
				( attribute "WATTAGE" "1/16W"
					( Origin gFrontEnd )
				)
				( attribute "XY" "(-3975,2150)"
					( Origin gFrontEnd )
				)
				( attribute "CHIPS_PART_NAME" "RES"
					( Origin gPackager )
				)
				( attribute "CDS_PART_NAME" "RES_0402-0.0,5%,1/16W,CHIP,G21A"
					( Origin gPackager )
				)
				( objectStatus "R2N20" )
				( pin "a"
					( attribute "PN" "1"
						( Origin gPackager )
					)
					( objectStatus "R2N20.1" )
				)
				( pin "b"
					( attribute "PN" "2"
						( Origin gPackager )
					)
					( objectStatus "R2N20.2" )
				)
			)
			( gate "@baseboard_fab2_lib.baseboard_fab2(sch_1):page138_i173"
				( attribute "BOM_COST" "SM_CONTROLLER"
					( Origin gFrontEnd )
				)
				( attribute "CDS_LIB" "mstr_discrete"
					( Origin gPackager )
				)
				( attribute "CDS_LOCATION" "R8B27"
					( Origin gPackager )
				)
				( attribute "CDS_SEC" "1"
					( Origin gPackager )
				)
				( attribute "LOCATION" "R8B27"
					( Origin gFrontEnd )
				)
				( attribute "MATERIAL" "CHIP"
					( Origin gFrontEnd )
				)
				( attribute "PACK_TYPE" "0402"
					( Origin gFrontEnd )
				)
				( attribute "PART_NUMBER" "G21796-173"
					( Origin gFrontEnd )
				)
				( attribute "PHYS_PAGE" "138"
					( Origin gFrontEnd )
				)
				( attribute "ROOM" "SMBUS"
					( Origin gFrontEnd )
				)
				( attribute "ROT" "0"
					( Origin gFrontEnd )
				)
				( attribute "SEC" "1"
					( Origin gFrontEnd )
				)
				( attribute "SEC_TYPE" "0402"
					( Origin gFrontEnd )
				)
				( attribute "TOLERANCE" "1%"
					( Origin gFrontEnd )
				)
				( attribute "VALUE" "20.0"
					( Origin gFrontEnd )
				)
				( attribute "VER" "1"
					( Origin gFrontEnd )
				)
				( attribute "WATTAGE" "1/16W"
					( Origin gFrontEnd )
				)
				( attribute "XY" "(-3950,2650)"
					( Origin gFrontEnd )
				)
				( attribute "CHIPS_PART_NAME" "RES"
					( Origin gPackager )
				)
				( attribute "CDS_PART_NAME" "RES_0402-20.0,1%,1/16W,CHIP,G2A"
					( Origin gPackager )
				)
				( objectStatus "R8B27" )
				( pin "a"
					( attribute "PN" "1"
						( Origin gPackager )
					)
					( objectStatus "R8B27.1" )
				)
				( pin "b"
					( attribute "PN" "2"
						( Origin gPackager )
					)
					( objectStatus "R8B27.2" )
				)
			)
			( gate "@baseboard_fab2_lib.baseboard_fab2(sch_1):page138_i174"
				( attribute "BOM_COST" "SM_CONTROLLER"
					( Origin gFrontEnd )
				)
				( attribute "CDS_LIB" "mstr_discrete"
					( Origin gPackager )
				)
				( attribute "CDS_LOCATION" "R8B28"
					( Origin gPackager )
				)
				( attribute "CDS_SEC" "1"
					( Origin gPackager )
				)
				( attribute "LOCATION" "R8B28"
					( Origin gFrontEnd )
				)
				( attribute "MATERIAL" "CHIP"
					( Origin gFrontEnd )
				)
				( attribute "PACK_TYPE" "0402"
					( Origin gFrontEnd )
				)
				( attribute "PART_NUMBER" "G21796-173"
					( Origin gFrontEnd )
				)
				( attribute "PHYS_PAGE" "138"
					( Origin gFrontEnd )
				)
				( attribute "ROOM" "SMBUS"
					( Origin gFrontEnd )
				)
				( attribute "ROT" "0"
					( Origin gFrontEnd )
				)
				( attribute "SEC" "1"
					( Origin gFrontEnd )
				)
				( attribute "SEC_TYPE" "0402"
					( Origin gFrontEnd )
				)
				( attribute "TOLERANCE" "1%"
					( Origin gFrontEnd )
				)
				( attribute "VALUE" "20.0"
					( Origin gFrontEnd )
				)
				( attribute "VER" "1"
					( Origin gFrontEnd )
				)
				( attribute "WATTAGE" "1/16W"
					( Origin gFrontEnd )
				)
				( attribute "XY" "(-3950,2500)"
					( Origin gFrontEnd )
				)
				( attribute "CHIPS_PART_NAME" "RES"
					( Origin gPackager )
				)
				( attribute "CDS_PART_NAME" "RES_0402-20.0,1%,1/16W,CHIP,G2A"
					( Origin gPackager )
				)
				( objectStatus "R8B28" )
				( pin "a"
					( attribute "PN" "1"
						( Origin gPackager )
					)
					( objectStatus "R8B28.1" )
				)
				( pin "b"
					( attribute "PN" "2"
						( Origin gPackager )
					)
					( objectStatus "R8B28.2" )
				)
			)
			( gate "@baseboard_fab2_lib.baseboard_fab2(sch_1):page138_i175"
				( attribute "BOM_COST" "SM_CONTROLLER"
					( Origin gFrontEnd )
				)
				( attribute "CDS_LIB" "mstr_discrete"
					( Origin gPackager )
				)
				( attribute "CDS_LOCATION" "R2N21"
					( Origin gPackager )
				)
				( attribute "CDS_SEC" "1"
					( Origin gPackager )
				)
				( attribute "LOCATION" "R2N21"
					( Origin gFrontEnd )
				)
				( attribute "MATERIAL" "CHIP"
					( Origin gFrontEnd )
				)
				( attribute "PACK_TYPE" "0402"
					( Origin gFrontEnd )
				)
				( attribute "PART_NUMBER" "G21497-005"
					( Origin gFrontEnd )
				)
				( attribute "PHYS_PAGE" "138"
					( Origin gFrontEnd )
				)
				( attribute "ROOM" "SMBUS"
					( Origin gFrontEnd )
				)
				( attribute "ROT" "0"
					( Origin gFrontEnd )
				)
				( attribute "SEC" "1"
					( Origin gFrontEnd )
				)
				( attribute "SEC_TYPE" "0402"
					( Origin gFrontEnd )
				)
				( attribute "TOLERANCE" "5%"
					( Origin gFrontEnd )
				)
				( attribute "VALUE" "0.0"
					( Origin gFrontEnd )
				)
				( attribute "VER" "1"
					( Origin gFrontEnd )
				)
				( attribute "WATTAGE" "1/16W"
					( Origin gFrontEnd )
				)
				( attribute "XY" "(-3975,2000)"
					( Origin gFrontEnd )
				)
				( attribute "CHIPS_PART_NAME" "RES"
					( Origin gPackager )
				)
				( attribute "CDS_PART_NAME" "RES_0402-0.0,5%,1/16W,CHIP,G21A"
					( Origin gPackager )
				)
				( objectStatus "R2N21" )
				( pin "a"
					( attribute "PN" "1"
						( Origin gPackager )
					)
					( objectStatus "R2N21.1" )
				)
				( pin "b"
					( attribute "PN" "2"
						( Origin gPackager )
					)
					( objectStatus "R2N21.2" )
				)
			)
			( gate "@baseboard_fab2_lib.baseboard_fab2(sch_1):page139_i72"
				( attribute "BOM_COST" "NT_GBE_BASE"
					( Origin gFrontEnd )
				)
				( attribute "CDS_LIB" "mstr_intel"
					( Origin gPackager )
				)
				( attribute "CDS_LOCATION" "EU9E1"
					( Origin gPackager )
				)
				( attribute "CDS_SEC" "1"
					( Origin gPackager )
				)
				( attribute "LOCATION" "EU9E1"
					( Origin gFrontEnd )
				)
				( attribute "MATERIAL" "IC"
					( Origin gFrontEnd )
				)
				( attribute "PACK_TYPE" "SM1"
					( Origin gFrontEnd )
				)
				( attribute "PART_NUMBER" "G47144-004"
					( Origin gFrontEnd )
				)
				( attribute "PHYS_PAGE" "139"
					( Origin gFrontEnd )
				)
				( attribute "ROOM" "NIC_SPRV"
					( Origin gFrontEnd )
				)
				( attribute "ROT" "0"
					( Origin gFrontEnd )
				)
				( attribute "SEC" "1"
					( Origin gFrontEnd )
				)
				( attribute "SEC_TYPE" "SM1"
					( Origin gFrontEnd )
				)
				( attribute "VER" "2"
					( Origin gFrontEnd )
				)
				( attribute "XY" "(-4200,3125)"
					( Origin gFrontEnd )
				)
				( attribute "CHIPS_PART_NAME" "SPRINGVILLE"
					( Origin gPackager )
				)
				( attribute "CDS_PART_NAME" "SPRINGVILLE_SM1-IC,G47144-004"
					( Origin gPackager )
				)
				( objectStatus "EU9E1" )
				( pin "cbot"
					( attribute "PN" "37"
						( Origin gPackager )
					)
					( objectStatus "EU9E1.37" )
				)
				( pin "ctop"
					( attribute "PN" "40"
						( Origin gPackager )
					)
					( objectStatus "EU9E1.40" )
				)
				( pin "dev_off_n"
					( attribute "PN" "28"
						( Origin gPackager )
					)
					( objectStatus "EU9E1.28" )
				)
				( pin "gnd"
					( attribute "PN" "65"
						( Origin gPackager )
					)
					( objectStatus "EU9E1.65" )
				)
				( pin "jtag_clk"
					( attribute "PN" "19"
						( Origin gPackager )
					)
					( objectStatus "EU9E1.19" )
				)
				( pin "jtag_tdi"
					( attribute "PN" "29"
						( Origin gPackager )
					)
					( objectStatus "EU9E1.29" )
				)
				( pin "jtag_tdo"
					( attribute "PN" "4"
						( Origin gPackager )
					)
					( objectStatus "EU9E1.4" )
				)
				( pin "jtag_tms"
					( attribute "PN" "18"
						( Origin gPackager )
					)
					( objectStatus "EU9E1.18" )
				)
				( pin "lan_pwr_good"
					( attribute "PN" "1"
						( Origin gPackager )
					)
					( objectStatus "EU9E1.1" )
				)
				( pin "led0"
					( attribute "PN" "31"
						( Origin gPackager )
					)
					( objectStatus "EU9E1.31" )
				)
				( pin "led1"
					( attribute "PN" "30"
						( Origin gPackager )
					)
					( objectStatus "EU9E1.30" )
				)
				( pin "led2"
					( attribute "PN" "33"
						( Origin gPackager )
					)
					( objectStatus "EU9E1.33" )
				)
				( pin "mdi_minus0_sfp_i2c_data"
					( attribute "PN" "57"
						( Origin gPackager )
					)
					( objectStatus "EU9E1.57" )
				)
				( pin "mdi_minus1_srds_sig_det"
					( attribute "PN" "54"
						( Origin gPackager )
					)
					( objectStatus "EU9E1.54" )
				)
				( pin "mdi_minus2_setn"
					( attribute "PN" "52"
						( Origin gPackager )
					)
					( objectStatus "EU9E1.52" )
				)
				( pin "mdi_minus3_sern"
					( attribute "PN" "49"
						( Origin gPackager )
					)
					( objectStatus "EU9E1.49" )
				)
				( pin "mdi_plus0_nc"
					( attribute "PN" "58"
						( Origin gPackager )
					)
					( objectStatus "EU9E1.58" )
				)
				( pin "mdi_plus1_sfp_i2c_clk"
					( attribute "PN" "55"
						( Origin gPackager )
					)
					( objectStatus "EU9E1.55" )
				)
				( pin "mdi_plus2_setp"
					( attribute "PN" "53"
						( Origin gPackager )
					)
					( objectStatus "EU9E1.53" )
				)
				( pin "mdi_plus3_serp"
					( attribute "PN" "50"
						( Origin gPackager )
					)
					( objectStatus "EU9E1.50" )
				)
				( pin "nc"
					( attribute "PN" "22"
						( Origin gPackager )
					)
					( objectStatus "EU9E1.22" )
				)
				( pin "nc_si_arb_in"
					( attribute "PN" "43"
						( Origin gPackager )
					)
					( objectStatus "EU9E1.43" )
				)
				( pin "nc_si_arb_out"
					( attribute "PN" "44"
						( Origin gPackager )
					)
					( objectStatus "EU9E1.44" )
				)
				( pin "nc_si_clk_in"
					( attribute "PN" "2"
						( Origin gPackager )
					)
					( objectStatus "EU9E1.2" )
				)
				( pin "nc_si_crs_dv"
					( attribute "PN" "3"
						( Origin gPackager )
					)
					( objectStatus "EU9E1.3" )
				)
				( pin "nc_si_rxd0"
					( attribute "PN" "6"
						( Origin gPackager )
					)
					( objectStatus "EU9E1.6" )
				)
				( pin "nc_si_rxd1"
					( attribute "PN" "5"
						( Origin gPackager )
					)
					( objectStatus "EU9E1.5" )
				)
				( pin "nc_si_tx_en"
					( attribute "PN" "7"
						( Origin gPackager )
					)
					( objectStatus "EU9E1.7" )
				)
				( pin "nc_si_txd0"
					( attribute "PN" "9"
						( Origin gPackager )
					)
					( objectStatus "EU9E1.9" )
				)
				( pin "nc_si_txd1"
					( attribute "PN" "8"
						( Origin gPackager )
					)
					( objectStatus "EU9E1.8" )
				)
				( pin "nvm_cs_n"
					( attribute "PN" "15"
						( Origin gPackager )
					)
					( objectStatus "EU9E1.15" )
				)
				( pin "nvm_si"
					( attribute "PN" "12"
						( Origin gPackager )
					)
					( objectStatus "EU9E1.12" )
				)
				( pin "nvm_sk"
					( attribute "PN" "13"
						( Origin gPackager )
					)
					( objectStatus "EU9E1.13" )
				)
				( pin "nvm_so"
					( attribute "PN" "14"
						( Origin gPackager )
					)
					( objectStatus "EU9E1.14" )
				)
				( pin "pe_rn"
					( attribute "PN" "23"
						( Origin gPackager )
					)
					( objectStatus "EU9E1.23" )
				)
				( pin "pe_rp"
					( attribute "PN" "24"
						( Origin gPackager )
					)
					( objectStatus "EU9E1.24" )
				)
				( pin "pe_rst_n"
					( attribute "PN" "17"
						( Origin gPackager )
					)
					( objectStatus "EU9E1.17" )
				)
				( pin "pe_tn"
					( attribute "PN" "20"
						( Origin gPackager )
					)
					( objectStatus "EU9E1.20" )
				)
				( pin "pe_tp"
					( attribute "PN" "21"
						( Origin gPackager )
					)
					( objectStatus "EU9E1.21" )
				)
				( pin "pe_wake_n"
					( attribute "PN" "16"
						( Origin gPackager )
					)
					( objectStatus "EU9E1.16" )
				)
				( pin "peclkn"
					( attribute "PN" "25"
						( Origin gPackager )
					)
					( objectStatus "EU9E1.25" )
				)
				( pin "peclkp"
					( attribute "PN" "26"
						( Origin gPackager )
					)
					( objectStatus "EU9E1.26" )
				)
				( pin "rset"
					( attribute "PN" "48"
						( Origin gPackager )
					)
					( objectStatus "EU9E1.48" )
				)
				( pin "sdp0"
					( attribute "PN" "63"
						( Origin gPackager )
					)
					( objectStatus "EU9E1.63" )
				)
				( pin "sdp1_pcie_dis_sdp1"
					( attribute "PN" "61"
						( Origin gPackager )
					)
					( objectStatus "EU9E1.61" )
				)
				( pin "sdp2"
					( attribute "PN" "62"
						( Origin gPackager )
					)
					( objectStatus "EU9E1.62" )
				)
				( pin "sdp3"
					( attribute "PN" "60"
						( Origin gPackager )
					)
					( objectStatus "EU9E1.60" )
				)
				( pin "smb_alrt_n"
					( attribute "PN" "35"
						( Origin gPackager )
					)
					( objectStatus "EU9E1.35" )
				)
				( pin "smb_clk"
					( attribute "PN" "34"
						( Origin gPackager )
					)
					( objectStatus "EU9E1.34" )
				)
				( pin "smb_data"
					( attribute "PN" "36"
						( Origin gPackager )
					)
					( objectStatus "EU9E1.36" )
				)
				( pin "vdd0p9(0)"
					( attribute "PN" "59"
						( Origin gPackager )
					)
					( objectStatus "EU9E1.59" )
				)
				( pin "vdd0p9(1)"
					( attribute "PN" "32"
						( Origin gPackager )
					)
					( objectStatus "EU9E1.32" )
				)
				( pin "vdd0p9(2)"
					( attribute "PN" "11"
						( Origin gPackager )
					)
					( objectStatus "EU9E1.11" )
				)
				( pin "vdd0p9(3)"
					( attribute "PN" "42"
						( Origin gPackager )
					)
					( objectStatus "EU9E1.42" )
				)
				( pin "vdd0p9_out"
					( attribute "PN" "38"
						( Origin gPackager )
					)
					( objectStatus "EU9E1.38" )
				)
				( pin "vdd1p5(0)"
					( attribute "PN" "56"
						( Origin gPackager )
					)
					( objectStatus "EU9E1.56" )
				)
				( pin "vdd1p5(1)"
					( attribute "PN" "47"
						( Origin gPackager )
					)
					( objectStatus "EU9E1.47" )
				)
				( pin "vdd1p5_out"
					( attribute "PN" "39"
						( Origin gPackager )
					)
					( objectStatus "EU9E1.39" )
				)
				( pin "vdd3p3(0)"
					( attribute "PN" "64"
						( Origin gPackager )
					)
					( objectStatus "EU9E1.64" )
				)
				( pin "vdd3p3(1)"
					( attribute "PN" "51"
						( Origin gPackager )
					)
					( objectStatus "EU9E1.51" )
				)
				( pin "vdd3p3(2)"
					( attribute "PN" "41"
						( Origin gPackager )
					)
					( objectStatus "EU9E1.41" )
				)
				( pin "vdd3p3(3)"
					( attribute "PN" "27"
						( Origin gPackager )
					)
					( objectStatus "EU9E1.27" )
				)
				( pin "vdd3p3(4)"
					( attribute "PN" "10"
						( Origin gPackager )
					)
					( objectStatus "EU9E1.10" )
				)
				( pin "xtal1"
					( attribute "PN" "46"
						( Origin gPackager )
					)
					( objectStatus "EU9E1.46" )
				)
				( pin "xtal2"
					( attribute "PN" "45"
						( Origin gPackager )
					)
					( objectStatus "EU9E1.45" )
				)
			)
			( gate "@baseboard_fab2_lib.baseboard_fab2(sch_1):page139_i76"
				( attribute "BOM_COST" "NT_GBE_BASE"
					( Origin gFrontEnd )
				)
				( attribute "CDS_LIB" "mstr_discrete"
					( Origin gPackager )
				)
				( attribute "CDS_LOCATION" "C9E7"
					( Origin gPackager )
				)
				( attribute "CDS_SEC" "1"
					( Origin gPackager )
				)
				( attribute "LOCATION" "C9E7"
					( Origin gFrontEnd )
				)
				( attribute "MATERIAL" "X7R"
					( Origin gFrontEnd )
				)
				( attribute "PACK_TYPE" "0402LF"
					( Origin gFrontEnd )
				)
				( attribute "PART_NUMBER" "A36096-063"
					( Origin gFrontEnd )
				)
				( attribute "PHYS_PAGE" "139"
					( Origin gFrontEnd )
				)
				( attribute "ROOM" "NIC_SPRV"
					( Origin gFrontEnd )
				)
				( attribute "ROT" "0"
					( Origin gFrontEnd )
				)
				( attribute "SEC" "1"
					( Origin gFrontEnd )
				)
				( attribute "SEC_TYPE" "0402LF"
					( Origin gFrontEnd )
				)
				( attribute "TOLERANCE" "10%"
					( Origin gFrontEnd )
				)
				( attribute "VALUE" "0.039UF"
					( Origin gFrontEnd )
				)
				( attribute "VER" "1"
					( Origin gFrontEnd )
				)
				( attribute "VOLTAGE" "25V"
					( Units "uVoltage" "V" 1.000000)
					( Origin gFrontEnd )
				)
				( attribute "XY" "(-2725,3500)"
					( Origin gFrontEnd )
				)
				( attribute "CHIPS_PART_NAME" "CAP"
					( Origin gPackager )
				)
				( attribute "CDS_PART_NAME" "CAP_0402LF-0.039UF,25V,10%,X7RA"
					( Origin gPackager )
				)
				( objectStatus "C9E7" )
				( pin "a"
					( attribute "PN" "1"
						( Origin gPackager )
					)
					( objectStatus "C9E7.1" )
				)
				( pin "b"
					( attribute "PN" "2"
						( Origin gPackager )
					)
					( objectStatus "C9E7.2" )
				)
			)
			( gate "@baseboard_fab2_lib.baseboard_fab2(sch_1):page139_i87"
				( attribute "BOM_COST" "NT_GBE_BASE"
					( Origin gFrontEnd )
				)
				( attribute "CDS_LIB" "dev_discrete"
					( Origin gPackager )
				)
				( attribute "CDS_LOCATION" "C9E5"
					( Origin gPackager )
				)
				( attribute "CDS_SEC" "1"
					( Origin gPackager )
				)
				( attribute "LOCATION" "C9E5"
					( Origin gFrontEnd )
				)
				( attribute "MATERIAL" "X7R"
					( Origin gFrontEnd )
				)
				( attribute "PACK_TYPE" "0402V"
					( Origin gFrontEnd )
				)
				( attribute "PART_NUMBER" "A36096-030"
					( Origin gFrontEnd )
				)
				( attribute "PHYS_PAGE" "139"
					( Origin gFrontEnd )
				)
				( attribute "ROOM" "NIC_SPRV"
					( Origin gFrontEnd )
				)
				( attribute "ROT" "0"
					( Origin gFrontEnd )
				)
				( attribute "SEC" "1"
					( Origin gFrontEnd )
				)
				( attribute "SEC_TYPE" "0402V"
					( Origin gFrontEnd )
				)
				( attribute "TOLERANCE" "10%"
					( Origin gFrontEnd )
				)
				( attribute "VALUE" "0.1UF"
					( Origin gFrontEnd )
				)
				( attribute "VER" "2"
					( Origin gFrontEnd )
				)
				( attribute "VOLTAGE" "16V"
					( Units "uVoltage" "V" 1.000000)
					( Origin gFrontEnd )
				)
				( attribute "XY" "(-1650,2075)"
					( Origin gFrontEnd )
				)
				( attribute "CHIPS_PART_NAME" "CAP_A"
					( Origin gPackager )
				)
				( attribute "CDS_PART_NAME" "CAP_A_0402V-0.1UF,16V,10%,X7R,A"
					( Origin gPackager )
				)
				( objectStatus "C9E5" )
				( pin "a"
					( attribute "PN" "1"
						( Origin gPackager )
					)
					( objectStatus "C9E5.1" )
				)
				( pin "b"
					( attribute "PN" "2"
						( Origin gPackager )
					)
					( objectStatus "C9E5.2" )
				)
			)
			( gate "@baseboard_fab2_lib.baseboard_fab2(sch_1):page139_i88"
				( attribute "BOM_COST" "NT_GBE_BASE"
					( Origin gFrontEnd )
				)
				( attribute "CDS_LIB" "dev_discrete"
					( Origin gPackager )
				)
				( attribute "CDS_LOCATION" "C9E4"
					( Origin gPackager )
				)
				( attribute "CDS_SEC" "1"
					( Origin gPackager )
				)
				( attribute "LOCATION" "C9E4"
					( Origin gFrontEnd )
				)
				( attribute "MATERIAL" "X7R"
					( Origin gFrontEnd )
				)
				( attribute "PACK_TYPE" "0402V"
					( Origin gFrontEnd )
				)
				( attribute "PART_NUMBER" "A36096-030"
					( Origin gFrontEnd )
				)
				( attribute "PHYS_PAGE" "139"
					( Origin gFrontEnd )
				)
				( attribute "ROOM" "NIC_SPRV"
					( Origin gFrontEnd )
				)
				( attribute "ROT" "0"
					( Origin gFrontEnd )
				)
				( attribute "SEC" "1"
					( Origin gFrontEnd )
				)
				( attribute "SEC_TYPE" "0402V"
					( Origin gFrontEnd )
				)
				( attribute "TOLERANCE" "10%"
					( Origin gFrontEnd )
				)
				( attribute "VALUE" "0.1UF"
					( Origin gFrontEnd )
				)
				( attribute "VER" "2"
					( Origin gFrontEnd )
				)
				( attribute "VOLTAGE" "16V"
					( Units "uVoltage" "V" 1.000000)
					( Origin gFrontEnd )
				)
				( attribute "XY" "(-2400,2125)"
					( Origin gFrontEnd )
				)
				( attribute "CHIPS_PART_NAME" "CAP_A"
					( Origin gPackager )
				)
				( attribute "CDS_PART_NAME" "CAP_A_0402V-0.1UF,16V,10%,X7R,A"
					( Origin gPackager )
				)
				( objectStatus "C9E4" )
				( pin "a"
					( attribute "PN" "1"
						( Origin gPackager )
					)
					( objectStatus "C9E4.1" )
				)
				( pin "b"
					( attribute "PN" "2"
						( Origin gPackager )
					)
					( objectStatus "C9E4.2" )
				)
			)
			( gate "@baseboard_fab2_lib.baseboard_fab2(sch_1):page139_i89"
				( attribute "BOM_COST" "NT_GBE_BASE"
					( Origin gFrontEnd )
				)
				( attribute "CDS_LIB" "dev_discrete"
					( Origin gPackager )
				)
				( attribute "CDS_LOCATION" "C2M23"
					( Origin gPackager )
				)
				( attribute "CDS_SEC" "1"
					( Origin gPackager )
				)
				( attribute "LOCATION" "C2M23"
					( Origin gFrontEnd )
				)
				( attribute "MATERIAL" "X7R"
					( Origin gFrontEnd )
				)
				( attribute "PACK_TYPE" "0402V"
					( Origin gFrontEnd )
				)
				( attribute "PART_NUMBER" "A36096-030"
					( Origin gFrontEnd )
				)
				( attribute "PHYS_PAGE" "139"
					( Origin gFrontEnd )
				)
				( attribute "ROOM" "NIC_SPRV"
					( Origin gFrontEnd )
				)
				( attribute "ROT" "0"
					( Origin gFrontEnd )
				)
				( attribute "SEC" "1"
					( Origin gFrontEnd )
				)
				( attribute "SEC_TYPE" "0402V"
					( Origin gFrontEnd )
				)
				( attribute "TOLERANCE" "10%"
					( Origin gFrontEnd )
				)
				( attribute "VALUE" "0.1UF"
					( Origin gFrontEnd )
				)
				( attribute "VER" "2"
					( Origin gFrontEnd )
				)
				( attribute "VOLTAGE" "16V"
					( Units "uVoltage" "V" 1.000000)
					( Origin gFrontEnd )
				)
				( attribute "XY" "(-5775,2125)"
					( Origin gFrontEnd )
				)
				( attribute "CHIPS_PART_NAME" "CAP_A"
					( Origin gPackager )
				)
				( attribute "CDS_PART_NAME" "CAP_A_0402V-0.1UF,16V,10%,X7R,A"
					( Origin gPackager )
				)
				( objectStatus "C2M23" )
				( pin "a"
					( attribute "PN" "1"
						( Origin gPackager )
					)
					( objectStatus "C2M23.1" )
				)
				( pin "b"
					( attribute "PN" "2"
						( Origin gPackager )
					)
					( objectStatus "C2M23.2" )
				)
			)
			( gate "@baseboard_fab2_lib.baseboard_fab2(sch_1):page139_i90"
				( attribute "BOM_COST" "NT_GBE_BASE"
					( Origin gFrontEnd )
				)
				( attribute "CDS_LIB" "dev_discrete"
					( Origin gPackager )
				)
				( attribute "CDS_LOCATION" "C2M24"
					( Origin gPackager )
				)
				( attribute "CDS_SEC" "1"
					( Origin gPackager )
				)
				( attribute "LOCATION" "C2M24"
					( Origin gFrontEnd )
				)
				( attribute "MATERIAL" "X7R"
					( Origin gFrontEnd )
				)
				( attribute "PACK_TYPE" "0402V"
					( Origin gFrontEnd )
				)
				( attribute "PART_NUMBER" "A36096-030"
					( Origin gFrontEnd )
				)
				( attribute "PHYS_PAGE" "139"
					( Origin gFrontEnd )
				)
				( attribute "ROOM" "NIC_SPRV"
					( Origin gFrontEnd )
				)
				( attribute "ROT" "0"
					( Origin gFrontEnd )
				)
				( attribute "SEC" "1"
					( Origin gFrontEnd )
				)
				( attribute "SEC_TYPE" "0402V"
					( Origin gFrontEnd )
				)
				( attribute "TOLERANCE" "10%"
					( Origin gFrontEnd )
				)
				( attribute "VALUE" "0.1UF"
					( Origin gFrontEnd )
				)
				( attribute "VER" "2"
					( Origin gFrontEnd )
				)
				( attribute "VOLTAGE" "16V"
					( Units "uVoltage" "V" 1.000000)
					( Origin gFrontEnd )
				)
				( attribute "XY" "(-6000,2075)"
					( Origin gFrontEnd )
				)
				( attribute "CHIPS_PART_NAME" "CAP_A"
					( Origin gPackager )
				)
				( attribute "CDS_PART_NAME" "CAP_A_0402V-0.1UF,16V,10%,X7R,A"
					( Origin gPackager )
				)
				( objectStatus "C2M24" )
				( pin "a"
					( attribute "PN" "1"
						( Origin gPackager )
					)
					( objectStatus "C2M24.1" )
				)
				( pin "b"
					( attribute "PN" "2"
						( Origin gPackager )
					)
					( objectStatus "C2M24.2" )
				)
			)
			( gate "@baseboard_fab2_lib.baseboard_fab2(sch_1):page139_i109"
				( attribute "BOM_COST" "NT_GBE_BASE"
					( Origin gFrontEnd )
				)
				( attribute "CDS_LIB" "mstr_discrete"
					( Origin gPackager )
				)
				( attribute "CDS_LOCATION" "Y9E1"
					( Origin gPackager )
				)
				( attribute "CDS_SEC" "1"
					( Origin gPackager )
				)
				( attribute "LOCATION" "Y9E1"
					( Origin gFrontEnd )
				)
				( attribute "MATERIAL" "IC"
					( Origin gFrontEnd )
				)
				( attribute "PACK_TYPE" "2013"
					( Origin gFrontEnd )
				)
				( attribute "PART_NUMBER" "D71700-057"
					( Origin gFrontEnd )
				)
				( attribute "PHYS_PAGE" "139"
					( Origin gFrontEnd )
				)
				( attribute "ROOM" "NIC_SPRV"
					( Origin gFrontEnd )
				)
				( attribute "ROT" "0"
					( Origin gFrontEnd )
				)
				( attribute "SEC" "1"
					( Origin gFrontEnd )
				)
				( attribute "SEC_TYPE" "2013"
					( Origin gFrontEnd )
				)
				( attribute "VALUE" "25.000MHZ"
					( Origin gFrontEnd )
				)
				( attribute "VER" "1"
					( Origin gFrontEnd )
				)
				( attribute "XY" "(-7525,1475)"
					( Origin gFrontEnd )
				)
				( attribute "CHIPS_PART_NAME" "CRYSTAL"
					( Origin gPackager )
				)
				( attribute "CDS_PART_NAME" "CRYSTAL_2013-25.000MHZ,IC,D717A"
					( Origin gPackager )
				)
				( objectStatus "Y9E1" )
				( pin "a"
					( attribute "PN" "1"
						( Origin gPackager )
					)
					( objectStatus "Y9E1.1" )
				)
				( pin "b"
					( attribute "PN" "3"
						( Origin gPackager )
					)
					( objectStatus "Y9E1.3" )
				)
			)
			( gate "@baseboard_fab2_lib.baseboard_fab2(sch_1):page139_i110"
				( attribute "BOM_COST" "NT_GBE_BASE"
					( Origin gFrontEnd )
				)
				( attribute "CDS_LIB" "mstr_discrete"
					( Origin gPackager )
				)
				( attribute "CDS_LOCATION" "R9E20"
					( Origin gPackager )
				)
				( attribute "CDS_SEC" "1"
					( Origin gPackager )
				)
				( attribute "LOCATION" "R9E20"
					( Origin gFrontEnd )
				)
				( attribute "MATERIAL" "CHIP"
					( Origin gFrontEnd )
				)
				( attribute "PACK_TYPE" "0402"
					( Origin gFrontEnd )
				)
				( attribute "PART_NUMBER" "G21497-005"
					( Origin gFrontEnd )
				)
				( attribute "PHYS_PAGE" "139"
					( Origin gFrontEnd )
				)
				( attribute "ROOM" "NIC_SPRV"
					( Origin gFrontEnd )
				)
				( attribute "ROT" "0"
					( Origin gFrontEnd )
				)
				( attribute "SEC" "1"
					( Origin gFrontEnd )
				)
				( attribute "SEC_TYPE" "0402"
					( Origin gFrontEnd )
				)
				( attribute "TOLERANCE" "5%"
					( Origin gFrontEnd )
				)
				( attribute "VALUE" "0.0"
					( Origin gFrontEnd )
				)
				( attribute "VER" "1"
					( Origin gFrontEnd )
				)
				( attribute "WATTAGE" "1/16W"
					( Origin gFrontEnd )
				)
				( attribute "XY" "(-6875,1675)"
					( Origin gFrontEnd )
				)
				( attribute "CHIPS_PART_NAME" "RES"
					( Origin gPackager )
				)
				( attribute "CDS_PART_NAME" "RES_0402-0.0,5%,1/16W,CHIP,G21A"
					( Origin gPackager )
				)
				( objectStatus "R9E20" )
				( pin "a"
					( attribute "PN" "1"
						( Origin gPackager )
					)
					( objectStatus "R9E20.1" )
				)
				( pin "b"
					( attribute "PN" "2"
						( Origin gPackager )
					)
					( objectStatus "R9E20.2" )
				)
			)
			( gate "@baseboard_fab2_lib.baseboard_fab2(sch_1):page139_i111"
				( attribute "BOM_COST" "NT_GBE_BASE"
					( Origin gFrontEnd )
				)
				( attribute "CDS_LIB" "mstr_discrete"
					( Origin gPackager )
				)
				( attribute "CDS_LOCATION" "C9E8"
					( Origin gPackager )
				)
				( attribute "CDS_SEC" "1"
					( Origin gPackager )
				)
				( attribute "LOCATION" "C9E8"
					( Origin gFrontEnd )
				)
				( attribute "MATERIAL" "COG"
					( Origin gFrontEnd )
				)
				( attribute "PACK_TYPE" "0402LF"
					( Origin gFrontEnd )
				)
				( attribute "PART_NUMBER" "A36095-030"
					( Origin gFrontEnd )
				)
				( attribute "PHYS_PAGE" "139"
					( Origin gFrontEnd )
				)
				( attribute "ROOM" "NIC_SPRV"
					( Origin gFrontEnd )
				)
				( attribute "ROT" "0"
					( Origin gFrontEnd )
				)
				( attribute "SEC" "1"
					( Origin gFrontEnd )
				)
				( attribute "SEC_TYPE" "0402LF"
					( Origin gFrontEnd )
				)
				( attribute "TOLERANCE" "5%"
					( Origin gFrontEnd )
				)
				( attribute "VALUE" "22.0PF"
					( Origin gFrontEnd )
				)
				( attribute "VER" "1"
					( Origin gFrontEnd )
				)
				( attribute "VOLTAGE" "50V"
					( Units "uVoltage" "V" 1.000000)
					( Origin gFrontEnd )
				)
				( attribute "XY" "(-7325,1275)"
					( Origin gFrontEnd )
				)
				( attribute "CHIPS_PART_NAME" "CAP"
					( Origin gPackager )
				)
				( attribute "CDS_PART_NAME" "CAP_0402LF-22.0PF,50V,5%,COG,AA"
					( Origin gPackager )
				)
				( objectStatus "C9E8" )
				( pin "a"
					( attribute "PN" "1"
						( Origin gPackager )
					)
					( objectStatus "C9E8.1" )
				)
				( pin "b"
					( attribute "PN" "2"
						( Origin gPackager )
					)
					( objectStatus "C9E8.2" )
				)
			)
			( gate "@baseboard_fab2_lib.baseboard_fab2(sch_1):page139_i112"
				( attribute "BOM_COST" "NT_GBE_BASE"
					( Origin gFrontEnd )
				)
				( attribute "CDS_LIB" "mstr_discrete"
					( Origin gPackager )
				)
				( attribute "CDS_LOCATION" "C9E9"
					( Origin gPackager )
				)
				( attribute "CDS_SEC" "1"
					( Origin gPackager )
				)
				( attribute "LOCATION" "C9E9"
					( Origin gFrontEnd )
				)
				( attribute "MATERIAL" "COG"
					( Origin gFrontEnd )
				)
				( attribute "PACK_TYPE" "0402LF"
					( Origin gFrontEnd )
				)
				( attribute "PART_NUMBER" "A36095-030"
					( Origin gFrontEnd )
				)
				( attribute "PHYS_PAGE" "139"
					( Origin gFrontEnd )
				)
				( attribute "ROOM" "NIC_SPRV"
					( Origin gFrontEnd )
				)
				( attribute "ROT" "0"
					( Origin gFrontEnd )
				)
				( attribute "SEC" "1"
					( Origin gFrontEnd )
				)
				( attribute "SEC_TYPE" "0402LF"
					( Origin gFrontEnd )
				)
				( attribute "TOLERANCE" "5%"
					( Origin gFrontEnd )
				)
				( attribute "VALUE" "22.0PF"
					( Origin gFrontEnd )
				)
				( attribute "VER" "1"
					( Origin gFrontEnd )
				)
				( attribute "VOLTAGE" "50V"
					( Units "uVoltage" "V" 1.000000)
					( Origin gFrontEnd )
				)
				( attribute "XY" "(-7750,1275)"
					( Origin gFrontEnd )
				)
				( attribute "CHIPS_PART_NAME" "CAP"
					( Origin gPackager )
				)
				( attribute "CDS_PART_NAME" "CAP_0402LF-22.0PF,50V,5%,COG,AA"
					( Origin gPackager )
				)
				( objectStatus "C9E9" )
				( pin "a"
					( attribute "PN" "1"
						( Origin gPackager )
					)
					( objectStatus "C9E9.1" )
				)
				( pin "b"
					( attribute "PN" "2"
						( Origin gPackager )
					)
					( objectStatus "C9E9.2" )
				)
			)
			( gate "@baseboard_fab2_lib.baseboard_fab2(sch_1):page139_i128"
				( attribute "BOM_COST" "NT_GBE_BASE"
					( Origin gFrontEnd )
				)
				( attribute "CDS_LIB" "mstr_discrete"
					( Origin gPackager )
				)
				( attribute "CDS_LOCATION" "R9E9"
					( Origin gPackager )
				)
				( attribute "CDS_SEC" "1"
					( Origin gPackager )
				)
				( attribute "LOCATION" "R9E9"
					( Origin gFrontEnd )
				)
				( attribute "MATERIAL" "CHIP"
					( Origin gFrontEnd )
				)
				( attribute "PACK_TYPE" "0402"
					( Origin gFrontEnd )
				)
				( attribute "PART_NUMBER" "G21796-074"
					( Origin gFrontEnd )
				)
				( attribute "PHYS_PAGE" "139"
					( Origin gFrontEnd )
				)
				( attribute "ROOM" "NIC_SPRV"
					( Origin gFrontEnd )
				)
				( attribute "ROT" "0"
					( Origin gFrontEnd )
				)
				( attribute "SEC" "1"
					( Origin gFrontEnd )
				)
				( attribute "SEC_TYPE" "0402"
					( Origin gFrontEnd )
				)
				( attribute "TOLERANCE" "1%"
					( Origin gFrontEnd )
				)
				( attribute "VALUE" "33.2"
					( Origin gFrontEnd )
				)
				( attribute "VER" "1"
					( Origin gFrontEnd )
				)
				( attribute "WATTAGE" "1/16W"
					( Origin gFrontEnd )
				)
				( attribute "XY" "(-2425,2375)"
					( Origin gFrontEnd )
				)
				( attribute "CHIPS_PART_NAME" "RES"
					( Origin gPackager )
				)
				( attribute "CDS_PART_NAME" "RES_0402-33.2,1%,1/16W,CHIP,G2A"
					( Origin gPackager )
				)
				( objectStatus "R9E9" )
				( pin "a"
					( attribute "PN" "1"
						( Origin gPackager )
					)
					( objectStatus "R9E9.1" )
				)
				( pin "b"
					( attribute "PN" "2"
						( Origin gPackager )
					)
					( objectStatus "R9E9.2" )
				)
			)
			( gate "@baseboard_fab2_lib.baseboard_fab2(sch_1):page139_i129"
				( attribute "BOM_COST" "NT_GBE_BASE"
					( Origin gFrontEnd )
				)
				( attribute "CDS_LIB" "mstr_discrete"
					( Origin gPackager )
				)
				( attribute "CDS_LOCATION" "R9E5"
					( Origin gPackager )
				)
				( attribute "CDS_SEC" "1"
					( Origin gPackager )
				)
				( attribute "LOCATION" "R9E5"
					( Origin gFrontEnd )
				)
				( attribute "MATERIAL" "CHIP"
					( Origin gFrontEnd )
				)
				( attribute "PACK_TYPE" "0402"
					( Origin gFrontEnd )
				)
				( attribute "PART_NUMBER" "G21796-074"
					( Origin gFrontEnd )
				)
				( attribute "PHYS_PAGE" "139"
					( Origin gFrontEnd )
				)
				( attribute "ROOM" "NIC_SPRV"
					( Origin gFrontEnd )
				)
				( attribute "ROT" "0"
					( Origin gFrontEnd )
				)
				( attribute "SEC" "1"
					( Origin gFrontEnd )
				)
				( attribute "SEC_TYPE" "0402"
					( Origin gFrontEnd )
				)
				( attribute "TOLERANCE" "1%"
					( Origin gFrontEnd )
				)
				( attribute "VALUE" "33.2"
					( Origin gFrontEnd )
				)
				( attribute "VER" "1"
					( Origin gFrontEnd )
				)
				( attribute "WATTAGE" "1/16W"
					( Origin gFrontEnd )
				)
				( attribute "XY" "(-1550,2325)"
					( Origin gFrontEnd )
				)
				( attribute "CHIPS_PART_NAME" "RES"
					( Origin gPackager )
				)
				( attribute "CDS_PART_NAME" "RES_0402-33.2,1%,1/16W,CHIP,G2A"
					( Origin gPackager )
				)
				( objectStatus "R9E5" )
				( pin "a"
					( attribute "PN" "1"
						( Origin gPackager )
					)
					( objectStatus "R9E5.1" )
				)
				( pin "b"
					( attribute "PN" "2"
						( Origin gPackager )
					)
					( objectStatus "R9E5.2" )
				)
			)
			( gate "@baseboard_fab2_lib.baseboard_fab2(sch_1):page139_i130"
				( attribute "BOM_COST" "NT_GBE_BASE"
					( Origin gFrontEnd )
				)
				( attribute "CDS_LIB" "mstr_discrete"
					( Origin gPackager )
				)
				( attribute "CDS_LOCATION" "R9E8"
					( Origin gPackager )
				)
				( attribute "CDS_SEC" "1"
					( Origin gPackager )
				)
				( attribute "LOCATION" "R9E8"
					( Origin gFrontEnd )
				)
				( attribute "MATERIAL" "CHIP"
					( Origin gFrontEnd )
				)
				( attribute "PACK_TYPE" "0402"
					( Origin gFrontEnd )
				)
				( attribute "PART_NUMBER" "G21796-074"
					( Origin gFrontEnd )
				)
				( attribute "PHYS_PAGE" "139"
					( Origin gFrontEnd )
				)
				( attribute "ROOM" "NIC_SPRV"
					( Origin gFrontEnd )
				)
				( attribute "ROT" "0"
					( Origin gFrontEnd )
				)
				( attribute "SEC" "1"
					( Origin gFrontEnd )
				)
				( attribute "SEC_TYPE" "0402"
					( Origin gFrontEnd )
				)
				( attribute "TOLERANCE" "1%"
					( Origin gFrontEnd )
				)
				( attribute "VALUE" "33.2"
					( Origin gFrontEnd )
				)
				( attribute "VER" "1"
					( Origin gFrontEnd )
				)
				( attribute "WATTAGE" "1/16W"
					( Origin gFrontEnd )
				)
				( attribute "XY" "(-2400,2275)"
					( Origin gFrontEnd )
				)
				( attribute "CHIPS_PART_NAME" "RES"
					( Origin gPackager )
				)
				( attribute "CDS_PART_NAME" "RES_0402-33.2,1%,1/16W,CHIP,G2A"
					( Origin gPackager )
				)
				( objectStatus "R9E8" )
				( pin "a"
					( attribute "PN" "1"
						( Origin gPackager )
					)
					( objectStatus "R9E8.1" )
				)
				( pin "b"
					( attribute "PN" "2"
						( Origin gPackager )
					)
					( objectStatus "R9E8.2" )
				)
			)
			( gate "@baseboard_fab2_lib.baseboard_fab2(sch_1):page139_i134"
				( attribute "BOM_COST" "NT_GBE_BASE"
					( Origin gFrontEnd )
				)
				( attribute "CDS_LIB" "mstr_discrete"
					( Origin gPackager )
				)
				( attribute "CDS_LOCATION" "C1T4"
					( Origin gPackager )
				)
				( attribute "CDS_SEC" "1"
					( Origin gPackager )
				)
				( attribute "LOCATION" "C1T4"
					( Origin gFrontEnd )
				)
				( attribute "MATERIAL" "X6S"
					( Origin gFrontEnd )
				)
				( attribute "PACK_TYPE" "0603"
					( Origin gFrontEnd )
				)
				( attribute "PART_NUMBER" "E15431-002"
					( Origin gFrontEnd )
				)
				( attribute "PHYS_PAGE" "139"
					( Origin gFrontEnd )
				)
				( attribute "ROOM" "NIC_SPRV"
					( Origin gFrontEnd )
				)
				( attribute "ROT" "0"
					( Origin gFrontEnd )
				)
				( attribute "SEC" "1"
					( Origin gFrontEnd )
				)
				( attribute "SEC_TYPE" "0603"
					( Origin gFrontEnd )
				)
				( attribute "TOLERANCE" "20%"
					( Origin gFrontEnd )
				)
				( attribute "VALUE" "10UF"
					( Origin gFrontEnd )
				)
				( attribute "VER" "1"
					( Origin gFrontEnd )
				)
				( attribute "VOLTAGE" "6.3V"
					( Units "uVoltage" "V" 1.000000)
					( Origin gFrontEnd )
				)
				( attribute "XY" "(-5975,4275)"
					( Origin gFrontEnd )
				)
				( attribute "CHIPS_PART_NAME" "CAP"
					( Origin gPackager )
				)
				( attribute "CDS_PART_NAME" "CAP_0603-10UF,6.3V,20%,X6S,E15A"
					( Origin gPackager )
				)
				( objectStatus "C1T4" )
				( pin "a"
					( attribute "PN" "1"
						( Origin gPackager )
					)
					( objectStatus "C1T4.1" )
				)
				( pin "b"
					( attribute "PN" "2"
						( Origin gPackager )
					)
					( objectStatus "C1T4.2" )
				)
			)
			( gate "@baseboard_fab2_lib.baseboard_fab2(sch_1):page139_i135"
				( attribute "BOM_COST" "NT_GBE_BASE"
					( Origin gFrontEnd )
				)
				( attribute "CDS_LIB" "mstr_discrete"
					( Origin gPackager )
				)
				( attribute "CDS_LOCATION" "C1R30"
					( Origin gPackager )
				)
				( attribute "CDS_SEC" "1"
					( Origin gPackager )
				)
				( attribute "LOCATION" "C1R30"
					( Origin gFrontEnd )
				)
				( attribute "MATERIAL" "X6S"
					( Origin gFrontEnd )
				)
				( attribute "PACK_TYPE" "0603"
					( Origin gFrontEnd )
				)
				( attribute "PART_NUMBER" "E15431-002"
					( Origin gFrontEnd )
				)
				( attribute "PHYS_PAGE" "139"
					( Origin gFrontEnd )
				)
				( attribute "ROOM" "NIC_SPRV"
					( Origin gFrontEnd )
				)
				( attribute "ROT" "0"
					( Origin gFrontEnd )
				)
				( attribute "SEC" "1"
					( Origin gFrontEnd )
				)
				( attribute "SEC_TYPE" "0603"
					( Origin gFrontEnd )
				)
				( attribute "TOLERANCE" "20%"
					( Origin gFrontEnd )
				)
				( attribute "VALUE" "10UF"
					( Origin gFrontEnd )
				)
				( attribute "VER" "1"
					( Origin gFrontEnd )
				)
				( attribute "VOLTAGE" "6.3V"
					( Units "uVoltage" "V" 1.000000)
					( Origin gFrontEnd )
				)
				( attribute "XY" "(-6325,3975)"
					( Origin gFrontEnd )
				)
				( attribute "CHIPS_PART_NAME" "CAP"
					( Origin gPackager )
				)
				( attribute "CDS_PART_NAME" "CAP_0603-10UF,6.3V,20%,X6S,E15A"
					( Origin gPackager )
				)
				( objectStatus "C1R30" )
				( pin "a"
					( attribute "PN" "1"
						( Origin gPackager )
					)
					( objectStatus "C1R30.1" )
				)
				( pin "b"
					( attribute "PN" "2"
						( Origin gPackager )
					)
					( objectStatus "C1R30.2" )
				)
			)
			( gate "@baseboard_fab2_lib.baseboard_fab2(sch_1):page139_i136"
				( attribute "BOM_COST" "NT_GBE_BASE"
					( Origin gFrontEnd )
				)
				( attribute "CDS_LIB" "mstr_discrete"
					( Origin gPackager )
				)
				( attribute "CDS_LOCATION" "C1R22"
					( Origin gPackager )
				)
				( attribute "CDS_SEC" "1"
					( Origin gPackager )
				)
				( attribute "LOCATION" "C1R22"
					( Origin gFrontEnd )
				)
				( attribute "MATERIAL" "X6S"
					( Origin gFrontEnd )
				)
				( attribute "PACK_TYPE" "0603"
					( Origin gFrontEnd )
				)
				( attribute "PART_NUMBER" "E15431-002"
					( Origin gFrontEnd )
				)
				( attribute "PHYS_PAGE" "139"
					( Origin gFrontEnd )
				)
				( attribute "ROOM" "NIC_SPRV"
					( Origin gFrontEnd )
				)
				( attribute "ROT" "0"
					( Origin gFrontEnd )
				)
				( attribute "SEC" "1"
					( Origin gFrontEnd )
				)
				( attribute "SEC_TYPE" "0603"
					( Origin gFrontEnd )
				)
				( attribute "TOLERANCE" "20%"
					( Origin gFrontEnd )
				)
				( attribute "VALUE" "10UF"
					( Origin gFrontEnd )
				)
				( attribute "VER" "1"
					( Origin gFrontEnd )
				)
				( attribute "VOLTAGE" "6.3V"
					( Units "uVoltage" "V" 1.000000)
					( Origin gFrontEnd )
				)
				( attribute "XY" "(-6725,3750)"
					( Origin gFrontEnd )
				)
				( attribute "CHIPS_PART_NAME" "CAP"
					( Origin gPackager )
				)
				( attribute "CDS_PART_NAME" "CAP_0603-10UF,6.3V,20%,X6S,E15A"
					( Origin gPackager )
				)
				( objectStatus "C1R22" )
				( pin "a"
					( attribute "PN" "1"
						( Origin gPackager )
					)
					( objectStatus "C1R22.1" )
				)
				( pin "b"
					( attribute "PN" "2"
						( Origin gPackager )
					)
					( objectStatus "C1R22.2" )
				)
			)
			( gate "@baseboard_fab2_lib.baseboard_fab2(sch_1):page139_i140"
				( attribute "BOM_COST" "NT_GBE_BASE"
					( Origin gFrontEnd )
				)
				( attribute "CDS_LIB" "mstr_discrete"
					( Origin gPackager )
				)
				( attribute "CDS_LOCATION" "C9F2"
					( Origin gPackager )
				)
				( attribute "CDS_SEC" "1"
					( Origin gPackager )
				)
				( attribute "LOCATION" "C9F2"
					( Origin gFrontEnd )
				)
				( attribute "MATERIAL" "EMPTY"
					( Origin gFrontEnd )
				)
				( attribute "PACK_TYPE" "1210"
					( Origin gFrontEnd )
				)
				( attribute "PART_NUMBER" "D38464-007"
					( Origin gFrontEnd )
				)
				( attribute "PHYS_PAGE" "139"
					( Origin gFrontEnd )
				)
				( attribute "ROOM" "NIC_SPRV"
					( Origin gFrontEnd )
				)
				( attribute "ROT" "0"
					( Origin gFrontEnd )
				)
				( attribute "SEC" "1"
					( Origin gPackager )
				)
				( attribute "TOLERANCE" "20%"
					( Origin gFrontEnd )
				)
				( attribute "VALUE" "47UF"
					( Origin gFrontEnd )
				)
				( attribute "VER" "1"
					( Origin gFrontEnd )
				)
				( attribute "VOLTAGE" "16V"
					( Units "uVoltage" "V" 1.000000)
					( Origin gFrontEnd )
				)
				( attribute "XY" "(-5275,875)"
					( Origin gFrontEnd )
				)
				( attribute "CHIPS_PART_NAME" "CAP"
					( Origin gPackager )
				)
				( attribute "CDS_PART_NAME" "CAP_1210-47UF,16V,20%,EMPTY,D3A"
					( Origin gPackager )
				)
				( objectStatus "C9F2" )
				( pin "a"
					( attribute "PN" "1"
						( Origin gPackager )
					)
					( objectStatus "C9F2.1" )
				)
				( pin "b"
					( attribute "PN" "2"
						( Origin gPackager )
					)
					( objectStatus "C9F2.2" )
				)
			)
			( gate "@baseboard_fab2_lib.baseboard_fab2(sch_1):page139_i142"
				( attribute "BOM_COST" "NT_GBE_BASE"
					( Origin gFrontEnd )
				)
				( attribute "CDS_LIB" "mstr_discrete"
					( Origin gPackager )
				)
				( attribute "CDS_LOCATION" "C1R13"
					( Origin gPackager )
				)
				( attribute "CDS_SEC" "1"
					( Origin gPackager )
				)
				( attribute "LOCATION" "C1R13"
					( Origin gFrontEnd )
				)
				( attribute "MATERIAL" "X6S"
					( Origin gFrontEnd )
				)
				( attribute "PACK_TYPE" "0603"
					( Origin gFrontEnd )
				)
				( attribute "PART_NUMBER" "E15431-002"
					( Origin gFrontEnd )
				)
				( attribute "PHYS_PAGE" "139"
					( Origin gFrontEnd )
				)
				( attribute "ROOM" "NIC_SPRV"
					( Origin gFrontEnd )
				)
				( attribute "ROT" "0"
					( Origin gFrontEnd )
				)
				( attribute "SEC" "1"
					( Origin gPackager )
				)
				( attribute "TOLERANCE" "20%"
					( Origin gFrontEnd )
				)
				( attribute "VALUE" "10UF"
					( Origin gFrontEnd )
				)
				( attribute "VER" "1"
					( Origin gFrontEnd )
				)
				( attribute "VOLTAGE" "6.3V"
					( Units "uVoltage" "V" 1.000000)
					( Origin gFrontEnd )
				)
				( attribute "XY" "(-5025,875)"
					( Origin gFrontEnd )
				)
				( attribute "CHIPS_PART_NAME" "CAP"
					( Origin gPackager )
				)
				( attribute "CDS_PART_NAME" "CAP_0603-10UF,6.3V,20%,X6S,E15A"
					( Origin gPackager )
				)
				( objectStatus "C1R13" )
				( pin "a"
					( attribute "PN" "1"
						( Origin gPackager )
					)
					( objectStatus "C1R13.1" )
				)
				( pin "b"
					( attribute "PN" "2"
						( Origin gPackager )
					)
					( objectStatus "C1R13.2" )
				)
			)
			( gate "@baseboard_fab2_lib.baseboard_fab2(sch_1):page139_i143"
				( attribute "BOM_COST" "NT_GBE_BASE"
					( Origin gFrontEnd )
				)
				( attribute "CDS_LIB" "dev_discrete"
					( Origin gPackager )
				)
				( attribute "CDS_LOCATION" "C1R20"
					( Origin gPackager )
				)
				( attribute "CDS_SEC" "1"
					( Origin gPackager )
				)
				( attribute "LOCATION" "C1R20"
					( Origin gFrontEnd )
				)
				( attribute "MATERIAL" "X7R"
					( Origin gFrontEnd )
				)
				( attribute "PACK_TYPE" "0402V"
					( Origin gFrontEnd )
				)
				( attribute "PART_NUMBER" "A36096-030"
					( Origin gFrontEnd )
				)
				( attribute "PHYS_PAGE" "139"
					( Origin gFrontEnd )
				)
				( attribute "ROOM" "NIC_SPRV"
					( Origin gFrontEnd )
				)
				( attribute "ROT" "0"
					( Origin gFrontEnd )
				)
				( attribute "SEC" "1"
					( Origin gPackager )
				)
				( attribute "TOLERANCE" "10%"
					( Origin gFrontEnd )
				)
				( attribute "VALUE" "0.1UF"
					( Origin gFrontEnd )
				)
				( attribute "VER" "1"
					( Origin gFrontEnd )
				)
				( attribute "VOLTAGE" "16V"
					( Units "uVoltage" "V" 1.000000)
					( Origin gFrontEnd )
				)
				( attribute "XY" "(-4775,875)"
					( Origin gFrontEnd )
				)
				( attribute "CHIPS_PART_NAME" "CAP_A"
					( Origin gPackager )
				)
				( attribute "CDS_PART_NAME" "CAP_A_0402V-0.1UF,16V,10%,X7R,A"
					( Origin gPackager )
				)
				( objectStatus "C1R20" )
				( pin "a"
					( attribute "PN" "1"
						( Origin gPackager )
					)
					( objectStatus "C1R20.1" )
				)
				( pin "b"
					( attribute "PN" "2"
						( Origin gPackager )
					)
					( objectStatus "C1R20.2" )
				)
			)
			( gate "@baseboard_fab2_lib.baseboard_fab2(sch_1):page139_i144"
				( attribute "BOM_COST" "NT_GBE_BASE"
					( Origin gFrontEnd )
				)
				( attribute "CDS_LIB" "dev_discrete"
					( Origin gPackager )
				)
				( attribute "CDS_LOCATION" "C1T3"
					( Origin gPackager )
				)
				( attribute "CDS_SEC" "1"
					( Origin gPackager )
				)
				( attribute "LOCATION" "C1T3"
					( Origin gFrontEnd )
				)
				( attribute "MATERIAL" "X7R"
					( Origin gFrontEnd )
				)
				( attribute "PACK_TYPE" "0402V"
					( Origin gFrontEnd )
				)
				( attribute "PART_NUMBER" "A36096-030"
					( Origin gFrontEnd )
				)
				( attribute "PHYS_PAGE" "139"
					( Origin gFrontEnd )
				)
				( attribute "ROOM" "NIC_SPRV"
					( Origin gFrontEnd )
				)
				( attribute "ROT" "0"
					( Origin gFrontEnd )
				)
				( attribute "SEC" "1"
					( Origin gPackager )
				)
				( attribute "TOLERANCE" "10%"
					( Origin gFrontEnd )
				)
				( attribute "VALUE" "0.1UF"
					( Origin gFrontEnd )
				)
				( attribute "VER" "1"
					( Origin gFrontEnd )
				)
				( attribute "VOLTAGE" "16V"
					( Units "uVoltage" "V" 1.000000)
					( Origin gFrontEnd )
				)
				( attribute "XY" "(-4525,875)"
					( Origin gFrontEnd )
				)
				( attribute "CHIPS_PART_NAME" "CAP_A"
					( Origin gPackager )
				)
				( attribute "CDS_PART_NAME" "CAP_A_0402V-0.1UF,16V,10%,X7R,A"
					( Origin gPackager )
				)
				( objectStatus "C1T3" )
				( pin "a"
					( attribute "PN" "1"
						( Origin gPackager )
					)
					( objectStatus "C1T3.1" )
				)
				( pin "b"
					( attribute "PN" "2"
						( Origin gPackager )
					)
					( objectStatus "C1T3.2" )
				)
			)
			( gate "@baseboard_fab2_lib.baseboard_fab2(sch_1):page139_i145"
				( attribute "BOM_COST" "NT_GBE_BASE"
					( Origin gFrontEnd )
				)
				( attribute "CDS_LIB" "dev_discrete"
					( Origin gPackager )
				)
				( attribute "CDS_LOCATION" "C1R14"
					( Origin gPackager )
				)
				( attribute "CDS_SEC" "1"
					( Origin gPackager )
				)
				( attribute "LOCATION" "C1R14"
					( Origin gFrontEnd )
				)
				( attribute "MATERIAL" "X7R"
					( Origin gFrontEnd )
				)
				( attribute "PACK_TYPE" "0402V"
					( Origin gFrontEnd )
				)
				( attribute "PART_NUMBER" "A36096-030"
					( Origin gFrontEnd )
				)
				( attribute "PHYS_PAGE" "139"
					( Origin gFrontEnd )
				)
				( attribute "ROOM" "NIC_SPRV"
					( Origin gFrontEnd )
				)
				( attribute "ROT" "0"
					( Origin gFrontEnd )
				)
				( attribute "SEC" "1"
					( Origin gPackager )
				)
				( attribute "TOLERANCE" "10%"
					( Origin gFrontEnd )
				)
				( attribute "VALUE" "0.1UF"
					( Origin gFrontEnd )
				)
				( attribute "VER" "1"
					( Origin gFrontEnd )
				)
				( attribute "VOLTAGE" "16V"
					( Units "uVoltage" "V" 1.000000)
					( Origin gFrontEnd )
				)
				( attribute "XY" "(-4275,875)"
					( Origin gFrontEnd )
				)
				( attribute "CHIPS_PART_NAME" "CAP_A"
					( Origin gPackager )
				)
				( attribute "CDS_PART_NAME" "CAP_A_0402V-0.1UF,16V,10%,X7R,A"
					( Origin gPackager )
				)
				( objectStatus "C1R14" )
				( pin "a"
					( attribute "PN" "1"
						( Origin gPackager )
					)
					( objectStatus "C1R14.1" )
				)
				( pin "b"
					( attribute "PN" "2"
						( Origin gPackager )
					)
					( objectStatus "C1R14.2" )
				)
			)
			( gate "@baseboard_fab2_lib.baseboard_fab2(sch_1):page139_i146"
				( attribute "BOM_COST" "NT_GBE_BASE"
					( Origin gFrontEnd )
				)
				( attribute "CDS_LIB" "dev_discrete"
					( Origin gPackager )
				)
				( attribute "CDS_LOCATION" "C1R21"
					( Origin gPackager )
				)
				( attribute "CDS_SEC" "1"
					( Origin gPackager )
				)
				( attribute "LOCATION" "C1R21"
					( Origin gFrontEnd )
				)
				( attribute "MATERIAL" "X7R"
					( Origin gFrontEnd )
				)
				( attribute "PACK_TYPE" "0402V"
					( Origin gFrontEnd )
				)
				( attribute "PART_NUMBER" "A36096-030"
					( Origin gFrontEnd )
				)
				( attribute "PHYS_PAGE" "139"
					( Origin gFrontEnd )
				)
				( attribute "ROOM" "NIC_SPRV"
					( Origin gFrontEnd )
				)
				( attribute "ROT" "0"
					( Origin gFrontEnd )
				)
				( attribute "SEC" "1"
					( Origin gPackager )
				)
				( attribute "TOLERANCE" "10%"
					( Origin gFrontEnd )
				)
				( attribute "VALUE" "0.1UF"
					( Origin gFrontEnd )
				)
				( attribute "VER" "1"
					( Origin gFrontEnd )
				)
				( attribute "VOLTAGE" "16V"
					( Units "uVoltage" "V" 1.000000)
					( Origin gFrontEnd )
				)
				( attribute "XY" "(-4025,875)"
					( Origin gFrontEnd )
				)
				( attribute "CHIPS_PART_NAME" "CAP_A"
					( Origin gPackager )
				)
				( attribute "CDS_PART_NAME" "CAP_A_0402V-0.1UF,16V,10%,X7R,A"
					( Origin gPackager )
				)
				( objectStatus "C1R21" )
				( pin "a"
					( attribute "PN" "1"
						( Origin gPackager )
					)
					( objectStatus "C1R21.1" )
				)
				( pin "b"
					( attribute "PN" "2"
						( Origin gPackager )
					)
					( objectStatus "C1R21.2" )
				)
			)
			( gate "@baseboard_fab2_lib.baseboard_fab2(sch_1):page139_i149"
				( attribute "BOM_COST" "NT_GBE_BASE"
					( Origin gFrontEnd )
				)
				( attribute "CDS_LIB" "dev_discrete"
					( Origin gPackager )
				)
				( attribute "CDS_LOCATION" "C1R26"
					( Origin gPackager )
				)
				( attribute "CDS_SEC" "1"
					( Origin gPackager )
				)
				( attribute "LOCATION" "C1R26"
					( Origin gFrontEnd )
				)
				( attribute "MATERIAL" "X7R"
					( Origin gFrontEnd )
				)
				( attribute "PACK_TYPE" "0402V"
					( Origin gFrontEnd )
				)
				( attribute "PART_NUMBER" "A36096-030"
					( Origin gFrontEnd )
				)
				( attribute "PHYS_PAGE" "139"
					( Origin gFrontEnd )
				)
				( attribute "ROOM" "NIC_SPRV"
					( Origin gFrontEnd )
				)
				( attribute "ROT" "0"
					( Origin gFrontEnd )
				)
				( attribute "SEC" "1"
					( Origin gPackager )
				)
				( attribute "TOLERANCE" "10%"
					( Origin gFrontEnd )
				)
				( attribute "VALUE" "0.1UF"
					( Origin gFrontEnd )
				)
				( attribute "VER" "1"
					( Origin gFrontEnd )
				)
				( attribute "VOLTAGE" "16V"
					( Units "uVoltage" "V" 1.000000)
					( Origin gFrontEnd )
				)
				( attribute "XY" "(-2325,875)"
					( Origin gFrontEnd )
				)
				( attribute "CHIPS_PART_NAME" "CAP_A"
					( Origin gPackager )
				)
				( attribute "CDS_PART_NAME" "CAP_A_0402V-0.1UF,16V,10%,X7R,A"
					( Origin gPackager )
				)
				( objectStatus "C1R26" )
				( pin "a"
					( attribute "PN" "1"
						( Origin gPackager )
					)
					( objectStatus "C1R26.1" )
				)
				( pin "b"
					( attribute "PN" "2"
						( Origin gPackager )
					)
					( objectStatus "C1R26.2" )
				)
			)
			( gate "@baseboard_fab2_lib.baseboard_fab2(sch_1):page139_i150"
				( attribute "BOM_COST" "NT_GBE_BASE"
					( Origin gFrontEnd )
				)
				( attribute "CDS_LIB" "dev_discrete"
					( Origin gPackager )
				)
				( attribute "CDS_LOCATION" "C1R29"
					( Origin gPackager )
				)
				( attribute "CDS_SEC" "1"
					( Origin gPackager )
				)
				( attribute "LOCATION" "C1R29"
					( Origin gFrontEnd )
				)
				( attribute "MATERIAL" "X7R"
					( Origin gFrontEnd )
				)
				( attribute "PACK_TYPE" "0402V"
					( Origin gFrontEnd )
				)
				( attribute "PART_NUMBER" "A36096-030"
					( Origin gFrontEnd )
				)
				( attribute "PHYS_PAGE" "139"
					( Origin gFrontEnd )
				)
				( attribute "ROOM" "NIC_SPRV"
					( Origin gFrontEnd )
				)
				( attribute "ROT" "0"
					( Origin gFrontEnd )
				)
				( attribute "SEC" "1"
					( Origin gPackager )
				)
				( attribute "TOLERANCE" "10%"
					( Origin gFrontEnd )
				)
				( attribute "VALUE" "0.1UF"
					( Origin gFrontEnd )
				)
				( attribute "VER" "1"
					( Origin gFrontEnd )
				)
				( attribute "VOLTAGE" "16V"
					( Units "uVoltage" "V" 1.000000)
					( Origin gFrontEnd )
				)
				( attribute "XY" "(-2575,875)"
					( Origin gFrontEnd )
				)
				( attribute "CHIPS_PART_NAME" "CAP_A"
					( Origin gPackager )
				)
				( attribute "CDS_PART_NAME" "CAP_A_0402V-0.1UF,16V,10%,X7R,A"
					( Origin gPackager )
				)
				( objectStatus "C1R29" )
				( pin "a"
					( attribute "PN" "1"
						( Origin gPackager )
					)
					( objectStatus "C1R29.1" )
				)
				( pin "b"
					( attribute "PN" "2"
						( Origin gPackager )
					)
					( objectStatus "C1R29.2" )
				)
			)
			( gate "@baseboard_fab2_lib.baseboard_fab2(sch_1):page139_i151"
				( attribute "BOM_COST" "NT_GBE_BASE"
					( Origin gFrontEnd )
				)
				( attribute "CDS_LIB" "dev_discrete"
					( Origin gPackager )
				)
				( attribute "CDS_LOCATION" "C1R19"
					( Origin gPackager )
				)
				( attribute "CDS_SEC" "1"
					( Origin gPackager )
				)
				( attribute "LOCATION" "C1R19"
					( Origin gFrontEnd )
				)
				( attribute "MATERIAL" "X7R"
					( Origin gFrontEnd )
				)
				( attribute "PACK_TYPE" "0402V"
					( Origin gFrontEnd )
				)
				( attribute "PART_NUMBER" "A36096-030"
					( Origin gFrontEnd )
				)
				( attribute "PHYS_PAGE" "139"
					( Origin gFrontEnd )
				)
				( attribute "ROOM" "NIC_SPRV"
					( Origin gFrontEnd )
				)
				( attribute "ROT" "0"
					( Origin gFrontEnd )
				)
				( attribute "SEC" "1"
					( Origin gPackager )
				)
				( attribute "TOLERANCE" "10%"
					( Origin gFrontEnd )
				)
				( attribute "VALUE" "0.1UF"
					( Origin gFrontEnd )
				)
				( attribute "VER" "1"
					( Origin gFrontEnd )
				)
				( attribute "VOLTAGE" "16V"
					( Units "uVoltage" "V" 1.000000)
					( Origin gFrontEnd )
				)
				( attribute "XY" "(-2825,875)"
					( Origin gFrontEnd )
				)
				( attribute "CHIPS_PART_NAME" "CAP_A"
					( Origin gPackager )
				)
				( attribute "CDS_PART_NAME" "CAP_A_0402V-0.1UF,16V,10%,X7R,A"
					( Origin gPackager )
				)
				( objectStatus "C1R19" )
				( pin "a"
					( attribute "PN" "1"
						( Origin gPackager )
					)
					( objectStatus "C1R19.1" )
				)
				( pin "b"
					( attribute "PN" "2"
						( Origin gPackager )
					)
					( objectStatus "C1R19.2" )
				)
			)
			( gate "@baseboard_fab2_lib.baseboard_fab2(sch_1):page139_i152"
				( attribute "BOM_COST" "NT_GBE_BASE"
					( Origin gFrontEnd )
				)
				( attribute "CDS_LIB" "dev_discrete"
					( Origin gPackager )
				)
				( attribute "CDS_LOCATION" "C1R31"
					( Origin gPackager )
				)
				( attribute "CDS_SEC" "1"
					( Origin gPackager )
				)
				( attribute "LOCATION" "C1R31"
					( Origin gFrontEnd )
				)
				( attribute "MATERIAL" "X7R"
					( Origin gFrontEnd )
				)
				( attribute "PACK_TYPE" "0402V"
					( Origin gFrontEnd )
				)
				( attribute "PART_NUMBER" "A36096-030"
					( Origin gFrontEnd )
				)
				( attribute "PHYS_PAGE" "139"
					( Origin gFrontEnd )
				)
				( attribute "ROOM" "NIC_SPRV"
					( Origin gFrontEnd )
				)
				( attribute "ROT" "0"
					( Origin gFrontEnd )
				)
				( attribute "SEC" "1"
					( Origin gPackager )
				)
				( attribute "TOLERANCE" "10%"
					( Origin gFrontEnd )
				)
				( attribute "VALUE" "0.1UF"
					( Origin gFrontEnd )
				)
				( attribute "VER" "1"
					( Origin gFrontEnd )
				)
				( attribute "VOLTAGE" "16V"
					( Units "uVoltage" "V" 1.000000)
					( Origin gFrontEnd )
				)
				( attribute "XY" "(-3075,875)"
					( Origin gFrontEnd )
				)
				( attribute "CHIPS_PART_NAME" "CAP_A"
					( Origin gPackager )
				)
				( attribute "CDS_PART_NAME" "CAP_A_0402V-0.1UF,16V,10%,X7R,A"
					( Origin gPackager )
				)
				( objectStatus "C1R31" )
				( pin "a"
					( attribute "PN" "1"
						( Origin gPackager )
					)
					( objectStatus "C1R31.1" )
				)
				( pin "b"
					( attribute "PN" "2"
						( Origin gPackager )
					)
					( objectStatus "C1R31.2" )
				)
			)
			( gate "@baseboard_fab2_lib.baseboard_fab2(sch_1):page139_i153"
				( attribute "BOM_COST" "NT_GBE_BASE"
					( Origin gFrontEnd )
				)
				( attribute "CDS_LIB" "mstr_discrete"
					( Origin gPackager )
				)
				( attribute "CDS_LOCATION" "C1R17"
					( Origin gPackager )
				)
				( attribute "CDS_SEC" "1"
					( Origin gPackager )
				)
				( attribute "LOCATION" "C1R17"
					( Origin gFrontEnd )
				)
				( attribute "MATERIAL" "X6S"
					( Origin gFrontEnd )
				)
				( attribute "PACK_TYPE" "0603"
					( Origin gFrontEnd )
				)
				( attribute "PART_NUMBER" "E15431-002"
					( Origin gFrontEnd )
				)
				( attribute "PHYS_PAGE" "139"
					( Origin gFrontEnd )
				)
				( attribute "ROOM" "NIC_SPRV"
					( Origin gFrontEnd )
				)
				( attribute "ROT" "0"
					( Origin gFrontEnd )
				)
				( attribute "SEC" "1"
					( Origin gPackager )
				)
				( attribute "TOLERANCE" "20%"
					( Origin gFrontEnd )
				)
				( attribute "VALUE" "10UF"
					( Origin gFrontEnd )
				)
				( attribute "VER" "1"
					( Origin gFrontEnd )
				)
				( attribute "VOLTAGE" "6.3V"
					( Units "uVoltage" "V" 1.000000)
					( Origin gFrontEnd )
				)
				( attribute "XY" "(-3325,875)"
					( Origin gFrontEnd )
				)
				( attribute "CHIPS_PART_NAME" "CAP"
					( Origin gPackager )
				)
				( attribute "CDS_PART_NAME" "CAP_0603-10UF,6.3V,20%,X6S,E15A"
					( Origin gPackager )
				)
				( objectStatus "C1R17" )
				( pin "a"
					( attribute "PN" "1"
						( Origin gPackager )
					)
					( objectStatus "C1R17.1" )
				)
				( pin "b"
					( attribute "PN" "2"
						( Origin gPackager )
					)
					( objectStatus "C1R17.2" )
				)
			)
			( gate "@baseboard_fab2_lib.baseboard_fab2(sch_1):page139_i155"
				( attribute "BOM_COST" "NT_GBE_BASE"
					( Origin gFrontEnd )
				)
				( attribute "CDS_LIB" "mstr_discrete"
					( Origin gPackager )
				)
				( attribute "CDS_LOCATION" "C9E6"
					( Origin gPackager )
				)
				( attribute "CDS_SEC" "1"
					( Origin gPackager )
				)
				( attribute "LOCATION" "C9E6"
					( Origin gFrontEnd )
				)
				( attribute "MATERIAL" "EMPTY"
					( Origin gFrontEnd )
				)
				( attribute "PACK_TYPE" "1210"
					( Origin gFrontEnd )
				)
				( attribute "PART_NUMBER" "D38464-007"
					( Origin gFrontEnd )
				)
				( attribute "PHYS_PAGE" "139"
					( Origin gFrontEnd )
				)
				( attribute "ROOM" "NIC_SPRV"
					( Origin gFrontEnd )
				)
				( attribute "ROT" "0"
					( Origin gFrontEnd )
				)
				( attribute "SEC" "1"
					( Origin gPackager )
				)
				( attribute "TOLERANCE" "20%"
					( Origin gFrontEnd )
				)
				( attribute "VALUE" "47UF"
					( Origin gFrontEnd )
				)
				( attribute "VER" "1"
					( Origin gFrontEnd )
				)
				( attribute "VOLTAGE" "16V"
					( Units "uVoltage" "V" 1.000000)
					( Origin gFrontEnd )
				)
				( attribute "XY" "(-3575,875)"
					( Origin gFrontEnd )
				)
				( attribute "CHIPS_PART_NAME" "CAP"
					( Origin gPackager )
				)
				( attribute "CDS_PART_NAME" "CAP_1210-47UF,16V,20%,EMPTY,D3A"
					( Origin gPackager )
				)
				( objectStatus "C9E6" )
				( pin "a"
					( attribute "PN" "1"
						( Origin gPackager )
					)
					( objectStatus "C9E6.1" )
				)
				( pin "b"
					( attribute "PN" "2"
						( Origin gPackager )
					)
					( objectStatus "C9E6.2" )
				)
			)
			( gate "@baseboard_fab2_lib.baseboard_fab2(sch_1):page139_i157"
				( attribute "BOM_COST" "NT_GBE_BASE"
					( Origin gFrontEnd )
				)
				( attribute "CDS_LIB" "dev_discrete"
					( Origin gPackager )
				)
				( attribute "CDS_LOCATION" "C1R18"
					( Origin gPackager )
				)
				( attribute "CDS_SEC" "1"
					( Origin gPackager )
				)
				( attribute "LOCATION" "C1R18"
					( Origin gFrontEnd )
				)
				( attribute "MATERIAL" "X7R"
					( Origin gFrontEnd )
				)
				( attribute "PACK_TYPE" "0402V"
					( Origin gFrontEnd )
				)
				( attribute "PART_NUMBER" "A36096-030"
					( Origin gFrontEnd )
				)
				( attribute "PHYS_PAGE" "139"
					( Origin gFrontEnd )
				)
				( attribute "ROOM" "NIC_SPRV"
					( Origin gFrontEnd )
				)
				( attribute "ROT" "0"
					( Origin gFrontEnd )
				)
				( attribute "SEC" "1"
					( Origin gPackager )
				)
				( attribute "TOLERANCE" "10%"
					( Origin gFrontEnd )
				)
				( attribute "VALUE" "0.1UF"
					( Origin gFrontEnd )
				)
				( attribute "VER" "1"
					( Origin gFrontEnd )
				)
				( attribute "VOLTAGE" "16V"
					( Units "uVoltage" "V" 1.000000)
					( Origin gFrontEnd )
				)
				( attribute "XY" "(-350,875)"
					( Origin gFrontEnd )
				)
				( attribute "CHIPS_PART_NAME" "CAP_A"
					( Origin gPackager )
				)
				( attribute "CDS_PART_NAME" "CAP_A_0402V-0.1UF,16V,10%,X7R,A"
					( Origin gPackager )
				)
				( objectStatus "C1R18" )
				( pin "a"
					( attribute "PN" "1"
						( Origin gPackager )
					)
					( objectStatus "C1R18.1" )
				)
				( pin "b"
					( attribute "PN" "2"
						( Origin gPackager )
					)
					( objectStatus "C1R18.2" )
				)
			)
			( gate "@baseboard_fab2_lib.baseboard_fab2(sch_1):page139_i158"
				( attribute "BOM_COST" "NT_GBE_BASE"
					( Origin gFrontEnd )
				)
				( attribute "CDS_LIB" "dev_discrete"
					( Origin gPackager )
				)
				( attribute "CDS_LOCATION" "C1T5"
					( Origin gPackager )
				)
				( attribute "CDS_SEC" "1"
					( Origin gPackager )
				)
				( attribute "LOCATION" "C1T5"
					( Origin gFrontEnd )
				)
				( attribute "MATERIAL" "X7R"
					( Origin gFrontEnd )
				)
				( attribute "PACK_TYPE" "0402V"
					( Origin gFrontEnd )
				)
				( attribute "PART_NUMBER" "A36096-030"
					( Origin gFrontEnd )
				)
				( attribute "PHYS_PAGE" "139"
					( Origin gFrontEnd )
				)
				( attribute "ROOM" "NIC_SPRV"
					( Origin gFrontEnd )
				)
				( attribute "ROT" "0"
					( Origin gFrontEnd )
				)
				( attribute "SEC" "1"
					( Origin gPackager )
				)
				( attribute "TOLERANCE" "10%"
					( Origin gFrontEnd )
				)
				( attribute "VALUE" "0.1UF"
					( Origin gFrontEnd )
				)
				( attribute "VER" "1"
					( Origin gFrontEnd )
				)
				( attribute "VOLTAGE" "16V"
					( Units "uVoltage" "V" 1.000000)
					( Origin gFrontEnd )
				)
				( attribute "XY" "(-600,875)"
					( Origin gFrontEnd )
				)
				( attribute "CHIPS_PART_NAME" "CAP_A"
					( Origin gPackager )
				)
				( attribute "CDS_PART_NAME" "CAP_A_0402V-0.1UF,16V,10%,X7R,A"
					( Origin gPackager )
				)
				( objectStatus "C1T5" )
				( pin "a"
					( attribute "PN" "1"
						( Origin gPackager )
					)
					( objectStatus "C1T5.1" )
				)
				( pin "b"
					( attribute "PN" "2"
						( Origin gPackager )
					)
					( objectStatus "C1T5.2" )
				)
			)
			( gate "@baseboard_fab2_lib.baseboard_fab2(sch_1):page139_i159"
				( attribute "BOM_COST" "NT_GBE_BASE"
					( Origin gFrontEnd )
				)
				( attribute "CDS_LIB" "dev_discrete"
					( Origin gPackager )
				)
				( attribute "CDS_LOCATION" "C1R24"
					( Origin gPackager )
				)
				( attribute "CDS_SEC" "1"
					( Origin gPackager )
				)
				( attribute "LOCATION" "C1R24"
					( Origin gFrontEnd )
				)
				( attribute "MATERIAL" "X7R"
					( Origin gFrontEnd )
				)
				( attribute "PACK_TYPE" "0402V"
					( Origin gFrontEnd )
				)
				( attribute "PART_NUMBER" "A36096-030"
					( Origin gFrontEnd )
				)
				( attribute "PHYS_PAGE" "139"
					( Origin gFrontEnd )
				)
				( attribute "ROOM" "NIC_SPRV"
					( Origin gFrontEnd )
				)
				( attribute "ROT" "0"
					( Origin gFrontEnd )
				)
				( attribute "SEC" "1"
					( Origin gPackager )
				)
				( attribute "TOLERANCE" "10%"
					( Origin gFrontEnd )
				)
				( attribute "VALUE" "0.1UF"
					( Origin gFrontEnd )
				)
				( attribute "VER" "1"
					( Origin gFrontEnd )
				)
				( attribute "VOLTAGE" "16V"
					( Units "uVoltage" "V" 1.000000)
					( Origin gFrontEnd )
				)
				( attribute "XY" "(-850,875)"
					( Origin gFrontEnd )
				)
				( attribute "CHIPS_PART_NAME" "CAP_A"
					( Origin gPackager )
				)
				( attribute "CDS_PART_NAME" "CAP_A_0402V-0.1UF,16V,10%,X7R,A"
					( Origin gPackager )
				)
				( objectStatus "C1R24" )
				( pin "a"
					( attribute "PN" "1"
						( Origin gPackager )
					)
					( objectStatus "C1R24.1" )
				)
				( pin "b"
					( attribute "PN" "2"
						( Origin gPackager )
					)
					( objectStatus "C1R24.2" )
				)
			)
			( gate "@baseboard_fab2_lib.baseboard_fab2(sch_1):page139_i160"
				( attribute "BOM_COST" "NT_GBE_BASE"
					( Origin gFrontEnd )
				)
				( attribute "CDS_LIB" "dev_discrete"
					( Origin gPackager )
				)
				( attribute "CDS_LOCATION" "C1R15"
					( Origin gPackager )
				)
				( attribute "CDS_SEC" "1"
					( Origin gPackager )
				)
				( attribute "LOCATION" "C1R15"
					( Origin gFrontEnd )
				)
				( attribute "MATERIAL" "X7R"
					( Origin gFrontEnd )
				)
				( attribute "PACK_TYPE" "0402V"
					( Origin gFrontEnd )
				)
				( attribute "PART_NUMBER" "A36096-030"
					( Origin gFrontEnd )
				)
				( attribute "PHYS_PAGE" "139"
					( Origin gFrontEnd )
				)
				( attribute "ROOM" "NIC_SPRV"
					( Origin gFrontEnd )
				)
				( attribute "ROT" "0"
					( Origin gFrontEnd )
				)
				( attribute "SEC" "1"
					( Origin gPackager )
				)
				( attribute "TOLERANCE" "10%"
					( Origin gFrontEnd )
				)
				( attribute "VALUE" "0.1UF"
					( Origin gFrontEnd )
				)
				( attribute "VER" "1"
					( Origin gFrontEnd )
				)
				( attribute "VOLTAGE" "16V"
					( Units "uVoltage" "V" 1.000000)
					( Origin gFrontEnd )
				)
				( attribute "XY" "(-1100,875)"
					( Origin gFrontEnd )
				)
				( attribute "CHIPS_PART_NAME" "CAP_A"
					( Origin gPackager )
				)
				( attribute "CDS_PART_NAME" "CAP_A_0402V-0.1UF,16V,10%,X7R,A"
					( Origin gPackager )
				)
				( objectStatus "C1R15" )
				( pin "a"
					( attribute "PN" "1"
						( Origin gPackager )
					)
					( objectStatus "C1R15.1" )
				)
				( pin "b"
					( attribute "PN" "2"
						( Origin gPackager )
					)
					( objectStatus "C1R15.2" )
				)
			)
			( gate "@baseboard_fab2_lib.baseboard_fab2(sch_1):page139_i161"
				( attribute "BOM_COST" "NT_GBE_BASE"
					( Origin gFrontEnd )
				)
				( attribute "CDS_LIB" "mstr_discrete"
					( Origin gPackager )
				)
				( attribute "CDS_LOCATION" "C1R16"
					( Origin gPackager )
				)
				( attribute "CDS_SEC" "1"
					( Origin gPackager )
				)
				( attribute "LOCATION" "C1R16"
					( Origin gFrontEnd )
				)
				( attribute "MATERIAL" "X6S"
					( Origin gFrontEnd )
				)
				( attribute "PACK_TYPE" "0603"
					( Origin gFrontEnd )
				)
				( attribute "PART_NUMBER" "E15431-002"
					( Origin gFrontEnd )
				)
				( attribute "PHYS_PAGE" "139"
					( Origin gFrontEnd )
				)
				( attribute "ROOM" "NIC_SPRV"
					( Origin gFrontEnd )
				)
				( attribute "ROT" "0"
					( Origin gFrontEnd )
				)
				( attribute "SEC" "1"
					( Origin gPackager )
				)
				( attribute "TOLERANCE" "20%"
					( Origin gFrontEnd )
				)
				( attribute "VALUE" "10UF"
					( Origin gFrontEnd )
				)
				( attribute "VER" "1"
					( Origin gFrontEnd )
				)
				( attribute "VOLTAGE" "6.3V"
					( Units "uVoltage" "V" 1.000000)
					( Origin gFrontEnd )
				)
				( attribute "XY" "(-1350,875)"
					( Origin gFrontEnd )
				)
				( attribute "CHIPS_PART_NAME" "CAP"
					( Origin gPackager )
				)
				( attribute "CDS_PART_NAME" "CAP_0603-10UF,6.3V,20%,X6S,E15A"
					( Origin gPackager )
				)
				( objectStatus "C1R16" )
				( pin "a"
					( attribute "PN" "1"
						( Origin gPackager )
					)
					( objectStatus "C1R16.1" )
				)
				( pin "b"
					( attribute "PN" "2"
						( Origin gPackager )
					)
					( objectStatus "C1R16.2" )
				)
			)
			( gate "@baseboard_fab2_lib.baseboard_fab2(sch_1):page139_i163"
				( attribute "BOM_COST" "NT_GBE_BASE"
					( Origin gFrontEnd )
				)
				( attribute "CDS_LIB" "dev_discrete"
					( Origin gPackager )
				)
				( attribute "CDS_LOCATION" "C9E1"
					( Origin gPackager )
				)
				( attribute "CDS_SEC" "1"
					( Origin gPackager )
				)
				( attribute "LOCATION" "C9E1"
					( Origin gFrontEnd )
				)
				( attribute "MATERIAL" "EMPTY"
					( Origin gFrontEnd )
				)
				( attribute "PACK_TYPE" "0603V"
					( Origin gFrontEnd )
				)
				( attribute "PART_NUMBER" "E15431-004"
					( Origin gFrontEnd )
				)
				( attribute "PHYS_PAGE" "139"
					( Origin gFrontEnd )
				)
				( attribute "ROOM" "NIC_SPRV"
					( Origin gFrontEnd )
				)
				( attribute "ROT" "0"
					( Origin gFrontEnd )
				)
				( attribute "SEC" "1"
					( Origin gFrontEnd )
				)
				( attribute "SEC_TYPE" "0603V"
					( Origin gFrontEnd )
				)
				( attribute "TOLERANCE" "20%"
					( Origin gFrontEnd )
				)
				( attribute "VALUE" "22.0UF"
					( Origin gFrontEnd )
				)
				( attribute "VER" "1"
					( Origin gFrontEnd )
				)
				( attribute "VOLTAGE" "4V"
					( Units "uVoltage" "V" 1.000000)
					( Origin gFrontEnd )
				)
				( attribute "XY" "(-1600,875)"
					( Origin gFrontEnd )
				)
				( attribute "CHIPS_PART_NAME" "CAP_A"
					( Origin gPackager )
				)
				( attribute "CDS_PART_NAME" "CAP_A_0603V-22.0UF,4V,20%,EMPTA"
					( Origin gPackager )
				)
				( objectStatus "C9E1" )
				( pin "a"
					( attribute "PN" "1"
						( Origin gPackager )
					)
					( objectStatus "C9E1.1" )
				)
				( pin "b"
					( attribute "PN" "2"
						( Origin gPackager )
					)
					( objectStatus "C9E1.2" )
				)
			)
			( gate "@baseboard_fab2_lib.baseboard_fab2(sch_1):page139_i173"
				( attribute "BOM_COST" "NT_GBE_BASE"
					( Origin gFrontEnd )
				)
				( attribute "CDS_LIB" "mstr_discrete"
					( Origin gPackager )
				)
				( attribute "CDS_LOCATION" "R9F5"
					( Origin gPackager )
				)
				( attribute "CDS_SEC" "1"
					( Origin gPackager )
				)
				( attribute "LOCATION" "R9F5"
					( Origin gFrontEnd )
				)
				( attribute "MATERIAL" "CHIP"
					( Origin gFrontEnd )
				)
				( attribute "PACK_TYPE" "0402"
					( Origin gFrontEnd )
				)
				( attribute "PART_NUMBER" "G21796-027"
					( Origin gFrontEnd )
				)
				( attribute "PHYS_PAGE" "139"
					( Origin gFrontEnd )
				)
				( attribute "ROOM" "NIC_SPRV"
					( Origin gFrontEnd )
				)
				( attribute "ROT" "0"
					( Origin gFrontEnd )
				)
				( attribute "SEC" "1"
					( Origin gPackager )
				)
				( attribute "TOLERANCE" "1%"
					( Origin gFrontEnd )
				)
				( attribute "VALUE" "3.32K"
					( Origin gFrontEnd )
				)
				( attribute "VER" "2"
					( Origin gFrontEnd )
				)
				( attribute "WATTAGE" "1/16W"
					( Origin gFrontEnd )
				)
				( attribute "XY" "(-900,3825)"
					( Origin gFrontEnd )
				)
				( attribute "CHIPS_PART_NAME" "RES"
					( Origin gPackager )
				)
				( attribute "CDS_PART_NAME" "RES_0402-3.32K,1%,1/16W,CHIP,GA"
					( Origin gPackager )
				)
				( objectStatus "R9F5" )
				( pin "a"
					( attribute "PN" "1"
						( Origin gPackager )
					)
					( objectStatus "R9F5.1" )
				)
				( pin "b"
					( attribute "PN" "2"
						( Origin gPackager )
					)
					( objectStatus "R9F5.2" )
				)
			)
			( gate "@baseboard_fab2_lib.baseboard_fab2(sch_1):page139_i174"
				( attribute "BOM_COST" "NT_GBE_BASE"
					( Origin gFrontEnd )
				)
				( attribute "CDS_LIB" "mstr_discrete"
					( Origin gPackager )
				)
				( attribute "CDS_LOCATION" "R9E23"
					( Origin gPackager )
				)
				( attribute "CDS_SEC" "1"
					( Origin gPackager )
				)
				( attribute "LOCATION" "R9E23"
					( Origin gFrontEnd )
				)
				( attribute "MATERIAL" "CHIP"
					( Origin gFrontEnd )
				)
				( attribute "PACK_TYPE" "0402"
					( Origin gFrontEnd )
				)
				( attribute "PART_NUMBER" "G21796-013"
					( Origin gFrontEnd )
				)
				( attribute "PHYS_PAGE" "139"
					( Origin gFrontEnd )
				)
				( attribute "ROOM" "NIC_SPRV"
					( Origin gFrontEnd )
				)
				( attribute "ROT" "0"
					( Origin gFrontEnd )
				)
				( attribute "SEC" "1"
					( Origin gFrontEnd )
				)
				( attribute "SEC_TYPE" "0402"
					( Origin gFrontEnd )
				)
				( attribute "TOLERANCE" "1%"
					( Origin gFrontEnd )
				)
				( attribute "VALUE" "4.99K"
					( Origin gFrontEnd )
				)
				( attribute "VER" "2"
					( Origin gFrontEnd )
				)
				( attribute "WATTAGE" "1/16W"
					( Origin gFrontEnd )
				)
				( attribute "XY" "(-900,3225)"
					( Origin gFrontEnd )
				)
				( attribute "CHIPS_PART_NAME" "RES"
					( Origin gPackager )
				)
				( attribute "CDS_PART_NAME" "RES_0402-4.99K,1%,1/16W,CHIP,GA"
					( Origin gPackager )
				)
				( objectStatus "R9E23" )
				( pin "a"
					( attribute "PN" "1"
						( Origin gPackager )
					)
					( objectStatus "R9E23.1" )
				)
				( pin "b"
					( attribute "PN" "2"
						( Origin gPackager )
					)
					( objectStatus "R9E23.2" )
				)
			)
			( gate "@baseboard_fab2_lib.baseboard_fab2(sch_1):page139_i177"
				( attribute "BOM_COST" "NT_GBE_BASE"
					( Origin gFrontEnd )
				)
				( attribute "CDS_LIB" "mstr_discrete"
					( Origin gPackager )
				)
				( attribute "CDS_LOCATION" "R9E2"
					( Origin gPackager )
				)
				( attribute "CDS_SEC" "1"
					( Origin gPackager )
				)
				( attribute "LOCATION" "R9E2"
					( Origin gFrontEnd )
				)
				( attribute "MATERIAL" "CHIP"
					( Origin gFrontEnd )
				)
				( attribute "PACK_TYPE" "0402"
					( Origin gFrontEnd )
				)
				( attribute "PART_NUMBER" "G21796-016"
					( Origin gFrontEnd )
				)
				( attribute "PHYS_PAGE" "139"
					( Origin gFrontEnd )
				)
				( attribute "ROOM" "NIC_SPRV"
					( Origin gFrontEnd )
				)
				( attribute "ROT" "0"
					( Origin gFrontEnd )
				)
				( attribute "SEC" "1"
					( Origin gFrontEnd )
				)
				( attribute "SEC_TYPE" "0402"
					( Origin gFrontEnd )
				)
				( attribute "TOLERANCE" "1%"
					( Origin gFrontEnd )
				)
				( attribute "VALUE" "10.0K"
					( Origin gFrontEnd )
				)
				( attribute "VER" "2"
					( Origin gFrontEnd )
				)
				( attribute "WATTAGE" "1/16W"
					( Origin gFrontEnd )
				)
				( attribute "XY" "(-7025,3125)"
					( Origin gFrontEnd )
				)
				( attribute "CHIPS_PART_NAME" "RES"
					( Origin gPackager )
				)
				( attribute "CDS_PART_NAME" "RES_0402-10.0K,1%,1/16W,CHIP,GA"
					( Origin gPackager )
				)
				( objectStatus "R9E2" )
				( pin "a"
					( attribute "PN" "1"
						( Origin gPackager )
					)
					( objectStatus "R9E2.1" )
				)
				( pin "b"
					( attribute "PN" "2"
						( Origin gPackager )
					)
					( objectStatus "R9E2.2" )
				)
			)
			( gate "@baseboard_fab2_lib.baseboard_fab2(sch_1):page139_i178"
				( attribute "BOM_COST" "NT_GBE_BASE"
					( Origin gFrontEnd )
				)
				( attribute "CDS_LIB" "mstr_discrete"
					( Origin gPackager )
				)
				( attribute "CDS_LOCATION" "R9E3"
					( Origin gPackager )
				)
				( attribute "CDS_SEC" "1"
					( Origin gPackager )
				)
				( attribute "LOCATION" "R9E3"
					( Origin gFrontEnd )
				)
				( attribute "MATERIAL" "CHIP"
					( Origin gFrontEnd )
				)
				( attribute "PACK_TYPE" "0402"
					( Origin gFrontEnd )
				)
				( attribute "PART_NUMBER" "G21796-016"
					( Origin gFrontEnd )
				)
				( attribute "PHYS_PAGE" "139"
					( Origin gFrontEnd )
				)
				( attribute "ROOM" "NIC_SPRV"
					( Origin gFrontEnd )
				)
				( attribute "ROT" "0"
					( Origin gFrontEnd )
				)
				( attribute "SEC" "1"
					( Origin gFrontEnd )
				)
				( attribute "SEC_TYPE" "0402"
					( Origin gFrontEnd )
				)
				( attribute "TOLERANCE" "1%"
					( Origin gFrontEnd )
				)
				( attribute "VALUE" "10.0K"
					( Origin gFrontEnd )
				)
				( attribute "VER" "2"
					( Origin gFrontEnd )
				)
				( attribute "WATTAGE" "1/16W"
					( Origin gFrontEnd )
				)
				( attribute "XY" "(-7275,3125)"
					( Origin gFrontEnd )
				)
				( attribute "CHIPS_PART_NAME" "RES"
					( Origin gPackager )
				)
				( attribute "CDS_PART_NAME" "RES_0402-10.0K,1%,1/16W,CHIP,GA"
					( Origin gPackager )
				)
				( objectStatus "R9E3" )
				( pin "a"
					( attribute "PN" "1"
						( Origin gPackager )
					)
					( objectStatus "R9E3.1" )
				)
				( pin "b"
					( attribute "PN" "2"
						( Origin gPackager )
					)
					( objectStatus "R9E3.2" )
				)
			)
			( gate "@baseboard_fab2_lib.baseboard_fab2(sch_1):page139_i179"
				( attribute "BOM_COST" "NT_GBE_BASE"
					( Origin gFrontEnd )
				)
				( attribute "CDS_LIB" "mstr_discrete"
					( Origin gPackager )
				)
				( attribute "CDS_LOCATION" "R9E1"
					( Origin gPackager )
				)
				( attribute "CDS_SEC" "1"
					( Origin gPackager )
				)
				( attribute "LOCATION" "R9E1"
					( Origin gFrontEnd )
				)
				( attribute "MATERIAL" "CHIP"
					( Origin gFrontEnd )
				)
				( attribute "PACK_TYPE" "0402"
					( Origin gFrontEnd )
				)
				( attribute "PART_NUMBER" "G21796-016"
					( Origin gFrontEnd )
				)
				( attribute "PHYS_PAGE" "139"
					( Origin gFrontEnd )
				)
				( attribute "ROOM" "NIC_SPRV"
					( Origin gFrontEnd )
				)
				( attribute "ROT" "0"
					( Origin gFrontEnd )
				)
				( attribute "SEC" "1"
					( Origin gFrontEnd )
				)
				( attribute "SEC_TYPE" "0402"
					( Origin gFrontEnd )
				)
				( attribute "TOLERANCE" "1%"
					( Origin gFrontEnd )
				)
				( attribute "VALUE" "10.0K"
					( Origin gFrontEnd )
				)
				( attribute "VER" "2"
					( Origin gFrontEnd )
				)
				( attribute "WATTAGE" "1/16W"
					( Origin gFrontEnd )
				)
				( attribute "XY" "(-7525,3125)"
					( Origin gFrontEnd )
				)
				( attribute "CHIPS_PART_NAME" "RES"
					( Origin gPackager )
				)
				( attribute "CDS_PART_NAME" "RES_0402-10.0K,1%,1/16W,CHIP,GA"
					( Origin gPackager )
				)
				( objectStatus "R9E1" )
				( pin "a"
					( attribute "PN" "1"
						( Origin gPackager )
					)
					( objectStatus "R9E1.1" )
				)
				( pin "b"
					( attribute "PN" "2"
						( Origin gPackager )
					)
					( objectStatus "R9E1.2" )
				)
			)
			( gate "@baseboard_fab2_lib.baseboard_fab2(sch_1):page139_i181"
				( attribute "BOM_COST" "NT_GBE_BASE"
					( Origin gFrontEnd )
				)
				( attribute "CDS_LIB" "mstr_discrete"
					( Origin gPackager )
				)
				( attribute "CDS_LOCATION" "R9E22"
					( Origin gPackager )
				)
				( attribute "CDS_SEC" "1"
					( Origin gPackager )
				)
				( attribute "LOCATION" "R9E22"
					( Origin gFrontEnd )
				)
				( attribute "MATERIAL" "CHIP"
					( Origin gFrontEnd )
				)
				( attribute "PACK_TYPE" "0402"
					( Origin gFrontEnd )
				)
				( attribute "PART_NUMBER" "G21796-016"
					( Origin gFrontEnd )
				)
				( attribute "PHYS_PAGE" "139"
					( Origin gFrontEnd )
				)
				( attribute "ROOM" "NIC_SPRV"
					( Origin gFrontEnd )
				)
				( attribute "ROT" "0"
					( Origin gFrontEnd )
				)
				( attribute "SEC" "1"
					( Origin gFrontEnd )
				)
				( attribute "SEC_TYPE" "0402"
					( Origin gFrontEnd )
				)
				( attribute "TOLERANCE" "1%"
					( Origin gFrontEnd )
				)
				( attribute "VALUE" "10.0K"
					( Origin gFrontEnd )
				)
				( attribute "VER" "1"
					( Origin gFrontEnd )
				)
				( attribute "WATTAGE" "1/16W"
					( Origin gFrontEnd )
				)
				( attribute "XY" "(-1500,2825)"
					( Origin gFrontEnd )
				)
				( attribute "CHIPS_PART_NAME" "RES"
					( Origin gPackager )
				)
				( attribute "CDS_PART_NAME" "RES_0402-10.0K,1%,1/16W,CHIP,GA"
					( Origin gPackager )
				)
				( objectStatus "R9E22" )
				( pin "a"
					( attribute "PN" "1"
						( Origin gPackager )
					)
					( objectStatus "R9E22.1" )
				)
				( pin "b"
					( attribute "PN" "2"
						( Origin gPackager )
					)
					( objectStatus "R9E22.2" )
				)
			)
			( gate "@baseboard_fab2_lib.baseboard_fab2(sch_1):page139_i193"
				( attribute "BOM_COST" "NT_GBE_BASE"
					( Origin gFrontEnd )
				)
				( attribute "CDS_LIB" "mstr_discrete"
					( Origin gPackager )
				)
				( attribute "CDS_LOCATION" "R9E7"
					( Origin gPackager )
				)
				( attribute "CDS_SEC" "1"
					( Origin gPackager )
				)
				( attribute "LOCATION" "R9E7"
					( Origin gFrontEnd )
				)
				( attribute "MATERIAL" "CHIP"
					( Origin gFrontEnd )
				)
				( attribute "PACK_TYPE" "0402"
					( Origin gFrontEnd )
				)
				( attribute "PART_NUMBER" "G21796-027"
					( Origin gFrontEnd )
				)
				( attribute "PHYS_PAGE" "139"
					( Origin gFrontEnd )
				)
				( attribute "ROOM" "NIC_SPRV"
					( Origin gFrontEnd )
				)
				( attribute "ROT" "0"
					( Origin gFrontEnd )
				)
				( attribute "SEC" "1"
					( Origin gPackager )
				)
				( attribute "TOLERANCE" "1%"
					( Origin gFrontEnd )
				)
				( attribute "VALUE" "3.32K"
					( Origin gFrontEnd )
				)
				( attribute "VER" "2"
					( Origin gFrontEnd )
				)
				( attribute "WATTAGE" "1/16W"
					( Origin gFrontEnd )
				)
				( attribute "XY" "(-1000,4475)"
					( Origin gFrontEnd )
				)
				( attribute "CHIPS_PART_NAME" "RES"
					( Origin gPackager )
				)
				( attribute "CDS_PART_NAME" "RES_0402-3.32K,1%,1/16W,CHIP,GA"
					( Origin gPackager )
				)
				( objectStatus "R9E7" )
				( pin "a"
					( attribute "PN" "1"
						( Origin gPackager )
					)
					( objectStatus "R9E7.1" )
				)
				( pin "b"
					( attribute "PN" "2"
						( Origin gPackager )
					)
					( objectStatus "R9E7.2" )
				)
			)
			( gate "@baseboard_fab2_lib.baseboard_fab2(sch_1):page139_i195"
				( attribute "BOM_COST" "NT_GBE_BASE"
					( Origin gFrontEnd )
				)
				( attribute "CDS_LIB" "mstr_discrete"
					( Origin gPackager )
				)
				( attribute "CDS_LOCATION" "R1R1"
					( Origin gPackager )
				)
				( attribute "CDS_SEC" "1"
					( Origin gPackager )
				)
				( attribute "LOCATION" "R1R1"
					( Origin gFrontEnd )
				)
				( attribute "MATERIAL" "CHIP"
					( Origin gFrontEnd )
				)
				( attribute "PACK_TYPE" "0402"
					( Origin gFrontEnd )
				)
				( attribute "PART_NUMBER" "G21497-005"
					( Origin gFrontEnd )
				)
				( attribute "PHYS_PAGE" "139"
					( Origin gFrontEnd )
				)
				( attribute "ROOM" "NIC_SPRV"
					( Origin gFrontEnd )
				)
				( attribute "ROT" "0"
					( Origin gFrontEnd )
				)
				( attribute "SEC" "1"
					( Origin gFrontEnd )
				)
				( attribute "SEC_TYPE" "0402"
					( Origin gFrontEnd )
				)
				( attribute "TOLERANCE" "5%"
					( Origin gFrontEnd )
				)
				( attribute "VALUE" "0.0"
					( Origin gFrontEnd )
				)
				( attribute "VER" "1"
					( Origin gFrontEnd )
				)
				( attribute "WATTAGE" "1/16W"
					( Origin gFrontEnd )
				)
				( attribute "XY" "(-6600,550)"
					( Origin gFrontEnd )
				)
				( attribute "CHIPS_PART_NAME" "RES"
					( Origin gPackager )
				)
				( attribute "CDS_PART_NAME" "RES_0402-0.0,5%,1/16W,CHIP,G21A"
					( Origin gPackager )
				)
				( objectStatus "R1R1" )
				( pin "a"
					( attribute "PN" "1"
						( Origin gPackager )
					)
					( objectStatus "R1R1.1" )
				)
				( pin "b"
					( attribute "PN" "2"
						( Origin gPackager )
					)
					( objectStatus "R1R1.2" )
				)
			)
			( gate "@baseboard_fab2_lib.baseboard_fab2(sch_1):page139_i200"
				( attribute "BOM_COST" "NT_GBE_BASE"
					( Origin gFrontEnd )
				)
				( attribute "CDS_LIB" "mstr_discrete"
					( Origin gPackager )
				)
				( attribute "CDS_LOCATION" "R9E4"
					( Origin gPackager )
				)
				( attribute "CDS_SEC" "1"
					( Origin gPackager )
				)
				( attribute "LOCATION" "R9E4"
					( Origin gFrontEnd )
				)
				( attribute "MATERIAL" "CHIP"
					( Origin gFrontEnd )
				)
				( attribute "PACK_TYPE" "0402"
					( Origin gFrontEnd )
				)
				( attribute "PART_NUMBER" "G21796-016"
					( Origin gFrontEnd )
				)
				( attribute "PHYS_PAGE" "139"
					( Origin gFrontEnd )
				)
				( attribute "ROOM" "NIC_SPRV"
					( Origin gFrontEnd )
				)
				( attribute "ROT" "0"
					( Origin gFrontEnd )
				)
				( attribute "SEC" "1"
					( Origin gFrontEnd )
				)
				( attribute "SEC_TYPE" "0402"
					( Origin gFrontEnd )
				)
				( attribute "TOLERANCE" "1%"
					( Origin gFrontEnd )
				)
				( attribute "VALUE" "10.0K"
					( Origin gFrontEnd )
				)
				( attribute "VER" "2"
					( Origin gFrontEnd )
				)
				( attribute "WATTAGE" "1/16W"
					( Origin gFrontEnd )
				)
				( attribute "XY" "(-6350,775)"
					( Origin gFrontEnd )
				)
				( attribute "CHIPS_PART_NAME" "RES"
					( Origin gPackager )
				)
				( attribute "CDS_PART_NAME" "RES_0402-10.0K,1%,1/16W,CHIP,GA"
					( Origin gPackager )
				)
				( objectStatus "R9E4" )
				( pin "a"
					( attribute "PN" "1"
						( Origin gPackager )
					)
					( objectStatus "R9E4.1" )
				)
				( pin "b"
					( attribute "PN" "2"
						( Origin gPackager )
					)
					( objectStatus "R9E4.2" )
				)
			)
			( gate "@baseboard_fab2_lib.baseboard_fab2(sch_1):page139_i201"
				( attribute "BOM_COST" "NT_GBE_BASE"
					( Origin gFrontEnd )
				)
				( attribute "CDS_LIB" "mstr_discrete"
					( Origin gPackager )
				)
				( attribute "CDS_LOCATION" "R9E18"
					( Origin gPackager )
				)
				( attribute "CDS_SEC" "1"
					( Origin gPackager )
				)
				( attribute "LOCATION" "R9E18"
					( Origin gFrontEnd )
				)
				( attribute "MATERIAL" "CHIP"
					( Origin gFrontEnd )
				)
				( attribute "PACK_TYPE" "0402"
					( Origin gFrontEnd )
				)
				( attribute "PART_NUMBER" "G21497-005"
					( Origin gFrontEnd )
				)
				( attribute "PHYS_PAGE" "139"
					( Origin gFrontEnd )
				)
				( attribute "ROOM" "NIC_SPRV"
					( Origin gFrontEnd )
				)
				( attribute "ROT" "0"
					( Origin gFrontEnd )
				)
				( attribute "SEC" "1"
					( Origin gFrontEnd )
				)
				( attribute "SEC_TYPE" "0402"
					( Origin gFrontEnd )
				)
				( attribute "TOLERANCE" "5%"
					( Origin gFrontEnd )
				)
				( attribute "VALUE" "0.0"
					( Origin gFrontEnd )
				)
				( attribute "VER" "1"
					( Origin gFrontEnd )
				)
				( attribute "WATTAGE" "1/16W"
					( Origin gFrontEnd )
				)
				( attribute "XY" "(-6875,1575)"
					( Origin gFrontEnd )
				)
				( attribute "CHIPS_PART_NAME" "RES"
					( Origin gPackager )
				)
				( attribute "CDS_PART_NAME" "RES_0402-0.0,5%,1/16W,CHIP,G21A"
					( Origin gPackager )
				)
				( objectStatus "R9E18" )
				( pin "a"
					( attribute "PN" "1"
						( Origin gPackager )
					)
					( objectStatus "R9E18.1" )
				)
				( pin "b"
					( attribute "PN" "2"
						( Origin gPackager )
					)
					( objectStatus "R9E18.2" )
				)
			)
			( gate "@baseboard_fab2_lib.baseboard_fab2(sch_1):page139_i212"
				( attribute "BOM_COST" "NT_GBE_BASE"
					( Origin gFrontEnd )
				)
				( attribute "CDS_LIB" "mstr_discrete"
					( Origin gPackager )
				)
				( attribute "CDS_LOCATION" "R9E13"
					( Origin gPackager )
				)
				( attribute "CDS_SEC" "1"
					( Origin gPackager )
				)
				( attribute "LOCATION" "R9E13"
					( Origin gFrontEnd )
				)
				( attribute "MATERIAL" "CHIP"
					( Origin gFrontEnd )
				)
				( attribute "PACK_TYPE" "0402"
					( Origin gFrontEnd )
				)
				( attribute "PART_NUMBER" "G21796-016"
					( Origin gFrontEnd )
				)
				( attribute "PHYS_PAGE" "139"
					( Origin gFrontEnd )
				)
				( attribute "ROOM" "NIC_SPRV"
					( Origin gFrontEnd )
				)
				( attribute "ROT" "0"
					( Origin gFrontEnd )
				)
				( attribute "SEC" "1"
					( Origin gPackager )
				)
				( attribute "TOLERANCE" "1%"
					( Origin gFrontEnd )
				)
				( attribute "VALUE" "10.0K"
					( Origin gFrontEnd )
				)
				( attribute "VER" "2"
					( Origin gFrontEnd )
				)
				( attribute "WATTAGE" "1/16W"
					( Origin gFrontEnd )
				)
				( attribute "XY" "(-1900,1650)"
					( Origin gFrontEnd )
				)
				( attribute "CHIPS_PART_NAME" "RES"
					( Origin gPackager )
				)
				( attribute "CDS_PART_NAME" "RES_0402-10.0K,1%,1/16W,CHIP,GA"
					( Origin gPackager )
				)
				( objectStatus "R9E13" )
				( pin "a"
					( attribute "PN" "1"
						( Origin gPackager )
					)
					( objectStatus "R9E13.1" )
				)
				( pin "b"
					( attribute "PN" "2"
						( Origin gPackager )
					)
					( objectStatus "R9E13.2" )
				)
			)
			( gate "@baseboard_fab2_lib.baseboard_fab2(sch_1):page139_i213"
				( attribute "BOM_COST" "NT_GBE_BASE"
					( Origin gFrontEnd )
				)
				( attribute "CDS_LIB" "mstr_discrete"
					( Origin gPackager )
				)
				( attribute "CDS_LOCATION" "R1R12"
					( Origin gPackager )
				)
				( attribute "CDS_SEC" "1"
					( Origin gPackager )
				)
				( attribute "LOCATION" "R1R12"
					( Origin gFrontEnd )
				)
				( attribute "MATERIAL" "CHIP"
					( Origin gFrontEnd )
				)
				( attribute "PACK_TYPE" "0402"
					( Origin gFrontEnd )
				)
				( attribute "PART_NUMBER" "G21796-016"
					( Origin gFrontEnd )
				)
				( attribute "PHYS_PAGE" "139"
					( Origin gFrontEnd )
				)
				( attribute "ROOM" "NIC_SPRV"
					( Origin gFrontEnd )
				)
				( attribute "ROT" "0"
					( Origin gFrontEnd )
				)
				( attribute "SEC" "1"
					( Origin gPackager )
				)
				( attribute "TOLERANCE" "1%"
					( Origin gFrontEnd )
				)
				( attribute "VALUE" "10.0K"
					( Origin gFrontEnd )
				)
				( attribute "VER" "2"
					( Origin gFrontEnd )
				)
				( attribute "WATTAGE" "1/16W"
					( Origin gFrontEnd )
				)
				( attribute "XY" "(-2875,1525)"
					( Origin gFrontEnd )
				)
				( attribute "CHIPS_PART_NAME" "RES"
					( Origin gPackager )
				)
				( attribute "CDS_PART_NAME" "RES_0402-10.0K,1%,1/16W,CHIP,GA"
					( Origin gPackager )
				)
				( objectStatus "R1R12" )
				( pin "a"
					( attribute "PN" "1"
						( Origin gPackager )
					)
					( objectStatus "R1R12.1" )
				)
				( pin "b"
					( attribute "PN" "2"
						( Origin gPackager )
					)
					( objectStatus "R1R12.2" )
				)
			)
			( gate "@baseboard_fab2_lib.baseboard_fab2(sch_1):page139_i214"
				( attribute "BOM_COST" "NT_GBE_BASE"
					( Origin gFrontEnd )
				)
				( attribute "CDS_LIB" "mstr_discrete"
					( Origin gPackager )
				)
				( attribute "CDS_LOCATION" "R1T1"
					( Origin gPackager )
				)
				( attribute "CDS_SEC" "1"
					( Origin gPackager )
				)
				( attribute "LOCATION" "R1T1"
					( Origin gFrontEnd )
				)
				( attribute "MATERIAL" "CHIP"
					( Origin gFrontEnd )
				)
				( attribute "PACK_TYPE" "0402"
					( Origin gFrontEnd )
				)
				( attribute "PART_NUMBER" "G21796-016"
					( Origin gFrontEnd )
				)
				( attribute "PHYS_PAGE" "139"
					( Origin gFrontEnd )
				)
				( attribute "ROOM" "NIC_SPRV"
					( Origin gFrontEnd )
				)
				( attribute "ROT" "0"
					( Origin gFrontEnd )
				)
				( attribute "SEC" "1"
					( Origin gPackager )
				)
				( attribute "TOLERANCE" "1%"
					( Origin gFrontEnd )
				)
				( attribute "VALUE" "10.0K"
					( Origin gFrontEnd )
				)
				( attribute "VER" "2"
					( Origin gFrontEnd )
				)
				( attribute "WATTAGE" "1/16W"
					( Origin gFrontEnd )
				)
				( attribute "XY" "(-875,1550)"
					( Origin gFrontEnd )
				)
				( attribute "CHIPS_PART_NAME" "RES"
					( Origin gPackager )
				)
				( attribute "CDS_PART_NAME" "RES_0402-10.0K,1%,1/16W,CHIP,GA"
					( Origin gPackager )
				)
				( objectStatus "R1T1" )
				( pin "a"
					( attribute "PN" "1"
						( Origin gPackager )
					)
					( objectStatus "R1T1.1" )
				)
				( pin "b"
					( attribute "PN" "2"
						( Origin gPackager )
					)
					( objectStatus "R1T1.2" )
				)
			)
			( gate "@baseboard_fab2_lib.baseboard_fab2(sch_1):page139_i225"
				( attribute "CDS_LIB" "mstr_discrete"
					( Origin gPackager )
				)
				( attribute "CDS_LOCATION" "R9F1"
					( Origin gPackager )
				)
				( attribute "CDS_SEC" "1"
					( Origin gPackager )
				)
				( attribute "LOCATION" "R9F1"
					( Origin gFrontEnd )
				)
				( attribute "MATERIAL" "CHIP"
					( Origin gFrontEnd )
				)
				( attribute "PACK_TYPE" "0402"
					( Origin gFrontEnd )
				)
				( attribute "PART_NUMBER" "G21796-250"
					( Origin gFrontEnd )
				)
				( attribute "PHYS_PAGE" "139"
					( Origin gFrontEnd )
				)
				( attribute "ROT" "0"
					( Origin gFrontEnd )
				)
				( attribute "SEC" "1"
					( Origin gPackager )
				)
				( attribute "TOLERANCE" "1.0%"
					( Origin gFrontEnd )
				)
				( attribute "VALUE" "22.1"
					( Origin gFrontEnd )
				)
				( attribute "VER" "1"
					( Origin gFrontEnd )
				)
				( attribute "WATTAGE" "1/16W"
					( Origin gFrontEnd )
				)
				( attribute "XY" "(-2400,2675)"
					( Origin gFrontEnd )
				)
				( attribute "CHIPS_PART_NAME" "RES"
					( Origin gPackager )
				)
				( attribute "CDS_PART_NAME" "RES_0402-22.1,1.0%,1/16W,CHIP,A"
					( Origin gPackager )
				)
				( objectStatus "R9F1" )
				( pin "a"
					( attribute "PN" "1"
						( Origin gPackager )
					)
					( objectStatus "R9F1.1" )
				)
				( pin "b"
					( attribute "PN" "2"
						( Origin gPackager )
					)
					( objectStatus "R9F1.2" )
				)
			)
			( gate "@baseboard_fab2_lib.baseboard_fab2(sch_1):page139_i228"
				( attribute "BOM_COST" "SM_CONTROLLER"
					( Origin gFrontEnd )
				)
				( attribute "CDS_LIB" "mstr_discrete"
					( Origin gPackager )
				)
				( attribute "CDS_LOCATION" "R9E19"
					( Origin gPackager )
				)
				( attribute "CDS_SEC" "1"
					( Origin gPackager )
				)
				( attribute "LOCATION" "R9E19"
					( Origin gFrontEnd )
				)
				( attribute "MATERIAL" "CHIP"
					( Origin gFrontEnd )
				)
				( attribute "PACK_TYPE" "0402"
					( Origin gFrontEnd )
				)
				( attribute "PART_NUMBER" "G21796-250"
					( Origin gFrontEnd )
				)
				( attribute "PHYS_PAGE" "139"
					( Origin gFrontEnd )
				)
				( attribute "ROOM" "BMC"
					( Origin gFrontEnd )
				)
				( attribute "ROT" "0"
					( Origin gFrontEnd )
				)
				( attribute "SEC" "1"
					( Origin gFrontEnd )
				)
				( attribute "SEC_TYPE" "0402"
					( Origin gFrontEnd )
				)
				( attribute "TOLERANCE" "1.0%"
					( Origin gFrontEnd )
				)
				( attribute "VALUE" "22.1"
					( Origin gFrontEnd )
				)
				( attribute "VER" "1"
					( Origin gFrontEnd )
				)
				( attribute "WATTAGE" "1/16W"
					( Origin gFrontEnd )
				)
				( attribute "XY" "(-2275,2525)"
					( Origin gFrontEnd )
				)
				( attribute "CHIPS_PART_NAME" "RES"
					( Origin gPackager )
				)
				( attribute "CDS_PART_NAME" "RES_0402-22.1,1.0%,1/16W,CHIP,A"
					( Origin gPackager )
				)
				( objectStatus "R9E19" )
				( pin "a"
					( attribute "PN" "1"
						( Origin gPackager )
					)
					( objectStatus "R9E19.1" )
				)
				( pin "b"
					( attribute "PN" "2"
						( Origin gPackager )
					)
					( objectStatus "R9E19.2" )
				)
			)
			( gate "@baseboard_fab2_lib.baseboard_fab2(sch_1):page139_i229"
				( attribute "BOM_COST" "SM_CONTROLLER"
					( Origin gFrontEnd )
				)
				( attribute "CDS_LIB" "mstr_discrete"
					( Origin gPackager )
				)
				( attribute "CDS_LOCATION" "R9E17"
					( Origin gPackager )
				)
				( attribute "CDS_SEC" "1"
					( Origin gPackager )
				)
				( attribute "LOCATION" "R9E17"
					( Origin gFrontEnd )
				)
				( attribute "MATERIAL" "CHIP"
					( Origin gFrontEnd )
				)
				( attribute "PACK_TYPE" "0402"
					( Origin gFrontEnd )
				)
				( attribute "PART_NUMBER" "G21796-250"
					( Origin gFrontEnd )
				)
				( attribute "PHYS_PAGE" "139"
					( Origin gFrontEnd )
				)
				( attribute "ROOM" "BMC"
					( Origin gFrontEnd )
				)
				( attribute "ROT" "0"
					( Origin gFrontEnd )
				)
				( attribute "SEC" "1"
					( Origin gFrontEnd )
				)
				( attribute "SEC_TYPE" "0402"
					( Origin gFrontEnd )
				)
				( attribute "TOLERANCE" "1.0%"
					( Origin gFrontEnd )
				)
				( attribute "VALUE" "22.1"
					( Origin gFrontEnd )
				)
				( attribute "VER" "1"
					( Origin gFrontEnd )
				)
				( attribute "WATTAGE" "1/16W"
					( Origin gFrontEnd )
				)
				( attribute "XY" "(-1750,2475)"
					( Origin gFrontEnd )
				)
				( attribute "CHIPS_PART_NAME" "RES"
					( Origin gPackager )
				)
				( attribute "CDS_PART_NAME" "RES_0402-22.1,1.0%,1/16W,CHIP,A"
					( Origin gPackager )
				)
				( objectStatus "R9E17" )
				( pin "a"
					( attribute "PN" "1"
						( Origin gPackager )
					)
					( objectStatus "R9E17.1" )
				)
				( pin "b"
					( attribute "PN" "2"
						( Origin gPackager )
					)
					( objectStatus "R9E17.2" )
				)
			)
			( gate "@baseboard_fab2_lib.baseboard_fab2(sch_1):page139_i235"
				( attribute "CDS_LIB" "mstr_discrete"
					( Origin gPackager )
				)
				( attribute "CDS_LOCATION" "R9E16"
					( Origin gPackager )
				)
				( attribute "CDS_SEC" "1"
					( Origin gPackager )
				)
				( attribute "LOCATION" "R9E16"
					( Origin gFrontEnd )
				)
				( attribute "MATERIAL" "CHIP"
					( Origin gFrontEnd )
				)
				( attribute "PACK_TYPE" "0402"
					( Origin gFrontEnd )
				)
				( attribute "PART_NUMBER" "G21796-074"
					( Origin gFrontEnd )
				)
				( attribute "PHYS_PAGE" "139"
					( Origin gFrontEnd )
				)
				( attribute "ROOM" "SB"
					( Origin gFrontEnd )
				)
				( attribute "ROT" "0"
					( Origin gFrontEnd )
				)
				( attribute "SEC" "1"
					( Origin gFrontEnd )
				)
				( attribute "SEC_TYPE" "0402"
					( Origin gFrontEnd )
				)
				( attribute "TOLERANCE" "1%"
					( Origin gFrontEnd )
				)
				( attribute "VALUE" "33.2"
					( Origin gFrontEnd )
				)
				( attribute "VER" "1"
					( Origin gFrontEnd )
				)
				( attribute "WATTAGE" "1/16W"
					( Origin gFrontEnd )
				)
				( attribute "XY" "(-2075,2725)"
					( Origin gFrontEnd )
				)
				( attribute "CHIPS_PART_NAME" "RES"
					( Origin gPackager )
				)
				( attribute "CDS_PART_NAME" "RES_0402-33.2,1%,1/16W,CHIP,G2A"
					( Origin gPackager )
				)
				( objectStatus "R9E16" )
				( pin "a"
					( attribute "PN" "1"
						( Origin gPackager )
					)
					( objectStatus "R9E16.1" )
				)
				( pin "b"
					( attribute "PN" "2"
						( Origin gPackager )
					)
					( objectStatus "R9E16.2" )
				)
			)
			( gate "@baseboard_fab2_lib.baseboard_fab2(sch_1):page139_i237"
				( attribute "BOM_COST" "NT_GBE_BASE"
					( Origin gFrontEnd )
				)
				( attribute "CDS_LIB" "mstr_discrete"
					( Origin gPackager )
				)
				( attribute "CDS_LOCATION" "R1R15"
					( Origin gPackager )
				)
				( attribute "CDS_SEC" "1"
					( Origin gPackager )
				)
				( attribute "LOCATION" "R1R15"
					( Origin gFrontEnd )
				)
				( attribute "MATERIAL" "CHIP"
					( Origin gFrontEnd )
				)
				( attribute "PACK_TYPE" "0603"
					( Origin gFrontEnd )
				)
				( attribute "PART_NUMBER" "G22178-002"
					( Origin gFrontEnd )
				)
				( attribute "PHYS_PAGE" "139"
					( Origin gFrontEnd )
				)
				( attribute "ROOM" "NIC_SPRV"
					( Origin gFrontEnd )
				)
				( attribute "ROT" "0"
					( Origin gFrontEnd )
				)
				( attribute "SEC" "1"
					( Origin gFrontEnd )
				)
				( attribute "SEC_TYPE" "0603"
					( Origin gFrontEnd )
				)
				( attribute "TOLERANCE" "5.0%"
					( Origin gFrontEnd )
				)
				( attribute "VALUE" "0"
					( Origin gFrontEnd )
				)
				( attribute "VER" "1"
					( Origin gFrontEnd )
				)
				( attribute "WATTAGE" "1/10W"
					( Origin gFrontEnd )
				)
				( attribute "XY" "(-5600,4025)"
					( Origin gFrontEnd )
				)
				( attribute "CHIPS_PART_NAME" "RES"
					( Origin gPackager )
				)
				( attribute "CDS_PART_NAME" "RES_0603-0,5.0%,1/10W,CHIP,G22A"
					( Origin gPackager )
				)
				( objectStatus "R1R15" )
				( pin "a"
					( attribute "PN" "1"
						( Origin gPackager )
					)
					( objectStatus "R1R15.1" )
				)
				( pin "b"
					( attribute "PN" "2"
						( Origin gPackager )
					)
					( objectStatus "R1R15.2" )
				)
			)
			( gate "@baseboard_fab2_lib.baseboard_fab2(sch_1):page139_i238"
				( attribute "BOM_COST" "NT_GBE_BASE"
					( Origin gFrontEnd )
				)
				( attribute "CDS_LIB" "mstr_discrete"
					( Origin gPackager )
				)
				( attribute "CDS_LOCATION" "R1T32"
					( Origin gPackager )
				)
				( attribute "CDS_SEC" "1"
					( Origin gPackager )
				)
				( attribute "LOCATION" "R1T32"
					( Origin gFrontEnd )
				)
				( attribute "MATERIAL" "CHIP"
					( Origin gFrontEnd )
				)
				( attribute "PACK_TYPE" "0603"
					( Origin gFrontEnd )
				)
				( attribute "PART_NUMBER" "G22178-002"
					( Origin gFrontEnd )
				)
				( attribute "PHYS_PAGE" "139"
					( Origin gFrontEnd )
				)
				( attribute "ROOM" "NIC_SPRV"
					( Origin gFrontEnd )
				)
				( attribute "ROT" "0"
					( Origin gFrontEnd )
				)
				( attribute "SEC" "1"
					( Origin gFrontEnd )
				)
				( attribute "SEC_TYPE" "0603"
					( Origin gFrontEnd )
				)
				( attribute "TOLERANCE" "5.0%"
					( Origin gFrontEnd )
				)
				( attribute "VALUE" "0"
					( Origin gFrontEnd )
				)
				( attribute "VER" "1"
					( Origin gFrontEnd )
				)
				( attribute "WATTAGE" "1/10W"
					( Origin gFrontEnd )
				)
				( attribute "XY" "(-5800,3875)"
					( Origin gFrontEnd )
				)
				( attribute "CHIPS_PART_NAME" "RES"
					( Origin gPackager )
				)
				( attribute "CDS_PART_NAME" "RES_0603-0,5.0%,1/10W,CHIP,G22A"
					( Origin gPackager )
				)
				( objectStatus "R1T32" )
				( pin "a"
					( attribute "PN" "1"
						( Origin gPackager )
					)
					( objectStatus "R1T32.1" )
				)
				( pin "b"
					( attribute "PN" "2"
						( Origin gPackager )
					)
					( objectStatus "R1T32.2" )
				)
			)
			( gate "@baseboard_fab2_lib.baseboard_fab2(sch_1):page139_i239"
				( attribute "BOM_COST" "NT_GBE_BASE"
					( Origin gFrontEnd )
				)
				( attribute "CDS_LIB" "mstr_discrete"
					( Origin gPackager )
				)
				( attribute "CDS_LOCATION" "R1T34"
					( Origin gPackager )
				)
				( attribute "CDS_SEC" "1"
					( Origin gPackager )
				)
				( attribute "LOCATION" "R1T34"
					( Origin gFrontEnd )
				)
				( attribute "MATERIAL" "CHIP"
					( Origin gFrontEnd )
				)
				( attribute "PACK_TYPE" "0603"
					( Origin gFrontEnd )
				)
				( attribute "PART_NUMBER" "G22178-002"
					( Origin gFrontEnd )
				)
				( attribute "PHYS_PAGE" "139"
					( Origin gFrontEnd )
				)
				( attribute "ROOM" "NIC_SPRV"
					( Origin gFrontEnd )
				)
				( attribute "ROT" "0"
					( Origin gFrontEnd )
				)
				( attribute "SEC" "1"
					( Origin gFrontEnd )
				)
				( attribute "SEC_TYPE" "0603"
					( Origin gFrontEnd )
				)
				( attribute "TOLERANCE" "5.0%"
					( Origin gFrontEnd )
				)
				( attribute "VALUE" "0"
					( Origin gFrontEnd )
				)
				( attribute "VER" "1"
					( Origin gFrontEnd )
				)
				( attribute "WATTAGE" "1/10W"
					( Origin gFrontEnd )
				)
				( attribute "XY" "(-5600,3525)"
					( Origin gFrontEnd )
				)
				( attribute "CHIPS_PART_NAME" "RES"
					( Origin gPackager )
				)
				( attribute "CDS_PART_NAME" "RES_0603-0,5.0%,1/10W,CHIP,G22A"
					( Origin gPackager )
				)
				( objectStatus "R1T34" )
				( pin "a"
					( attribute "PN" "1"
						( Origin gPackager )
					)
					( objectStatus "R1T34.1" )
				)
				( pin "b"
					( attribute "PN" "2"
						( Origin gPackager )
					)
					( objectStatus "R1T34.2" )
				)
			)
			( gate "@baseboard_fab2_lib.baseboard_fab2(sch_1):page139_i240"
				( attribute "BOM_COST" "NT_GBE_BASE"
					( Origin gFrontEnd )
				)
				( attribute "CDS_LIB" "mstr_discrete"
					( Origin gPackager )
				)
				( attribute "CDS_LOCATION" "R1T33"
					( Origin gPackager )
				)
				( attribute "CDS_SEC" "1"
					( Origin gPackager )
				)
				( attribute "LOCATION" "R1T33"
					( Origin gFrontEnd )
				)
				( attribute "MATERIAL" "EMPTY"
					( Origin gFrontEnd )
				)
				( attribute "PACK_TYPE" "0603"
					( Origin gFrontEnd )
				)
				( attribute "PART_NUMBER" "G22178-002"
					( Origin gFrontEnd )
				)
				( attribute "PHYS_PAGE" "139"
					( Origin gFrontEnd )
				)
				( attribute "ROOM" "NIC_SPRV"
					( Origin gFrontEnd )
				)
				( attribute "ROT" "0"
					( Origin gFrontEnd )
				)
				( attribute "SEC" "1"
					( Origin gFrontEnd )
				)
				( attribute "SEC_TYPE" "0603"
					( Origin gFrontEnd )
				)
				( attribute "TOLERANCE" "5.0%"
					( Origin gFrontEnd )
				)
				( attribute "VALUE" "0"
					( Origin gFrontEnd )
				)
				( attribute "VER" "1"
					( Origin gFrontEnd )
				)
				( attribute "WATTAGE" "1/10W"
					( Origin gFrontEnd )
				)
				( attribute "XY" "(-5800,3725)"
					( Origin gFrontEnd )
				)
				( attribute "CHIPS_PART_NAME" "RES"
					( Origin gPackager )
				)
				( attribute "CDS_PART_NAME" "RES_0603-0,5.0%,1/10W,EMPTY,G2A"
					( Origin gPackager )
				)
				( objectStatus "R1T33" )
				( pin "a"
					( attribute "PN" "1"
						( Origin gPackager )
					)
					( objectStatus "R1T33.1" )
				)
				( pin "b"
					( attribute "PN" "2"
						( Origin gPackager )
					)
					( objectStatus "R1T33.2" )
				)
			)
			( gate "@baseboard_fab2_lib.baseboard_fab2(sch_1):page139_i241"
				( attribute "BOM_COST" "NT_GBE_BASE"
					( Origin gFrontEnd )
				)
				( attribute "CDS_LIB" "dev_discrete"
					( Origin gPackager )
				)
				( attribute "CDS_LOCATION" "C9E12"
					( Origin gPackager )
				)
				( attribute "CDS_SEC" "1"
					( Origin gPackager )
				)
				( attribute "LOCATION" "C9E12"
					( Origin gFrontEnd )
				)
				( attribute "MATERIAL" "EMPTY"
					( Origin gFrontEnd )
				)
				( attribute "PACK_TYPE" "0603V"
					( Origin gFrontEnd )
				)
				( attribute "PART_NUMBER" "E15431-004"
					( Origin gFrontEnd )
				)
				( attribute "PHYS_PAGE" "139"
					( Origin gFrontEnd )
				)
				( attribute "ROOM" "NIC_SPRV"
					( Origin gFrontEnd )
				)
				( attribute "ROT" "0"
					( Origin gFrontEnd )
				)
				( attribute "SEC" "1"
					( Origin gFrontEnd )
				)
				( attribute "SEC_TYPE" "0603V"
					( Origin gFrontEnd )
				)
				( attribute "TOLERANCE" "20%"
					( Origin gFrontEnd )
				)
				( attribute "VALUE" "22.0UF"
					( Origin gFrontEnd )
				)
				( attribute "VER" "1"
					( Origin gFrontEnd )
				)
				( attribute "VOLTAGE" "4V"
					( Units "uVoltage" "V" 1.000000)
					( Origin gFrontEnd )
				)
				( attribute "XY" "(-1925,875)"
					( Origin gFrontEnd )
				)
				( attribute "CHIPS_PART_NAME" "CAP_A"
					( Origin gPackager )
				)
				( attribute "CDS_PART_NAME" "CAP_A_0603V-22.0UF,4V,20%,EMPTA"
					( Origin gPackager )
				)
				( objectStatus "C9E12" )
				( pin "a"
					( attribute "PN" "1"
						( Origin gPackager )
					)
					( objectStatus "C9E12.1" )
				)
				( pin "b"
					( attribute "PN" "2"
						( Origin gPackager )
					)
					( objectStatus "C9E12.2" )
				)
			)
			( gate "@baseboard_fab2_lib.baseboard_fab2(sch_1):page140_i1"
				( attribute "BOM_COST" "NT_GBE_BASE"
					( Origin gFrontEnd )
				)
				( attribute "CDS_LIB" "mstr_memory"
					( Origin gPackager )
				)
				( attribute "CDS_LOCATION" "U9E1"
					( Origin gPackager )
				)
				( attribute "CDS_SEC" "1"
					( Origin gPackager )
				)
				( attribute "LOCATION" "U9E1"
					( Origin gFrontEnd )
				)
				( attribute "MATERIAL" "IC"
					( Origin gFrontEnd )
				)
				( attribute "PACK_TYPE" "SM"
					( Origin gFrontEnd )
				)
				( attribute "PART_NUMBER" "H77797-001"
					( Origin gFrontEnd )
				)
				( attribute "PHYS_PAGE" "140"
					( Origin gFrontEnd )
				)
				( attribute "ROOM" "NIC_SPRV"
					( Origin gFrontEnd )
				)
				( attribute "ROT" "0"
					( Origin gFrontEnd )
				)
				( attribute "SEC" "1"
					( Origin gFrontEnd )
				)
				( attribute "SEC_TYPE" "SM"
					( Origin gFrontEnd )
				)
				( attribute "VER" "1"
					( Origin gFrontEnd )
				)
				( attribute "XY" "(-2350,2700)"
					( Origin gFrontEnd )
				)
				( attribute "CHIPS_PART_NAME" "M25PE16"
					( Origin gPackager )
				)
				( attribute "CDS_PART_NAME" "M25PE16_SM-IC,H77797-001"
					( Origin gPackager )
				)
				( objectStatus "U9E1" )
				( pin "c"
					( attribute "PN" "6"
						( Origin gPackager )
					)
					( objectStatus "U9E1.6" )
				)
				( pin "dq0"
					( attribute "PN" "5"
						( Origin gPackager )
					)
					( objectStatus "U9E1.5" )
				)
				( pin "dq1"
					( attribute "PN" "2"
						( Origin gPackager )
					)
					( objectStatus "U9E1.2" )
				)
				( pin "reset_n"
					( attribute "PN" "7"
						( Origin gPackager )
					)
					( objectStatus "U9E1.7" )
				)
				( pin "s_n"
					( attribute "PN" "1"
						( Origin gPackager )
					)
					( objectStatus "U9E1.1" )
				)
				( pin "vcc"
					( attribute "PN" "8"
						( Origin gPackager )
					)
					( objectStatus "U9E1.8" )
				)
				( pin "vss"
					( attribute "PN" "4"
						( Origin gPackager )
					)
					( objectStatus "U9E1.4" )
				)
				( pin "w_n"
					( attribute "PN" "3"
						( Origin gPackager )
					)
					( objectStatus "U9E1.3" )
				)
			)
			( gate "@baseboard_fab2_lib.baseboard_fab2(sch_1):page140_i3"
				( attribute "BOM_COST" "NT_GBE_BASE"
					( Origin gFrontEnd )
				)
				( attribute "CDS_LIB" "dev_discrete"
					( Origin gPackager )
				)
				( attribute "CDS_LOCATION" "C1R25"
					( Origin gPackager )
				)
				( attribute "CDS_SEC" "1"
					( Origin gPackager )
				)
				( attribute "LOCATION" "C1R25"
					( Origin gFrontEnd )
				)
				( attribute "MATERIAL" "X7R"
					( Origin gFrontEnd )
				)
				( attribute "PACK_TYPE" "0402V"
					( Origin gFrontEnd )
				)
				( attribute "PART_NUMBER" "A36096-030"
					( Origin gFrontEnd )
				)
				( attribute "PHYS_PAGE" "140"
					( Origin gFrontEnd )
				)
				( attribute "ROOM" "NIC_SPRV"
					( Origin gFrontEnd )
				)
				( attribute "ROT" "0"
					( Origin gFrontEnd )
				)
				( attribute "SEC" "1"
					( Origin gFrontEnd )
				)
				( attribute "SEC_TYPE" "0402V"
					( Origin gFrontEnd )
				)
				( attribute "TOLERANCE" "10%"
					( Origin gFrontEnd )
				)
				( attribute "VALUE" "0.1UF"
					( Origin gFrontEnd )
				)
				( attribute "VER" "1"
					( Origin gFrontEnd )
				)
				( attribute "VOLTAGE" "16V"
					( Units "uVoltage" "V" 1.000000)
					( Origin gFrontEnd )
				)
				( attribute "XY" "(-2475,3375)"
					( Origin gFrontEnd )
				)
				( attribute "CHIPS_PART_NAME" "CAP_A"
					( Origin gPackager )
				)
				( attribute "CDS_PART_NAME" "CAP_A_0402V-0.1UF,16V,10%,X7R,A"
					( Origin gPackager )
				)
				( objectStatus "C1R25" )
				( pin "a"
					( attribute "PN" "1"
						( Origin gPackager )
					)
					( objectStatus "C1R25.1" )
				)
				( pin "b"
					( attribute "PN" "2"
						( Origin gPackager )
					)
					( objectStatus "C1R25.2" )
				)
			)
			( gate "@baseboard_fab2_lib.baseboard_fab2(sch_1):page140_i10"
				( attribute "BOM_COST" "NT_GBE_BASE"
					( Origin gFrontEnd )
				)
				( attribute "CDS_LIB" "mstr_discrete"
					( Origin gPackager )
				)
				( attribute "CDS_LOCATION" "R1R9"
					( Origin gPackager )
				)
				( attribute "CDS_SEC" "1"
					( Origin gPackager )
				)
				( attribute "LOCATION" "R1R9"
					( Origin gFrontEnd )
				)
				( attribute "MATERIAL" "CHIP"
					( Origin gFrontEnd )
				)
				( attribute "PACK_TYPE" "0402"
					( Origin gFrontEnd )
				)
				( attribute "PART_NUMBER" "G21796-027"
					( Origin gFrontEnd )
				)
				( attribute "PHYS_PAGE" "140"
					( Origin gFrontEnd )
				)
				( attribute "ROOM" "NIC_SPRV"
					( Origin gFrontEnd )
				)
				( attribute "ROT" "0"
					( Origin gFrontEnd )
				)
				( attribute "SEC" "1"
					( Origin gFrontEnd )
				)
				( attribute "SEC_TYPE" "0402"
					( Origin gFrontEnd )
				)
				( attribute "TOLERANCE" "1%"
					( Origin gFrontEnd )
				)
				( attribute "VALUE" "3.32K"
					( Origin gFrontEnd )
				)
				( attribute "VER" "2"
					( Origin gFrontEnd )
				)
				( attribute "WATTAGE" "1/16W"
					( Origin gFrontEnd )
				)
				( attribute "XY" "(-3200,3300)"
					( Origin gFrontEnd )
				)
				( attribute "CHIPS_PART_NAME" "RES"
					( Origin gPackager )
				)
				( attribute "CDS_PART_NAME" "RES_0402-3.32K,1%,1/16W,CHIP,GA"
					( Origin gPackager )
				)
				( objectStatus "R1R9" )
				( pin "a"
					( attribute "PN" "1"
						( Origin gPackager )
					)
					( objectStatus "R1R9.1" )
				)
				( pin "b"
					( attribute "PN" "2"
						( Origin gPackager )
					)
					( objectStatus "R1R9.2" )
				)
			)
			( gate "@baseboard_fab2_lib.baseboard_fab2(sch_1):page140_i11"
				( attribute "BOM_COST" "NT_GBE_BASE"
					( Origin gFrontEnd )
				)
				( attribute "CDS_LIB" "mstr_discrete"
					( Origin gPackager )
				)
				( attribute "CDS_LOCATION" "R1R3"
					( Origin gPackager )
				)
				( attribute "CDS_SEC" "1"
					( Origin gPackager )
				)
				( attribute "LOCATION" "R1R3"
					( Origin gFrontEnd )
				)
				( attribute "MATERIAL" "CHIP"
					( Origin gFrontEnd )
				)
				( attribute "PACK_TYPE" "0402"
					( Origin gFrontEnd )
				)
				( attribute "PART_NUMBER" "G21796-027"
					( Origin gFrontEnd )
				)
				( attribute "PHYS_PAGE" "140"
					( Origin gFrontEnd )
				)
				( attribute "ROOM" "NIC_SPRV"
					( Origin gFrontEnd )
				)
				( attribute "ROT" "0"
					( Origin gFrontEnd )
				)
				( attribute "SEC" "1"
					( Origin gFrontEnd )
				)
				( attribute "SEC_TYPE" "0402"
					( Origin gFrontEnd )
				)
				( attribute "TOLERANCE" "1%"
					( Origin gFrontEnd )
				)
				( attribute "VALUE" "3.32K"
					( Origin gFrontEnd )
				)
				( attribute "VER" "2"
					( Origin gFrontEnd )
				)
				( attribute "WATTAGE" "1/16W"
					( Origin gFrontEnd )
				)
				( attribute "XY" "(-3550,3300)"
					( Origin gFrontEnd )
				)
				( attribute "CHIPS_PART_NAME" "RES"
					( Origin gPackager )
				)
				( attribute "CDS_PART_NAME" "RES_0402-3.32K,1%,1/16W,CHIP,GA"
					( Origin gPackager )
				)
				( objectStatus "R1R3" )
				( pin "a"
					( attribute "PN" "1"
						( Origin gPackager )
					)
					( objectStatus "R1R3.1" )
				)
				( pin "b"
					( attribute "PN" "2"
						( Origin gPackager )
					)
					( objectStatus "R1R3.2" )
				)
			)
			( gate "@baseboard_fab2_lib.baseboard_fab2(sch_1):page140_i12"
				( attribute "BOM_COST" "NT_GBE_BASE"
					( Origin gFrontEnd )
				)
				( attribute "CDS_LIB" "mstr_discrete"
					( Origin gPackager )
				)
				( attribute "CDS_LOCATION" "R1R7"
					( Origin gPackager )
				)
				( attribute "CDS_SEC" "1"
					( Origin gPackager )
				)
				( attribute "LOCATION" "R1R7"
					( Origin gFrontEnd )
				)
				( attribute "MATERIAL" "CHIP"
					( Origin gFrontEnd )
				)
				( attribute "PACK_TYPE" "0402"
					( Origin gFrontEnd )
				)
				( attribute "PART_NUMBER" "G21796-040"
					( Origin gFrontEnd )
				)
				( attribute "PHYS_PAGE" "140"
					( Origin gFrontEnd )
				)
				( attribute "ROOM" "NIC_SPRV"
					( Origin gFrontEnd )
				)
				( attribute "ROT" "0"
					( Origin gFrontEnd )
				)
				( attribute "SEC" "1"
					( Origin gFrontEnd )
				)
				( attribute "SEC_TYPE" "0402"
					( Origin gFrontEnd )
				)
				( attribute "TOLERANCE" "1%"
					( Origin gFrontEnd )
				)
				( attribute "VALUE" "20.0K"
					( Origin gFrontEnd )
				)
				( attribute "VER" "2"
					( Origin gFrontEnd )
				)
				( attribute "WATTAGE" "1/16W"
					( Origin gFrontEnd )
				)
				( attribute "XY" "(-3950,3300)"
					( Origin gFrontEnd )
				)
				( attribute "CHIPS_PART_NAME" "RES"
					( Origin gPackager )
				)
				( attribute "CDS_PART_NAME" "RES_0402-20.0K,1%,1/16W,CHIP,GA"
					( Origin gPackager )
				)
				( objectStatus "R1R7" )
				( pin "a"
					( attribute "PN" "1"
						( Origin gPackager )
					)
					( objectStatus "R1R7.1" )
				)
				( pin "b"
					( attribute "PN" "2"
						( Origin gPackager )
					)
					( objectStatus "R1R7.2" )
				)
			)
			( gate "@baseboard_fab2_lib.baseboard_fab2(sch_1):page140_i14"
				( attribute "BOM_COST" "NT_GBE_BASE"
					( Origin gFrontEnd )
				)
				( attribute "CDS_LIB" "mstr_discrete"
					( Origin gPackager )
				)
				( attribute "CDS_LOCATION" "R1R6"
					( Origin gPackager )
				)
				( attribute "CDS_SEC" "1"
					( Origin gPackager )
				)
				( attribute "LOCATION" "R1R6"
					( Origin gFrontEnd )
				)
				( attribute "MATERIAL" "EMPTY"
					( Origin gFrontEnd )
				)
				( attribute "PACK_TYPE" "0402"
					( Origin gFrontEnd )
				)
				( attribute "PART_NUMBER" "G21796-027"
					( Origin gFrontEnd )
				)
				( attribute "PHYS_PAGE" "140"
					( Origin gFrontEnd )
				)
				( attribute "ROOM" "NIC_SPRV"
					( Origin gFrontEnd )
				)
				( attribute "ROT" "0"
					( Origin gFrontEnd )
				)
				( attribute "SEC" "1"
					( Origin gFrontEnd )
				)
				( attribute "SEC_TYPE" "0402"
					( Origin gFrontEnd )
				)
				( attribute "TOLERANCE" "1%"
					( Origin gFrontEnd )
				)
				( attribute "VALUE" "3.32K"
					( Origin gFrontEnd )
				)
				( attribute "VER" "2"
					( Origin gFrontEnd )
				)
				( attribute "WATTAGE" "1/16W"
					( Origin gFrontEnd )
				)
				( attribute "XY" "(-3825,2350)"
					( Origin gFrontEnd )
				)
				( attribute "CHIPS_PART_NAME" "RES"
					( Origin gPackager )
				)
				( attribute "CDS_PART_NAME" "RES_0402-3.32K,1%,1/16W,EMPTY,A"
					( Origin gPackager )
				)
				( objectStatus "R1R6" )
				( pin "a"
					( attribute "PN" "1"
						( Origin gPackager )
					)
					( objectStatus "R1R6.1" )
				)
				( pin "b"
					( attribute "PN" "2"
						( Origin gPackager )
					)
					( objectStatus "R1R6.2" )
				)
			)
			( gate "@baseboard_fab2_lib.baseboard_fab2(sch_1):page140_i17"
				( attribute "BOM_COST" "NT_GBE_BASE"
					( Origin gFrontEnd )
				)
				( attribute "CDS_LIB" "mstr_discrete"
					( Origin gPackager )
				)
				( attribute "CDS_LOCATION" "R9E6"
					( Origin gPackager )
				)
				( attribute "CDS_SEC" "1"
					( Origin gPackager )
				)
				( attribute "LOCATION" "R9E6"
					( Origin gFrontEnd )
				)
				( attribute "MATERIAL" "CHIP"
					( Origin gFrontEnd )
				)
				( attribute "PACK_TYPE" "0402"
					( Origin gFrontEnd )
				)
				( attribute "PART_NUMBER" "G21796-074"
					( Origin gFrontEnd )
				)
				( attribute "PHYS_PAGE" "140"
					( Origin gFrontEnd )
				)
				( attribute "ROOM" "NIC_SPRV"
					( Origin gFrontEnd )
				)
				( attribute "ROT" "0"
					( Origin gFrontEnd )
				)
				( attribute "SEC" "1"
					( Origin gFrontEnd )
				)
				( attribute "SEC_TYPE" "0402"
					( Origin gFrontEnd )
				)
				( attribute "TOLERANCE" "1%"
					( Origin gFrontEnd )
				)
				( attribute "VALUE" "33.2"
					( Origin gFrontEnd )
				)
				( attribute "VER" "1"
					( Origin gFrontEnd )
				)
				( attribute "WATTAGE" "1/16W"
					( Origin gFrontEnd )
				)
				( attribute "XY" "(-1400,2750)"
					( Origin gFrontEnd )
				)
				( attribute "CHIPS_PART_NAME" "RES"
					( Origin gPackager )
				)
				( attribute "CDS_PART_NAME" "RES_0402-33.2,1%,1/16W,CHIP,G2A"
					( Origin gPackager )
				)
				( objectStatus "R9E6" )
				( pin "a"
					( attribute "PN" "1"
						( Origin gPackager )
					)
					( objectStatus "R9E6.1" )
				)
				( pin "b"
					( attribute "PN" "2"
						( Origin gPackager )
					)
					( objectStatus "R9E6.2" )
				)
			)
			( gate "@baseboard_fab2_lib.baseboard_fab2(sch_1):page141_i28"
				( attribute "BOM_COST" "NT_GBE_BASE"
					( Origin gFrontEnd )
				)
				( attribute "CDS_LIB" "mstr_discrete"
					( Origin gPackager )
				)
				( attribute "CDS_LOCATION" "R9G3"
					( Origin gPackager )
				)
				( attribute "CDS_SEC" "1"
					( Origin gPackager )
				)
				( attribute "LOCATION" "R9G3"
					( Origin gFrontEnd )
				)
				( attribute "MATERIAL" "CHIP"
					( Origin gFrontEnd )
				)
				( attribute "PACK_TYPE" "0402"
					( Origin gFrontEnd )
				)
				( attribute "PART_NUMBER" "G21796-009"
					( Origin gFrontEnd )
				)
				( attribute "PHYS_PAGE" "141"
					( Origin gFrontEnd )
				)
				( attribute "ROOM" "NIC_SPRV"
					( Origin gFrontEnd )
				)
				( attribute "ROT" "0"
					( Origin gFrontEnd )
				)
				( attribute "SEC" "1"
					( Origin gFrontEnd )
				)
				( attribute "SEC_TYPE" "0402"
					( Origin gFrontEnd )
				)
				( attribute "TOLERANCE" "1%"
					( Origin gFrontEnd )
				)
				( attribute "VALUE" "150.0"
					( Origin gFrontEnd )
				)
				( attribute "VER" "1"
					( Origin gFrontEnd )
				)
				( attribute "WATTAGE" "1/16W"
					( Origin gFrontEnd )
				)
				( attribute "XY" "(-2375,2400)"
					( Origin gFrontEnd )
				)
				( attribute "CHIPS_PART_NAME" "RES"
					( Origin gPackager )
				)
				( attribute "CDS_PART_NAME" "RES_0402-150.0,1%,1/16W,CHIP,GA"
					( Origin gPackager )
				)
				( objectStatus "R9G3" )
				( pin "a"
					( attribute "PN" "1"
						( Origin gPackager )
					)
					( objectStatus "R9G3.1" )
				)
				( pin "b"
					( attribute "PN" "2"
						( Origin gPackager )
					)
					( objectStatus "R9G3.2" )
				)
			)
			( gate "@baseboard_fab2_lib.baseboard_fab2(sch_1):page141_i30"
				( attribute "BOM_COST" "NT_GBE_BASE"
					( Origin gFrontEnd )
				)
				( attribute "CDS_LIB" "mstr_discrete"
					( Origin gPackager )
				)
				( attribute "CDS_LOCATION" "R9G2"
					( Origin gPackager )
				)
				( attribute "CDS_SEC" "1"
					( Origin gPackager )
				)
				( attribute "LOCATION" "R9G2"
					( Origin gFrontEnd )
				)
				( attribute "MATERIAL" "CHIP"
					( Origin gFrontEnd )
				)
				( attribute "PACK_TYPE" "0402"
					( Origin gFrontEnd )
				)
				( attribute "PART_NUMBER" "G21796-009"
					( Origin gFrontEnd )
				)
				( attribute "PHYS_PAGE" "141"
					( Origin gFrontEnd )
				)
				( attribute "ROOM" "NIC_SPRV"
					( Origin gFrontEnd )
				)
				( attribute "ROT" "0"
					( Origin gFrontEnd )
				)
				( attribute "SEC" "1"
					( Origin gFrontEnd )
				)
				( attribute "SEC_TYPE" "0402"
					( Origin gFrontEnd )
				)
				( attribute "TOLERANCE" "1%"
					( Origin gFrontEnd )
				)
				( attribute "VALUE" "150.0"
					( Origin gFrontEnd )
				)
				( attribute "VER" "1"
					( Origin gFrontEnd )
				)
				( attribute "WATTAGE" "1/16W"
					( Origin gFrontEnd )
				)
				( attribute "XY" "(-2550,2300)"
					( Origin gFrontEnd )
				)
				( attribute "CHIPS_PART_NAME" "RES"
					( Origin gPackager )
				)
				( attribute "CDS_PART_NAME" "RES_0402-150.0,1%,1/16W,CHIP,GA"
					( Origin gPackager )
				)
				( objectStatus "R9G2" )
				( pin "a"
					( attribute "PN" "1"
						( Origin gPackager )
					)
					( objectStatus "R9G2.1" )
				)
				( pin "b"
					( attribute "PN" "2"
						( Origin gPackager )
					)
					( objectStatus "R9G2.2" )
				)
			)
			( gate "@baseboard_fab2_lib.baseboard_fab2(sch_1):page141_i33"
				( attribute "BOM_COST" "NT_GBE_BASE"
					( Origin gFrontEnd )
				)
				( attribute "CDS_LIB" "dev_discrete"
					( Origin gPackager )
				)
				( attribute "CDS_LOCATION" "C9G7"
					( Origin gPackager )
				)
				( attribute "CDS_SEC" "1"
					( Origin gPackager )
				)
				( attribute "LOCATION" "C9G7"
					( Origin gFrontEnd )
				)
				( attribute "MATERIAL" "X7R"
					( Origin gFrontEnd )
				)
				( attribute "PACK_TYPE" "0402V"
					( Origin gFrontEnd )
				)
				( attribute "PART_NUMBER" "A36096-030"
					( Origin gFrontEnd )
				)
				( attribute "PHYS_PAGE" "141"
					( Origin gFrontEnd )
				)
				( attribute "ROOM" "NIC_SPRV"
					( Origin gFrontEnd )
				)
				( attribute "ROT" "0"
					( Origin gFrontEnd )
				)
				( attribute "SEC" "1"
					( Origin gFrontEnd )
				)
				( attribute "SEC_TYPE" "0402V"
					( Origin gFrontEnd )
				)
				( attribute "TOLERANCE" "10%"
					( Origin gFrontEnd )
				)
				( attribute "VALUE" "0.1UF"
					( Origin gFrontEnd )
				)
				( attribute "VER" "1"
					( Origin gFrontEnd )
				)
				( attribute "VOLTAGE" "16V"
					( Units "uVoltage" "V" 1.000000)
					( Origin gFrontEnd )
				)
				( attribute "XY" "(-5575,2150)"
					( Origin gFrontEnd )
				)
				( attribute "CHIPS_PART_NAME" "CAP_A"
					( Origin gPackager )
				)
				( attribute "CDS_PART_NAME" "CAP_A_0402V-0.1UF,16V,10%,X7R,A"
					( Origin gPackager )
				)
				( objectStatus "C9G7" )
				( pin "a"
					( attribute "PN" "1"
						( Origin gPackager )
					)
					( objectStatus "C9G7.1" )
				)
				( pin "b"
					( attribute "PN" "2"
						( Origin gPackager )
					)
					( objectStatus "C9G7.2" )
				)
			)
			( gate "@baseboard_fab2_lib.baseboard_fab2(sch_1):page141_i36"
				( attribute "BOM_COST" "NT_GBE_BASE"
					( Origin gFrontEnd )
				)
				( attribute "CDS_LIB" "mstr_discrete"
					( Origin gPackager )
				)
				( attribute "CDS_LOCATION" "C9G2"
					( Origin gPackager )
				)
				( attribute "CDS_SEC" "1"
					( Origin gPackager )
				)
				( attribute "LOCATION" "C9G2"
					( Origin gFrontEnd )
				)
				( attribute "MATERIAL" "X7R"
					( Origin gFrontEnd )
				)
				( attribute "PACK_TYPE" "0402LF"
					( Origin gFrontEnd )
				)
				( attribute "PART_NUMBER" "A36096-049"
					( Origin gFrontEnd )
				)
				( attribute "PHYS_PAGE" "141"
					( Origin gFrontEnd )
				)
				( attribute "ROOM" "NIC_SPRV"
					( Origin gFrontEnd )
				)
				( attribute "ROT" "0"
					( Origin gFrontEnd )
				)
				( attribute "SEC" "1"
					( Origin gFrontEnd )
				)
				( attribute "SEC_TYPE" "0402LF"
					( Origin gFrontEnd )
				)
				( attribute "TOLERANCE" "10%"
					( Origin gFrontEnd )
				)
				( attribute "VALUE" "470PF"
					( Origin gFrontEnd )
				)
				( attribute "VER" "1"
					( Origin gFrontEnd )
				)
				( attribute "VOLTAGE" "50V"
					( Units "uVoltage" "V" 1.000000)
					( Origin gFrontEnd )
				)
				( attribute "XY" "(-1700,925)"
					( Origin gFrontEnd )
				)
				( attribute "CHIPS_PART_NAME" "CAP"
					( Origin gPackager )
				)
				( attribute "CDS_PART_NAME" "CAP_0402LF-470PF,50V,10%,X7R,AA"
					( Origin gPackager )
				)
				( objectStatus "C9G2" )
				( pin "a"
					( attribute "PN" "1"
						( Origin gPackager )
					)
					( objectStatus "C9G2.1" )
				)
				( pin "b"
					( attribute "PN" "2"
						( Origin gPackager )
					)
					( objectStatus "C9G2.2" )
				)
			)
			( gate "@baseboard_fab2_lib.baseboard_fab2(sch_1):page141_i46"
				( attribute "BOM_COST" "NT_GBE_BASE"
					( Origin gFrontEnd )
				)
				( attribute "CDS_LIB" "dev_discrete"
					( Origin gPackager )
				)
				( attribute "CDS_LOCATION" "C9G4"
					( Origin gPackager )
				)
				( attribute "CDS_SEC" "1"
					( Origin gPackager )
				)
				( attribute "LOCATION" "C9G4"
					( Origin gFrontEnd )
				)
				( attribute "MATERIAL" "X7R"
					( Origin gFrontEnd )
				)
				( attribute "PACK_TYPE" "0402V"
					( Origin gFrontEnd )
				)
				( attribute "PART_NUMBER" "A36096-030"
					( Origin gFrontEnd )
				)
				( attribute "PHYS_PAGE" "141"
					( Origin gFrontEnd )
				)
				( attribute "ROOM" "NIC_SPRV"
					( Origin gFrontEnd )
				)
				( attribute "ROT" "0"
					( Origin gFrontEnd )
				)
				( attribute "SEC" "1"
					( Origin gFrontEnd )
				)
				( attribute "SEC_TYPE" "0402V"
					( Origin gFrontEnd )
				)
				( attribute "TOLERANCE" "10%"
					( Origin gFrontEnd )
				)
				( attribute "VALUE" "0.1UF"
					( Origin gFrontEnd )
				)
				( attribute "VER" "1"
					( Origin gFrontEnd )
				)
				( attribute "VOLTAGE" "16V"
					( Units "uVoltage" "V" 1.000000)
					( Origin gFrontEnd )
				)
				( attribute "XY" "(-5925,1250)"
					( Origin gFrontEnd )
				)
				( attribute "CHIPS_PART_NAME" "CAP_A"
					( Origin gPackager )
				)
				( attribute "CDS_PART_NAME" "CAP_A_0402V-0.1UF,16V,10%,X7R,A"
					( Origin gPackager )
				)
				( objectStatus "C9G4" )
				( pin "a"
					( attribute "PN" "1"
						( Origin gPackager )
					)
					( objectStatus "C9G4.1" )
				)
				( pin "b"
					( attribute "PN" "2"
						( Origin gPackager )
					)
					( objectStatus "C9G4.2" )
				)
			)
			( gate "@baseboard_fab2_lib.baseboard_fab2(sch_1):page141_i47"
				( attribute "BOM_COST" "NT_GBE_BASE"
					( Origin gFrontEnd )
				)
				( attribute "CDS_LIB" "dev_discrete"
					( Origin gPackager )
				)
				( attribute "CDS_LOCATION" "C9G6"
					( Origin gPackager )
				)
				( attribute "CDS_SEC" "1"
					( Origin gPackager )
				)
				( attribute "LOCATION" "C9G6"
					( Origin gFrontEnd )
				)
				( attribute "MATERIAL" "X7R"
					( Origin gFrontEnd )
				)
				( attribute "PACK_TYPE" "0402V"
					( Origin gFrontEnd )
				)
				( attribute "PART_NUMBER" "A36096-030"
					( Origin gFrontEnd )
				)
				( attribute "PHYS_PAGE" "141"
					( Origin gFrontEnd )
				)
				( attribute "ROOM" "NIC_SPRV"
					( Origin gFrontEnd )
				)
				( attribute "ROT" "0"
					( Origin gFrontEnd )
				)
				( attribute "SEC" "1"
					( Origin gFrontEnd )
				)
				( attribute "SEC_TYPE" "0402V"
					( Origin gFrontEnd )
				)
				( attribute "TOLERANCE" "10%"
					( Origin gFrontEnd )
				)
				( attribute "VALUE" "0.1UF"
					( Origin gFrontEnd )
				)
				( attribute "VER" "1"
					( Origin gFrontEnd )
				)
				( attribute "VOLTAGE" "16V"
					( Units "uVoltage" "V" 1.000000)
					( Origin gFrontEnd )
				)
				( attribute "XY" "(-6250,1250)"
					( Origin gFrontEnd )
				)
				( attribute "CHIPS_PART_NAME" "CAP_A"
					( Origin gPackager )
				)
				( attribute "CDS_PART_NAME" "CAP_A_0402V-0.1UF,16V,10%,X7R,A"
					( Origin gPackager )
				)
				( objectStatus "C9G6" )
				( pin "a"
					( attribute "PN" "1"
						( Origin gPackager )
					)
					( objectStatus "C9G6.1" )
				)
				( pin "b"
					( attribute "PN" "2"
						( Origin gPackager )
					)
					( objectStatus "C9G6.2" )
				)
			)
			( gate "@baseboard_fab2_lib.baseboard_fab2(sch_1):page141_i48"
				( attribute "BOM_COST" "NT_GBE_BASE"
					( Origin gFrontEnd )
				)
				( attribute "CDS_LIB" "mstr_discrete"
					( Origin gPackager )
				)
				( attribute "CDS_LOCATION" "C9G5"
					( Origin gPackager )
				)
				( attribute "CDS_SEC" "1"
					( Origin gPackager )
				)
				( attribute "LOCATION" "C9G5"
					( Origin gFrontEnd )
				)
				( attribute "MATERIAL" "X7S"
					( Origin gFrontEnd )
				)
				( attribute "PACK_TYPE" "0402"
					( Origin gFrontEnd )
				)
				( attribute "PART_NUMBER" "G71842-007"
					( Origin gFrontEnd )
				)
				( attribute "PHYS_PAGE" "141"
					( Origin gFrontEnd )
				)
				( attribute "ROOM" "NIC_SPRV"
					( Origin gFrontEnd )
				)
				( attribute "ROT" "0"
					( Origin gFrontEnd )
				)
				( attribute "SEC" "1"
					( Origin gFrontEnd )
				)
				( attribute "SEC_TYPE" "0402"
					( Origin gFrontEnd )
				)
				( attribute "TOLERANCE" "10%"
					( Origin gFrontEnd )
				)
				( attribute "VALUE" "1.0UF"
					( Origin gFrontEnd )
				)
				( attribute "VER" "1"
					( Origin gFrontEnd )
				)
				( attribute "VOLTAGE" "16V"
					( Units "uVoltage" "V" 1.000000)
					( Origin gFrontEnd )
				)
				( attribute "XY" "(-6600,1250)"
					( Origin gFrontEnd )
				)
				( attribute "CHIPS_PART_NAME" "CAP"
					( Origin gPackager )
				)
				( attribute "CDS_PART_NAME" "CAP_0402-1.0UF,16V,10%,X7S,G71A"
					( Origin gPackager )
				)
				( objectStatus "C9G5" )
				( pin "a"
					( attribute "PN" "1"
						( Origin gPackager )
					)
					( objectStatus "C9G5.1" )
				)
				( pin "b"
					( attribute "PN" "2"
						( Origin gPackager )
					)
					( objectStatus "C9G5.2" )
				)
			)
			( gate "@baseboard_fab2_lib.baseboard_fab2(sch_1):page141_i54"
				( attribute "BOM_COST" "NT_GBE_BASE"
					( Origin gFrontEnd )
				)
				( attribute "CDS_LIB" "mstr_discrete"
					( Origin gPackager )
				)
				( attribute "CDS_LOCATION" "R9G1"
					( Origin gPackager )
				)
				( attribute "CDS_SEC" "1"
					( Origin gPackager )
				)
				( attribute "LOCATION" "R9G1"
					( Origin gFrontEnd )
				)
				( attribute "MATERIAL" "CHIP"
					( Origin gFrontEnd )
				)
				( attribute "PACK_TYPE" "0402"
					( Origin gFrontEnd )
				)
				( attribute "PART_NUMBER" "G21796-009"
					( Origin gFrontEnd )
				)
				( attribute "PHYS_PAGE" "141"
					( Origin gFrontEnd )
				)
				( attribute "ROOM" "NIC_SPRV"
					( Origin gFrontEnd )
				)
				( attribute "ROT" "0"
					( Origin gFrontEnd )
				)
				( attribute "SEC" "1"
					( Origin gFrontEnd )
				)
				( attribute "SEC_TYPE" "0402"
					( Origin gFrontEnd )
				)
				( attribute "TOLERANCE" "1%"
					( Origin gFrontEnd )
				)
				( attribute "VALUE" "150.0"
					( Origin gFrontEnd )
				)
				( attribute "VER" "1"
					( Origin gFrontEnd )
				)
				( attribute "WATTAGE" "1/16W"
					( Origin gFrontEnd )
				)
				( attribute "XY" "(-4550,2150)"
					( Origin gFrontEnd )
				)
				( attribute "CHIPS_PART_NAME" "RES"
					( Origin gPackager )
				)
				( attribute "CDS_PART_NAME" "RES_0402-150.0,1%,1/16W,CHIP,GA"
					( Origin gPackager )
				)
				( objectStatus "R9G1" )
				( pin "a"
					( attribute "PN" "1"
						( Origin gPackager )
					)
					( objectStatus "R9G1.1" )
				)
				( pin "b"
					( attribute "PN" "2"
						( Origin gPackager )
					)
					( objectStatus "R9G1.2" )
				)
			)
			( gate "@baseboard_fab2_lib.baseboard_fab2(sch_1):page141_i56"
				( attribute "BOM_COST" "NT_GBE_BASE"
					( Origin gFrontEnd )
				)
				( attribute "CDS_LIB" "mstr_discrete"
					( Origin gPackager )
				)
				( attribute "CDS_LOCATION" "R9G4"
					( Origin gPackager )
				)
				( attribute "CDS_SEC" "1"
					( Origin gPackager )
				)
				( attribute "LOCATION" "R9G4"
					( Origin gFrontEnd )
				)
				( attribute "MATERIAL" "CHIP"
					( Origin gFrontEnd )
				)
				( attribute "PACK_TYPE" "0402"
					( Origin gFrontEnd )
				)
				( attribute "PART_NUMBER" "G21497-005"
					( Origin gFrontEnd )
				)
				( attribute "PHYS_PAGE" "141"
					( Origin gFrontEnd )
				)
				( attribute "ROOM" "NIC_SPRV"
					( Origin gFrontEnd )
				)
				( attribute "ROT" "0"
					( Origin gFrontEnd )
				)
				( attribute "SEC" "1"
					( Origin gFrontEnd )
				)
				( attribute "SEC_TYPE" "0402"
					( Origin gFrontEnd )
				)
				( attribute "TOLERANCE" "5%"
					( Origin gFrontEnd )
				)
				( attribute "VALUE" "0.0"
					( Origin gFrontEnd )
				)
				( attribute "VER" "1"
					( Origin gFrontEnd )
				)
				( attribute "WATTAGE" "1/16W"
					( Origin gFrontEnd )
				)
				( attribute "XY" "(-1925,1175)"
					( Origin gFrontEnd )
				)
				( attribute "CHIPS_PART_NAME" "RES"
					( Origin gPackager )
				)
				( attribute "CDS_PART_NAME" "RES_0402-0.0,5%,1/16W,CHIP,G21A"
					( Origin gPackager )
				)
				( objectStatus "R9G4" )
				( pin "a"
					( attribute "PN" "1"
						( Origin gPackager )
					)
					( objectStatus "R9G4.1" )
				)
				( pin "b"
					( attribute "PN" "2"
						( Origin gPackager )
					)
					( objectStatus "R9G4.2" )
				)
			)
			( gate "@baseboard_fab2_lib.baseboard_fab2(sch_1):page141_i58"
				( attribute "BOM_COST" "NT_GBE_BASE"
					( Origin gFrontEnd )
				)
				( attribute "CDS_LIB" "mstr_discrete"
					( Origin gPackager )
				)
				( attribute "CDS_LOCATION" "C9G1"
					( Origin gPackager )
				)
				( attribute "CDS_SEC" "1"
					( Origin gPackager )
				)
				( attribute "LOCATION" "C9G1"
					( Origin gFrontEnd )
				)
				( attribute "MATERIAL" "X7R"
					( Origin gFrontEnd )
				)
				( attribute "PACK_TYPE" "0402LF"
					( Origin gFrontEnd )
				)
				( attribute "PART_NUMBER" "A36096-049"
					( Origin gFrontEnd )
				)
				( attribute "PHYS_PAGE" "141"
					( Origin gFrontEnd )
				)
				( attribute "ROOM" "NIC_SPRV"
					( Origin gFrontEnd )
				)
				( attribute "ROT" "0"
					( Origin gFrontEnd )
				)
				( attribute "SEC" "1"
					( Origin gFrontEnd )
				)
				( attribute "SEC_TYPE" "0402LF"
					( Origin gFrontEnd )
				)
				( attribute "TOLERANCE" "10%"
					( Origin gFrontEnd )
				)
				( attribute "VALUE" "470PF"
					( Origin gFrontEnd )
				)
				( attribute "VER" "1"
					( Origin gFrontEnd )
				)
				( attribute "VOLTAGE" "50V"
					( Units "uVoltage" "V" 1.000000)
					( Origin gFrontEnd )
				)
				( attribute "XY" "(-2050,2050)"
					( Origin gFrontEnd )
				)
				( attribute "CHIPS_PART_NAME" "CAP"
					( Origin gPackager )
				)
				( attribute "CDS_PART_NAME" "CAP_0402LF-470PF,50V,10%,X7R,AA"
					( Origin gPackager )
				)
				( objectStatus "C9G1" )
				( pin "a"
					( attribute "PN" "1"
						( Origin gPackager )
					)
					( objectStatus "C9G1.1" )
				)
				( pin "b"
					( attribute "PN" "2"
						( Origin gPackager )
					)
					( objectStatus "C9G1.2" )
				)
			)
			( gate "@baseboard_fab2_lib.baseboard_fab2(sch_1):page141_i59"
				( attribute "BOM_COST" "NT_GBE_BASE"
					( Origin gFrontEnd )
				)
				( attribute "CDS_LIB" "mstr_discrete"
					( Origin gPackager )
				)
				( attribute "CDS_LOCATION" "C9G3"
					( Origin gPackager )
				)
				( attribute "CDS_SEC" "1"
					( Origin gPackager )
				)
				( attribute "LOCATION" "C9G3"
					( Origin gFrontEnd )
				)
				( attribute "MATERIAL" "X7R"
					( Origin gFrontEnd )
				)
				( attribute "PACK_TYPE" "0402LF"
					( Origin gFrontEnd )
				)
				( attribute "PART_NUMBER" "A36096-049"
					( Origin gFrontEnd )
				)
				( attribute "PHYS_PAGE" "141"
					( Origin gFrontEnd )
				)
				( attribute "ROOM" "NIC_SPRV"
					( Origin gFrontEnd )
				)
				( attribute "ROT" "0"
					( Origin gFrontEnd )
				)
				( attribute "SEC" "1"
					( Origin gFrontEnd )
				)
				( attribute "SEC_TYPE" "0402LF"
					( Origin gFrontEnd )
				)
				( attribute "TOLERANCE" "10%"
					( Origin gFrontEnd )
				)
				( attribute "VALUE" "470PF"
					( Origin gFrontEnd )
				)
				( attribute "VER" "1"
					( Origin gFrontEnd )
				)
				( attribute "VOLTAGE" "50V"
					( Units "uVoltage" "V" 1.000000)
					( Origin gFrontEnd )
				)
				( attribute "XY" "(-1750,2050)"
					( Origin gFrontEnd )
				)
				( attribute "CHIPS_PART_NAME" "CAP"
					( Origin gPackager )
				)
				( attribute "CDS_PART_NAME" "CAP_0402LF-470PF,50V,10%,X7R,AA"
					( Origin gPackager )
				)
				( objectStatus "C9G3" )
				( pin "a"
					( attribute "PN" "1"
						( Origin gPackager )
					)
					( objectStatus "C9G3.1" )
				)
				( pin "b"
					( attribute "PN" "2"
						( Origin gPackager )
					)
					( objectStatus "C9G3.2" )
				)
			)
			( gate "@baseboard_fab2_lib.baseboard_fab2(sch_1):page141_i60"
				( attribute "BOM_COST" "NT_GBE_BASE"
					( Origin gFrontEnd )
				)
				( attribute "CDS_LIB" "mstr_discrete"
					( Origin gPackager )
				)
				( attribute "CDS_LOCATION" "C9F22"
					( Origin gPackager )
				)
				( attribute "CDS_SEC" "1"
					( Origin gPackager )
				)
				( attribute "LOCATION" "C9F22"
					( Origin gFrontEnd )
				)
				( attribute "MATERIAL" "X7R"
					( Origin gFrontEnd )
				)
				( attribute "PACK_TYPE" "0402LF"
					( Origin gFrontEnd )
				)
				( attribute "PART_NUMBER" "A36096-049"
					( Origin gFrontEnd )
				)
				( attribute "PHYS_PAGE" "141"
					( Origin gFrontEnd )
				)
				( attribute "ROOM" "NIC_SPRV"
					( Origin gFrontEnd )
				)
				( attribute "ROT" "0"
					( Origin gFrontEnd )
				)
				( attribute "SEC" "1"
					( Origin gFrontEnd )
				)
				( attribute "SEC_TYPE" "0402LF"
					( Origin gFrontEnd )
				)
				( attribute "TOLERANCE" "10%"
					( Origin gFrontEnd )
				)
				( attribute "VALUE" "470PF"
					( Origin gFrontEnd )
				)
				( attribute "VER" "1"
					( Origin gFrontEnd )
				)
				( attribute "VOLTAGE" "50V"
					( Units "uVoltage" "V" 1.000000)
					( Origin gFrontEnd )
				)
				( attribute "XY" "(-4800,1950)"
					( Origin gFrontEnd )
				)
				( attribute "CHIPS_PART_NAME" "CAP"
					( Origin gPackager )
				)
				( attribute "CDS_PART_NAME" "CAP_0402LF-470PF,50V,10%,X7R,AA"
					( Origin gPackager )
				)
				( objectStatus "C9F22" )
				( pin "a"
					( attribute "PN" "1"
						( Origin gPackager )
					)
					( objectStatus "C9F22.1" )
				)
				( pin "b"
					( attribute "PN" "2"
						( Origin gPackager )
					)
					( objectStatus "C9F22.2" )
				)
			)
			( gate "@baseboard_fab2_lib.baseboard_fab2(sch_1):page141_i75"
				( attribute "BOM_COST" "NT_GBE_BASE"
					( Origin gFrontEnd )
				)
				( attribute "CDS_LIB" "mstr_discrete"
					( Origin gPackager )
				)
				( attribute "CDS_LOCATION" "R9G9"
					( Origin gPackager )
				)
				( attribute "CDS_SEC" "1"
					( Origin gPackager )
				)
				( attribute "LOCATION" "R9G9"
					( Origin gFrontEnd )
				)
				( attribute "MATERIAL" "CHIP"
					( Origin gFrontEnd )
				)
				( attribute "PACK_TYPE" "0402"
					( Origin gFrontEnd )
				)
				( attribute "PART_NUMBER" "G21497-005"
					( Origin gFrontEnd )
				)
				( attribute "PHYS_PAGE" "141"
					( Origin gFrontEnd )
				)
				( attribute "ROOM" "NIC_SPRV"
					( Origin gFrontEnd )
				)
				( attribute "ROT" "0"
					( Origin gFrontEnd )
				)
				( attribute "SEC" "1"
					( Origin gPackager )
				)
				( attribute "TOLERANCE" "5%"
					( Origin gFrontEnd )
				)
				( attribute "VALUE" "0.0"
					( Origin gFrontEnd )
				)
				( attribute "VER" "1"
					( Origin gFrontEnd )
				)
				( attribute "WATTAGE" "1/16W"
					( Origin gFrontEnd )
				)
				( attribute "XY" "(-3550,3775)"
					( Origin gFrontEnd )
				)
				( attribute "CHIPS_PART_NAME" "RES"
					( Origin gPackager )
				)
				( attribute "CDS_PART_NAME" "RES_0402-0.0,5%,1/16W,CHIP,G21A"
					( Origin gPackager )
				)
				( objectStatus "R9G9" )
				( pin "a"
					( attribute "PN" "1"
						( Origin gPackager )
					)
					( objectStatus "R9G9.1" )
				)
				( pin "b"
					( attribute "PN" "2"
						( Origin gPackager )
					)
					( objectStatus "R9G9.2" )
				)
			)
			( gate "@baseboard_fab2_lib.baseboard_fab2(sch_1):page141_i76"
				( attribute "BOM_COST" "NT_GBE_BASE"
					( Origin gFrontEnd )
				)
				( attribute "CDS_LIB" "mstr_discrete"
					( Origin gPackager )
				)
				( attribute "CDS_LOCATION" "R9G11"
					( Origin gPackager )
				)
				( attribute "CDS_SEC" "1"
					( Origin gPackager )
				)
				( attribute "LOCATION" "R9G11"
					( Origin gFrontEnd )
				)
				( attribute "MATERIAL" "CHIP"
					( Origin gFrontEnd )
				)
				( attribute "PACK_TYPE" "0402"
					( Origin gFrontEnd )
				)
				( attribute "PART_NUMBER" "G21497-005"
					( Origin gFrontEnd )
				)
				( attribute "PHYS_PAGE" "141"
					( Origin gFrontEnd )
				)
				( attribute "ROOM" "NIC_SPRV"
					( Origin gFrontEnd )
				)
				( attribute "ROT" "0"
					( Origin gFrontEnd )
				)
				( attribute "SEC" "1"
					( Origin gPackager )
				)
				( attribute "TOLERANCE" "5%"
					( Origin gFrontEnd )
				)
				( attribute "VALUE" "0.0"
					( Origin gFrontEnd )
				)
				( attribute "VER" "1"
					( Origin gFrontEnd )
				)
				( attribute "WATTAGE" "1/16W"
					( Origin gFrontEnd )
				)
				( attribute "XY" "(-3550,3725)"
					( Origin gFrontEnd )
				)
				( attribute "CHIPS_PART_NAME" "RES"
					( Origin gPackager )
				)
				( attribute "CDS_PART_NAME" "RES_0402-0.0,5%,1/16W,CHIP,G21A"
					( Origin gPackager )
				)
				( objectStatus "R9G11" )
				( pin "a"
					( attribute "PN" "1"
						( Origin gPackager )
					)
					( objectStatus "R9G11.1" )
				)
				( pin "b"
					( attribute "PN" "2"
						( Origin gPackager )
					)
					( objectStatus "R9G11.2" )
				)
			)
			( gate "@baseboard_fab2_lib.baseboard_fab2(sch_1):page141_i77"
				( attribute "BOM_COST" "NT_GBE_BASE"
					( Origin gFrontEnd )
				)
				( attribute "CDS_LIB" "mstr_discrete"
					( Origin gPackager )
				)
				( attribute "CDS_LOCATION" "R9G18"
					( Origin gPackager )
				)
				( attribute "CDS_SEC" "1"
					( Origin gPackager )
				)
				( attribute "LOCATION" "R9G18"
					( Origin gFrontEnd )
				)
				( attribute "MATERIAL" "CHIP"
					( Origin gFrontEnd )
				)
				( attribute "PACK_TYPE" "0402"
					( Origin gFrontEnd )
				)
				( attribute "PART_NUMBER" "G21497-005"
					( Origin gFrontEnd )
				)
				( attribute "PHYS_PAGE" "141"
					( Origin gFrontEnd )
				)
				( attribute "ROOM" "NIC_SPRV"
					( Origin gFrontEnd )
				)
				( attribute "ROT" "0"
					( Origin gFrontEnd )
				)
				( attribute "SEC" "1"
					( Origin gPackager )
				)
				( attribute "TOLERANCE" "5%"
					( Origin gFrontEnd )
				)
				( attribute "VALUE" "0.0"
					( Origin gFrontEnd )
				)
				( attribute "VER" "1"
					( Origin gFrontEnd )
				)
				( attribute "WATTAGE" "1/16W"
					( Origin gFrontEnd )
				)
				( attribute "XY" "(-3550,3675)"
					( Origin gFrontEnd )
				)
				( attribute "CHIPS_PART_NAME" "RES"
					( Origin gPackager )
				)
				( attribute "CDS_PART_NAME" "RES_0402-0.0,5%,1/16W,CHIP,G21A"
					( Origin gPackager )
				)
				( objectStatus "R9G18" )
				( pin "a"
					( attribute "PN" "1"
						( Origin gPackager )
					)
					( objectStatus "R9G18.1" )
				)
				( pin "b"
					( attribute "PN" "2"
						( Origin gPackager )
					)
					( objectStatus "R9G18.2" )
				)
			)
			( gate "@baseboard_fab2_lib.baseboard_fab2(sch_1):page141_i78"
				( attribute "BOM_COST" "NT_GBE_BASE"
					( Origin gFrontEnd )
				)
				( attribute "CDS_LIB" "mstr_discrete"
					( Origin gPackager )
				)
				( attribute "CDS_LOCATION" "R9G17"
					( Origin gPackager )
				)
				( attribute "CDS_SEC" "1"
					( Origin gPackager )
				)
				( attribute "LOCATION" "R9G17"
					( Origin gFrontEnd )
				)
				( attribute "MATERIAL" "CHIP"
					( Origin gFrontEnd )
				)
				( attribute "PACK_TYPE" "0402"
					( Origin gFrontEnd )
				)
				( attribute "PART_NUMBER" "G21497-005"
					( Origin gFrontEnd )
				)
				( attribute "PHYS_PAGE" "141"
					( Origin gFrontEnd )
				)
				( attribute "ROOM" "NIC_SPRV"
					( Origin gFrontEnd )
				)
				( attribute "ROT" "0"
					( Origin gFrontEnd )
				)
				( attribute "SEC" "1"
					( Origin gPackager )
				)
				( attribute "TOLERANCE" "5%"
					( Origin gFrontEnd )
				)
				( attribute "VALUE" "0.0"
					( Origin gFrontEnd )
				)
				( attribute "VER" "1"
					( Origin gFrontEnd )
				)
				( attribute "WATTAGE" "1/16W"
					( Origin gFrontEnd )
				)
				( attribute "XY" "(-3550,3625)"
					( Origin gFrontEnd )
				)
				( attribute "CHIPS_PART_NAME" "RES"
					( Origin gPackager )
				)
				( attribute "CDS_PART_NAME" "RES_0402-0.0,5%,1/16W,CHIP,G21A"
					( Origin gPackager )
				)
				( objectStatus "R9G17" )
				( pin "a"
					( attribute "PN" "1"
						( Origin gPackager )
					)
					( objectStatus "R9G17.1" )
				)
				( pin "b"
					( attribute "PN" "2"
						( Origin gPackager )
					)
					( objectStatus "R9G17.2" )
				)
			)
			( gate "@baseboard_fab2_lib.baseboard_fab2(sch_1):page141_i79"
				( attribute "BOM_COST" "NT_GBE_BASE"
					( Origin gFrontEnd )
				)
				( attribute "CDS_LIB" "mstr_discrete"
					( Origin gPackager )
				)
				( attribute "CDS_LOCATION" "R9G19"
					( Origin gPackager )
				)
				( attribute "CDS_SEC" "1"
					( Origin gPackager )
				)
				( attribute "LOCATION" "R9G19"
					( Origin gFrontEnd )
				)
				( attribute "MATERIAL" "CHIP"
					( Origin gFrontEnd )
				)
				( attribute "PACK_TYPE" "0402"
					( Origin gFrontEnd )
				)
				( attribute "PART_NUMBER" "G21497-005"
					( Origin gFrontEnd )
				)
				( attribute "PHYS_PAGE" "141"
					( Origin gFrontEnd )
				)
				( attribute "ROOM" "NIC_SPRV"
					( Origin gFrontEnd )
				)
				( attribute "ROT" "0"
					( Origin gFrontEnd )
				)
				( attribute "SEC" "1"
					( Origin gPackager )
				)
				( attribute "TOLERANCE" "5%"
					( Origin gFrontEnd )
				)
				( attribute "VALUE" "0.0"
					( Origin gFrontEnd )
				)
				( attribute "VER" "1"
					( Origin gFrontEnd )
				)
				( attribute "WATTAGE" "1/16W"
					( Origin gFrontEnd )
				)
				( attribute "XY" "(-3550,3575)"
					( Origin gFrontEnd )
				)
				( attribute "CHIPS_PART_NAME" "RES"
					( Origin gPackager )
				)
				( attribute "CDS_PART_NAME" "RES_0402-0.0,5%,1/16W,CHIP,G21A"
					( Origin gPackager )
				)
				( objectStatus "R9G19" )
				( pin "a"
					( attribute "PN" "1"
						( Origin gPackager )
					)
					( objectStatus "R9G19.1" )
				)
				( pin "b"
					( attribute "PN" "2"
						( Origin gPackager )
					)
					( objectStatus "R9G19.2" )
				)
			)
			( gate "@baseboard_fab2_lib.baseboard_fab2(sch_1):page141_i80"
				( attribute "BOM_COST" "NT_GBE_BASE"
					( Origin gFrontEnd )
				)
				( attribute "CDS_LIB" "mstr_discrete"
					( Origin gPackager )
				)
				( attribute "CDS_LOCATION" "R9G20"
					( Origin gPackager )
				)
				( attribute "CDS_SEC" "1"
					( Origin gPackager )
				)
				( attribute "LOCATION" "R9G20"
					( Origin gFrontEnd )
				)
				( attribute "MATERIAL" "CHIP"
					( Origin gFrontEnd )
				)
				( attribute "PACK_TYPE" "0402"
					( Origin gFrontEnd )
				)
				( attribute "PART_NUMBER" "G21497-005"
					( Origin gFrontEnd )
				)
				( attribute "PHYS_PAGE" "141"
					( Origin gFrontEnd )
				)
				( attribute "ROOM" "NIC_SPRV"
					( Origin gFrontEnd )
				)
				( attribute "ROT" "0"
					( Origin gFrontEnd )
				)
				( attribute "SEC" "1"
					( Origin gPackager )
				)
				( attribute "TOLERANCE" "5%"
					( Origin gFrontEnd )
				)
				( attribute "VALUE" "0.0"
					( Origin gFrontEnd )
				)
				( attribute "VER" "1"
					( Origin gFrontEnd )
				)
				( attribute "WATTAGE" "1/16W"
					( Origin gFrontEnd )
				)
				( attribute "XY" "(-3550,3525)"
					( Origin gFrontEnd )
				)
				( attribute "CHIPS_PART_NAME" "RES"
					( Origin gPackager )
				)
				( attribute "CDS_PART_NAME" "RES_0402-0.0,5%,1/16W,CHIP,G21A"
					( Origin gPackager )
				)
				( objectStatus "R9G20" )
				( pin "a"
					( attribute "PN" "1"
						( Origin gPackager )
					)
					( objectStatus "R9G20.1" )
				)
				( pin "b"
					( attribute "PN" "2"
						( Origin gPackager )
					)
					( objectStatus "R9G20.2" )
				)
			)
			( gate "@baseboard_fab2_lib.baseboard_fab2(sch_1):page141_i81"
				( attribute "BOM_COST" "NT_GBE_BASE"
					( Origin gFrontEnd )
				)
				( attribute "CDS_LIB" "mstr_discrete"
					( Origin gPackager )
				)
				( attribute "CDS_LOCATION" "R9G24"
					( Origin gPackager )
				)
				( attribute "CDS_SEC" "1"
					( Origin gPackager )
				)
				( attribute "LOCATION" "R9G24"
					( Origin gFrontEnd )
				)
				( attribute "MATERIAL" "CHIP"
					( Origin gFrontEnd )
				)
				( attribute "PACK_TYPE" "0402"
					( Origin gFrontEnd )
				)
				( attribute "PART_NUMBER" "G21497-005"
					( Origin gFrontEnd )
				)
				( attribute "PHYS_PAGE" "141"
					( Origin gFrontEnd )
				)
				( attribute "ROOM" "NIC_SPRV"
					( Origin gFrontEnd )
				)
				( attribute "ROT" "0"
					( Origin gFrontEnd )
				)
				( attribute "SEC" "1"
					( Origin gPackager )
				)
				( attribute "TOLERANCE" "5%"
					( Origin gFrontEnd )
				)
				( attribute "VALUE" "0.0"
					( Origin gFrontEnd )
				)
				( attribute "VER" "1"
					( Origin gFrontEnd )
				)
				( attribute "WATTAGE" "1/16W"
					( Origin gFrontEnd )
				)
				( attribute "XY" "(-3550,3475)"
					( Origin gFrontEnd )
				)
				( attribute "CHIPS_PART_NAME" "RES"
					( Origin gPackager )
				)
				( attribute "CDS_PART_NAME" "RES_0402-0.0,5%,1/16W,CHIP,G21A"
					( Origin gPackager )
				)
				( objectStatus "R9G24" )
				( pin "a"
					( attribute "PN" "1"
						( Origin gPackager )
					)
					( objectStatus "R9G24.1" )
				)
				( pin "b"
					( attribute "PN" "2"
						( Origin gPackager )
					)
					( objectStatus "R9G24.2" )
				)
			)
			( gate "@baseboard_fab2_lib.baseboard_fab2(sch_1):page141_i82"
				( attribute "BOM_COST" "NT_GBE_BASE"
					( Origin gFrontEnd )
				)
				( attribute "CDS_LIB" "mstr_discrete"
					( Origin gPackager )
				)
				( attribute "CDS_LOCATION" "R9G22"
					( Origin gPackager )
				)
				( attribute "CDS_SEC" "1"
					( Origin gPackager )
				)
				( attribute "LOCATION" "R9G22"
					( Origin gFrontEnd )
				)
				( attribute "MATERIAL" "CHIP"
					( Origin gFrontEnd )
				)
				( attribute "PACK_TYPE" "0402"
					( Origin gFrontEnd )
				)
				( attribute "PART_NUMBER" "G21497-005"
					( Origin gFrontEnd )
				)
				( attribute "PHYS_PAGE" "141"
					( Origin gFrontEnd )
				)
				( attribute "ROOM" "NIC_SPRV"
					( Origin gFrontEnd )
				)
				( attribute "ROT" "0"
					( Origin gFrontEnd )
				)
				( attribute "SEC" "1"
					( Origin gPackager )
				)
				( attribute "TOLERANCE" "5%"
					( Origin gFrontEnd )
				)
				( attribute "VALUE" "0.0"
					( Origin gFrontEnd )
				)
				( attribute "VER" "1"
					( Origin gFrontEnd )
				)
				( attribute "WATTAGE" "1/16W"
					( Origin gFrontEnd )
				)
				( attribute "XY" "(-3550,3425)"
					( Origin gFrontEnd )
				)
				( attribute "CHIPS_PART_NAME" "RES"
					( Origin gPackager )
				)
				( attribute "CDS_PART_NAME" "RES_0402-0.0,5%,1/16W,CHIP,G21A"
					( Origin gPackager )
				)
				( objectStatus "R9G22" )
				( pin "a"
					( attribute "PN" "1"
						( Origin gPackager )
					)
					( objectStatus "R9G22.1" )
				)
				( pin "b"
					( attribute "PN" "2"
						( Origin gPackager )
					)
					( objectStatus "R9G22.2" )
				)
			)
			( gate "@baseboard_fab2_lib.baseboard_fab2(sch_1):page141_i99"
				( attribute "BOM_COST" "NT_GBE_BASE"
					( Origin gFrontEnd )
				)
				( attribute "CDS_LIB" "mstr_discrete"
					( Origin gPackager )
				)
				( attribute "CDS_LOCATION" "C9G9"
					( Origin gPackager )
				)
				( attribute "CDS_SEC" "1"
					( Origin gPackager )
				)
				( attribute "LOCATION" "C9G9"
					( Origin gFrontEnd )
				)
				( attribute "MATERIAL" "EMPTY"
					( Origin gFrontEnd )
				)
				( attribute "NO_XNET_CONNECTION" "1"
					( Origin gFrontEnd )
				)
				( attribute "PACK_TYPE" "0402LF"
					( Origin gFrontEnd )
				)
				( attribute "PART_NUMBER" "A36096-066"
					( Origin gFrontEnd )
				)
				( attribute "PHYS_PAGE" "141"
					( Origin gFrontEnd )
				)
				( attribute "ROOM" "NIC_SPRV"
					( Origin gFrontEnd )
				)
				( attribute "ROT" "0"
					( Origin gFrontEnd )
				)
				( attribute "SEC" "1"
					( Origin gPackager )
				)
				( attribute "TOLERANCE" "10%"
					( Origin gFrontEnd )
				)
				( attribute "VALUE" "4700PF"
					( Origin gFrontEnd )
				)
				( attribute "VER" "2"
					( Origin gFrontEnd )
				)
				( attribute "VOLTAGE" "50V"
					( Units "uVoltage" "V" 1.000000)
					( Origin gFrontEnd )
				)
				( attribute "XY" "(-2875,4425)"
					( Origin gFrontEnd )
				)
				( attribute "CHIPS_PART_NAME" "CAP"
					( Origin gPackager )
				)
				( attribute "CDS_PART_NAME" "CAP_0402LF-4700PF,50V,10%,EMPTA"
					( Origin gPackager )
				)
				( objectStatus "C9G9" )
				( pin "a"
					( attribute "PN" "1"
						( Origin gPackager )
					)
					( objectStatus "C9G9.1" )
				)
				( pin "b"
					( attribute "PN" "2"
						( Origin gPackager )
					)
					( objectStatus "C9G9.2" )
				)
			)
			( gate "@baseboard_fab2_lib.baseboard_fab2(sch_1):page141_i100"
				( attribute "BOM_COST" "NT_GBE_BASE"
					( Origin gFrontEnd )
				)
				( attribute "CDS_LIB" "mstr_discrete"
					( Origin gPackager )
				)
				( attribute "CDS_LOCATION" "C9G12"
					( Origin gPackager )
				)
				( attribute "CDS_SEC" "1"
					( Origin gPackager )
				)
				( attribute "LOCATION" "C9G12"
					( Origin gFrontEnd )
				)
				( attribute "MATERIAL" "EMPTY"
					( Origin gFrontEnd )
				)
				( attribute "NO_XNET_CONNECTION" "1"
					( Origin gFrontEnd )
				)
				( attribute "PACK_TYPE" "0402LF"
					( Origin gFrontEnd )
				)
				( attribute "PART_NUMBER" "A36096-066"
					( Origin gFrontEnd )
				)
				( attribute "PHYS_PAGE" "141"
					( Origin gFrontEnd )
				)
				( attribute "ROOM" "NIC_SPRV"
					( Origin gFrontEnd )
				)
				( attribute "ROT" "0"
					( Origin gFrontEnd )
				)
				( attribute "SEC" "1"
					( Origin gPackager )
				)
				( attribute "TOLERANCE" "10%"
					( Origin gFrontEnd )
				)
				( attribute "VALUE" "4700PF"
					( Origin gFrontEnd )
				)
				( attribute "VER" "2"
					( Origin gFrontEnd )
				)
				( attribute "VOLTAGE" "50V"
					( Units "uVoltage" "V" 1.000000)
					( Origin gFrontEnd )
				)
				( attribute "XY" "(-3150,4375)"
					( Origin gFrontEnd )
				)
				( attribute "CHIPS_PART_NAME" "CAP"
					( Origin gPackager )
				)
				( attribute "CDS_PART_NAME" "CAP_0402LF-4700PF,50V,10%,EMPTA"
					( Origin gPackager )
				)
				( objectStatus "C9G12" )
				( pin "a"
					( attribute "PN" "1"
						( Origin gPackager )
					)
					( objectStatus "C9G12.1" )
				)
				( pin "b"
					( attribute "PN" "2"
						( Origin gPackager )
					)
					( objectStatus "C9G12.2" )
				)
			)
			( gate "@baseboard_fab2_lib.baseboard_fab2(sch_1):page141_i101"
				( attribute "BOM_COST" "NT_GBE_BASE"
					( Origin gFrontEnd )
				)
				( attribute "CDS_LIB" "mstr_discrete"
					( Origin gPackager )
				)
				( attribute "CDS_LOCATION" "C9G16"
					( Origin gPackager )
				)
				( attribute "CDS_SEC" "1"
					( Origin gPackager )
				)
				( attribute "LOCATION" "C9G16"
					( Origin gFrontEnd )
				)
				( attribute "MATERIAL" "EMPTY"
					( Origin gFrontEnd )
				)
				( attribute "NO_XNET_CONNECTION" "1"
					( Origin gFrontEnd )
				)
				( attribute "PACK_TYPE" "0402LF"
					( Origin gFrontEnd )
				)
				( attribute "PART_NUMBER" "A36096-066"
					( Origin gFrontEnd )
				)
				( attribute "PHYS_PAGE" "141"
					( Origin gFrontEnd )
				)
				( attribute "ROOM" "NIC_SPRV"
					( Origin gFrontEnd )
				)
				( attribute "ROT" "0"
					( Origin gFrontEnd )
				)
				( attribute "SEC" "1"
					( Origin gPackager )
				)
				( attribute "TOLERANCE" "10%"
					( Origin gFrontEnd )
				)
				( attribute "VALUE" "4700PF"
					( Origin gFrontEnd )
				)
				( attribute "VER" "2"
					( Origin gFrontEnd )
				)
				( attribute "VOLTAGE" "50V"
					( Units "uVoltage" "V" 1.000000)
					( Origin gFrontEnd )
				)
				( attribute "XY" "(-2825,4075)"
					( Origin gFrontEnd )
				)
				( attribute "CHIPS_PART_NAME" "CAP"
					( Origin gPackager )
				)
				( attribute "CDS_PART_NAME" "CAP_0402LF-4700PF,50V,10%,EMPTA"
					( Origin gPackager )
				)
				( objectStatus "C9G16" )
				( pin "a"
					( attribute "PN" "1"
						( Origin gPackager )
					)
					( objectStatus "C9G16.1" )
				)
				( pin "b"
					( attribute "PN" "2"
						( Origin gPackager )
					)
					( objectStatus "C9G16.2" )
				)
			)
			( gate "@baseboard_fab2_lib.baseboard_fab2(sch_1):page141_i102"
				( attribute "BOM_COST" "NT_GBE_BASE"
					( Origin gFrontEnd )
				)
				( attribute "CDS_LIB" "mstr_discrete"
					( Origin gPackager )
				)
				( attribute "CDS_LOCATION" "C9G13"
					( Origin gPackager )
				)
				( attribute "CDS_SEC" "1"
					( Origin gPackager )
				)
				( attribute "LOCATION" "C9G13"
					( Origin gFrontEnd )
				)
				( attribute "MATERIAL" "EMPTY"
					( Origin gFrontEnd )
				)
				( attribute "NO_XNET_CONNECTION" "1"
					( Origin gFrontEnd )
				)
				( attribute "PACK_TYPE" "0402LF"
					( Origin gFrontEnd )
				)
				( attribute "PART_NUMBER" "A36096-066"
					( Origin gFrontEnd )
				)
				( attribute "PHYS_PAGE" "141"
					( Origin gFrontEnd )
				)
				( attribute "ROOM" "NIC_SPRV"
					( Origin gFrontEnd )
				)
				( attribute "ROT" "0"
					( Origin gFrontEnd )
				)
				( attribute "SEC" "1"
					( Origin gPackager )
				)
				( attribute "TOLERANCE" "10%"
					( Origin gFrontEnd )
				)
				( attribute "VALUE" "4700PF"
					( Origin gFrontEnd )
				)
				( attribute "VER" "2"
					( Origin gFrontEnd )
				)
				( attribute "VOLTAGE" "50V"
					( Units "uVoltage" "V" 1.000000)
					( Origin gFrontEnd )
				)
				( attribute "XY" "(-3100,4025)"
					( Origin gFrontEnd )
				)
				( attribute "CHIPS_PART_NAME" "CAP"
					( Origin gPackager )
				)
				( attribute "CDS_PART_NAME" "CAP_0402LF-4700PF,50V,10%,EMPTA"
					( Origin gPackager )
				)
				( objectStatus "C9G13" )
				( pin "a"
					( attribute "PN" "1"
						( Origin gPackager )
					)
					( objectStatus "C9G13.1" )
				)
				( pin "b"
					( attribute "PN" "2"
						( Origin gPackager )
					)
					( objectStatus "C9G13.2" )
				)
			)
			( gate "@baseboard_fab2_lib.baseboard_fab2(sch_1):page141_i109"
				( attribute "BOM_COST" "NT_GBE_BASE"
					( Origin gFrontEnd )
				)
				( attribute "CDS_LIB" "mstr_conn"
					( Origin gPackager )
				)
				( attribute "CDS_LMAN_SYM_OUTLINE" "-400,550,400,-550"
					( Origin gPackager )
				)
				( attribute "CDS_LOCATION" "JA9G1"
					( Origin gPackager )
				)
				( attribute "CDS_SEC" "1"
					( Origin gPackager )
				)
				( attribute "LOCATION" "JA9G1"
					( Origin gFrontEnd )
				)
				( attribute "MATERIAL" "CONN"
					( Origin gFrontEnd )
				)
				( attribute "PACK_TYPE" "PIP1"
					( Origin gFrontEnd )
				)
				( attribute "PART_NUMBER" "H71061-002"
					( Origin gFrontEnd )
				)
				( attribute "PHYS_PAGE" "141"
					( Origin gFrontEnd )
				)
				( attribute "ROOM" "NIC_SPRV"
					( Origin gFrontEnd )
				)
				( attribute "ROT" "0"
					( Origin gFrontEnd )
				)
				( attribute "SEC" "1"
					( Origin gPackager )
				)
				( attribute "VER" "1"
					( Origin gFrontEnd )
				)
				( attribute "XY" "(-3575,2500)"
					( Origin gFrontEnd )
				)
				( attribute "CHIPS_PART_NAME" "CONN17_H71061002"
					( Origin gPackager )
				)
				( attribute "CDS_PART_NAME" "CONN17_H71061002_PIP1-CONN,H71A"
					( Origin gPackager )
				)
				( objectStatus "JA9G1" )
				( pin "l1"
					( attribute "PN" "L1"
						( Origin gPackager )
					)
					( objectStatus "JA9G1.L1" )
				)
				( pin "l2"
					( attribute "PN" "L2"
						( Origin gPackager )
					)
					( objectStatus "JA9G1.L2" )
				)
				( pin "l3"
					( attribute "PN" "L3"
						( Origin gPackager )
					)
					( objectStatus "JA9G1.L3" )
				)
				( pin "l4"
					( attribute "PN" "L4"
						( Origin gPackager )
					)
					( objectStatus "JA9G1.L4" )
				)
				( pin "l5"
					( attribute "PN" "L5"
						( Origin gPackager )
					)
					( objectStatus "JA9G1.L5" )
				)
				( pin "mh1"
					( attribute "PN" "MH1"
						( Origin gPackager )
					)
					( objectStatus "JA9G1.MH1" )
				)
				( pin "mh2"
					( attribute "PN" "MH2"
						( Origin gPackager )
					)
					( objectStatus "JA9G1.MH2" )
				)
				( pin "trct1"
					( attribute "PN" "R12"
						( Origin gPackager )
					)
					( objectStatus "JA9G1.R12" )
				)
				( pin "trct2"
					( attribute "PN" "R6"
						( Origin gPackager )
					)
					( objectStatus "JA9G1.R6" )
				)
				( pin "trct3"
					( attribute "PN" "R1"
						( Origin gPackager )
					)
					( objectStatus "JA9G1.R1" )
				)
				( pin "trct4"
					( attribute "PN" "R7"
						( Origin gPackager )
					)
					( objectStatus "JA9G1.R7" )
				)
				( pin "trd1n"
					( attribute "PN" "R10"
						( Origin gPackager )
					)
					( objectStatus "JA9G1.R10" )
				)
				( pin "trd1p"
					( attribute "PN" "R11"
						( Origin gPackager )
					)
					( objectStatus "JA9G1.R11" )
				)
				( pin "trd2n"
					( attribute "PN" "R5"
						( Origin gPackager )
					)
					( objectStatus "JA9G1.R5" )
				)
				( pin "trd2p"
					( attribute "PN" "R4"
						( Origin gPackager )
					)
					( objectStatus "JA9G1.R4" )
				)
				( pin "trd3n"
					( attribute "PN" "R2"
						( Origin gPackager )
					)
					( objectStatus "JA9G1.R2" )
				)
				( pin "trd3p"
					( attribute "PN" "R3"
						( Origin gPackager )
					)
					( objectStatus "JA9G1.R3" )
				)
				( pin "trd4n"
					( attribute "PN" "R9"
						( Origin gPackager )
					)
					( objectStatus "JA9G1.R9" )
				)
				( pin "trd4p"
					( attribute "PN" "R8"
						( Origin gPackager )
					)
					( objectStatus "JA9G1.R8" )
				)
			)
			( gate "@baseboard_fab2_lib.baseboard_fab2(sch_1):page141_i112"
				( attribute "BOM_COST" "NT_GBE_BASE"
					( Origin gFrontEnd )
				)
				( attribute "CDS_LIB" "mstr_discrete"
					( Origin gPackager )
				)
				( attribute "CDS_LOCATION" "R1U51"
					( Origin gPackager )
				)
				( attribute "CDS_SEC" "1"
					( Origin gPackager )
				)
				( attribute "LOCATION" "R1U51"
					( Origin gFrontEnd )
				)
				( attribute "MATERIAL" "CHIP"
					( Origin gFrontEnd )
				)
				( attribute "PACK_TYPE" "0402"
					( Origin gFrontEnd )
				)
				( attribute "PART_NUMBER" "G21497-005"
					( Origin gFrontEnd )
				)
				( attribute "PHYS_PAGE" "141"
					( Origin gFrontEnd )
				)
				( attribute "ROOM" "NIC_SPRV"
					( Origin gFrontEnd )
				)
				( attribute "ROT" "0"
					( Origin gFrontEnd )
				)
				( attribute "SEC" "1"
					( Origin gFrontEnd )
				)
				( attribute "SEC_TYPE" "0402"
					( Origin gFrontEnd )
				)
				( attribute "TOLERANCE" "5%"
					( Origin gFrontEnd )
				)
				( attribute "VALUE" "0.0"
					( Origin gFrontEnd )
				)
				( attribute "VER" "1"
					( Origin gFrontEnd )
				)
				( attribute "WATTAGE" "1/16W"
					( Origin gFrontEnd )
				)
				( attribute "XY" "(-4450,1400)"
					( Origin gFrontEnd )
				)
				( attribute "CHIPS_PART_NAME" "RES"
					( Origin gPackager )
				)
				( attribute "CDS_PART_NAME" "RES_0402-0.0,5%,1/16W,CHIP,G21A"
					( Origin gPackager )
				)
				( objectStatus "R1U51" )
				( pin "a"
					( attribute "PN" "1"
						( Origin gPackager )
					)
					( objectStatus "R1U51.1" )
				)
				( pin "b"
					( attribute "PN" "2"
						( Origin gPackager )
					)
					( objectStatus "R1U51.2" )
				)
			)
			( gate "@baseboard_fab2_lib.baseboard_fab2(sch_1):page141_i114"
				( attribute "BOM_COST" "NT_GBE_BASE"
					( Origin gFrontEnd )
				)
				( attribute "CDS_LIB" "mstr_discrete"
					( Origin gPackager )
				)
				( attribute "CDS_LOCATION" "R1U3"
					( Origin gPackager )
				)
				( attribute "CDS_SEC" "1"
					( Origin gPackager )
				)
				( attribute "LOCATION" "R1U3"
					( Origin gFrontEnd )
				)
				( attribute "MATERIAL" "CHIP"
					( Origin gFrontEnd )
				)
				( attribute "PACK_TYPE" "0402"
					( Origin gFrontEnd )
				)
				( attribute "PART_NUMBER" "G21497-005"
					( Origin gFrontEnd )
				)
				( attribute "PHYS_PAGE" "141"
					( Origin gFrontEnd )
				)
				( attribute "ROOM" "NIC_SPRV"
					( Origin gFrontEnd )
				)
				( attribute "ROT" "0"
					( Origin gFrontEnd )
				)
				( attribute "SEC" "1"
					( Origin gFrontEnd )
				)
				( attribute "SEC_TYPE" "0402"
					( Origin gFrontEnd )
				)
				( attribute "TOLERANCE" "5%"
					( Origin gFrontEnd )
				)
				( attribute "VALUE" "0.0"
					( Origin gFrontEnd )
				)
				( attribute "VER" "1"
					( Origin gFrontEnd )
				)
				( attribute "WATTAGE" "1/16W"
					( Origin gFrontEnd )
				)
				( attribute "XY" "(-4450,1000)"
					( Origin gFrontEnd )
				)
				( attribute "CHIPS_PART_NAME" "RES"
					( Origin gPackager )
				)
				( attribute "CDS_PART_NAME" "RES_0402-0.0,5%,1/16W,CHIP,G21A"
					( Origin gPackager )
				)
				( objectStatus "R1U3" )
				( pin "a"
					( attribute "PN" "1"
						( Origin gPackager )
					)
					( objectStatus "R1U3.1" )
				)
				( pin "b"
					( attribute "PN" "2"
						( Origin gPackager )
					)
					( objectStatus "R1U3.2" )
				)
			)
			( gate "@baseboard_fab2_lib.baseboard_fab2(sch_1):page142_i1"
				( attribute "BOM_COST" "SB"
					( Origin gFrontEnd )
				)
				( attribute "CDS_LIB" "mstr_ttl"
					( Origin gPackager )
				)
				( attribute "CDS_LOCATION" "U8E4"
					( Origin gPackager )
				)
				( attribute "CDS_SEC" "1"
					( Origin gPackager )
				)
				( attribute "LOCATION" "U8E4"
					( Origin gFrontEnd )
				)
				( attribute "MATERIAL" "IC"
					( Origin gFrontEnd )
				)
				( attribute "PACK_TYPE" "SOT"
					( Origin gFrontEnd )
				)
				( attribute "PART_NUMBER" "A79322-001"
					( Origin gFrontEnd )
				)
				( attribute "PHYS_PAGE" "142"
					( Origin gFrontEnd )
				)
				( attribute "ROOM" "PCIE_WAKE_BUFFER"
					( Origin gFrontEnd )
				)
				( attribute "ROT" "6"
					( Origin gFrontEnd )
				)
				( attribute "SEC" "1"
					( Origin gFrontEnd )
				)
				( attribute "SEC_TYPE" "SOT"
					( Origin gFrontEnd )
				)
				( attribute "VALUE" "74HC1G126"
					( Origin gFrontEnd )
				)
				( attribute "VER" "1"
					( Origin gFrontEnd )
				)
				( attribute "XY" "(-3525,2275)"
					( Origin gFrontEnd )
				)
				( attribute "CHIPS_PART_NAME" "TTL1G126_A"
					( Origin gPackager )
				)
				( attribute "CDS_PART_NAME" "TTL1G126_A_SOT-74HC1G126,IC,A7B"
					( Origin gPackager )
				)
				( objectStatus "U8E4" )
				( pin "a"
					( attribute "PN" "2"
						( Origin gPackager )
					)
					( objectStatus "U8E4.2" )
				)
				( pin "oe"
					( attribute "PN" "1"
						( Origin gPackager )
					)
					( objectStatus "U8E4.1" )
				)
				( pin "y"
					( attribute "PN" "4"
						( Origin gPackager )
					)
					( objectStatus "U8E4.4" )
				)
			)
			( gate "@baseboard_fab2_lib.baseboard_fab2(sch_1):page142_i2"
				( attribute "BOM_COST" "SB"
					( Origin gFrontEnd )
				)
				( attribute "CDS_LIB" "mstr_discrete"
					( Origin gPackager )
				)
				( attribute "CDS_LOCATION" "R8E17"
					( Origin gPackager )
				)
				( attribute "CDS_SEC" "1"
					( Origin gPackager )
				)
				( attribute "LOCATION" "R8E17"
					( Origin gFrontEnd )
				)
				( attribute "MATERIAL" "CHIP"
					( Origin gFrontEnd )
				)
				( attribute "PACK_TYPE" "0402"
					( Origin gFrontEnd )
				)
				( attribute "PART_NUMBER" "G21796-074"
					( Origin gFrontEnd )
				)
				( attribute "PHYS_PAGE" "142"
					( Origin gFrontEnd )
				)
				( attribute "ROOM" "PCIE_WAKE_BUFFER"
					( Origin gFrontEnd )
				)
				( attribute "ROT" "0"
					( Origin gFrontEnd )
				)
				( attribute "SEC" "1"
					( Origin gFrontEnd )
				)
				( attribute "SEC_TYPE" "0402"
					( Origin gFrontEnd )
				)
				( attribute "TOLERANCE" "1%"
					( Origin gFrontEnd )
				)
				( attribute "VALUE" "33.2"
					( Origin gFrontEnd )
				)
				( attribute "VER" "1"
					( Origin gFrontEnd )
				)
				( attribute "WATTAGE" "1/16W"
					( Origin gFrontEnd )
				)
				( attribute "XY" "(-2625,2275)"
					( Origin gFrontEnd )
				)
				( attribute "CHIPS_PART_NAME" "RES"
					( Origin gPackager )
				)
				( attribute "CDS_PART_NAME" "RES_0402-33.2,1%,1/16W,CHIP,G2A"
					( Origin gPackager )
				)
				( objectStatus "R8E17" )
				( pin "a"
					( attribute "PN" "1"
						( Origin gPackager )
					)
					( objectStatus "R8E17.1" )
				)
				( pin "b"
					( attribute "PN" "2"
						( Origin gPackager )
					)
					( objectStatus "R8E17.2" )
				)
			)
			( gate "@baseboard_fab2_lib.baseboard_fab2(sch_1):page142_i3"
				( attribute "BOM_COST" "SB"
					( Origin gFrontEnd )
				)
				( attribute "CDS_LIB" "mstr_discrete"
					( Origin gPackager )
				)
				( attribute "CDS_LOCATION" "R8E23"
					( Origin gPackager )
				)
				( attribute "CDS_SEC" "1"
					( Origin gPackager )
				)
				( attribute "LOCATION" "R8E23"
					( Origin gFrontEnd )
				)
				( attribute "MATERIAL" "CHIP"
					( Origin gFrontEnd )
				)
				( attribute "PACK_TYPE" "0402"
					( Origin gFrontEnd )
				)
				( attribute "PART_NUMBER" "G21796-072"
					( Origin gFrontEnd )
				)
				( attribute "PHYS_PAGE" "142"
					( Origin gFrontEnd )
				)
				( attribute "ROOM" "PCIE_WAKE_BUFFER"
					( Origin gFrontEnd )
				)
				( attribute "ROT" "0"
					( Origin gFrontEnd )
				)
				( attribute "SEC" "1"
					( Origin gFrontEnd )
				)
				( attribute "SEC_TYPE" "0402"
					( Origin gFrontEnd )
				)
				( attribute "TOLERANCE" "1%"
					( Origin gFrontEnd )
				)
				( attribute "VALUE" "4.75K"
					( Origin gFrontEnd )
				)
				( attribute "VER" "1"
					( Origin gFrontEnd )
				)
				( attribute "WATTAGE" "1/16W"
					( Origin gFrontEnd )
				)
				( attribute "XY" "(-3050,2700)"
					( Origin gFrontEnd )
				)
				( attribute "CHIPS_PART_NAME" "RES"
					( Origin gPackager )
				)
				( attribute "CDS_PART_NAME" "RES_0402-4.75K,1%,1/16W,CHIP,GA"
					( Origin gPackager )
				)
				( objectStatus "R8E23" )
				( pin "a"
					( attribute "PN" "1"
						( Origin gPackager )
					)
					( objectStatus "R8E23.1" )
				)
				( pin "b"
					( attribute "PN" "2"
						( Origin gPackager )
					)
					( objectStatus "R8E23.2" )
				)
			)
			( gate "@baseboard_fab2_lib.baseboard_fab2(sch_1):page142_i18"
				( attribute "BOM_COST" "SB"
					( Origin gFrontEnd )
				)
				( attribute "CDS_LIB" "mstr_discrete"
					( Origin gPackager )
				)
				( attribute "CDS_LOCATION" "R8E29"
					( Origin gPackager )
				)
				( attribute "CDS_SEC" "1"
					( Origin gPackager )
				)
				( attribute "LOCATION" "R8E29"
					( Origin gFrontEnd )
				)
				( attribute "MATERIAL" "EMPTY"
					( Origin gFrontEnd )
				)
				( attribute "PACK_TYPE" "0402"
					( Origin gFrontEnd )
				)
				( attribute "PART_NUMBER" "G21497-005"
					( Origin gFrontEnd )
				)
				( attribute "PHYS_PAGE" "142"
					( Origin gFrontEnd )
				)
				( attribute "ROOM" "PCIE_WAKE_BUFFER"
					( Origin gFrontEnd )
				)
				( attribute "ROT" "0"
					( Origin gFrontEnd )
				)
				( attribute "SEC" "1"
					( Origin gFrontEnd )
				)
				( attribute "SEC_TYPE" "0402"
					( Origin gFrontEnd )
				)
				( attribute "TOLERANCE" "5%"
					( Origin gFrontEnd )
				)
				( attribute "VALUE" "0.0"
					( Origin gFrontEnd )
				)
				( attribute "VER" "1"
					( Origin gFrontEnd )
				)
				( attribute "WATTAGE" "1/16W"
					( Origin gFrontEnd )
				)
				( attribute "XY" "(-4300,3125)"
					( Origin gFrontEnd )
				)
				( attribute "CHIPS_PART_NAME" "RES"
					( Origin gPackager )
				)
				( attribute "CDS_PART_NAME" "RES_0402-0.0,5%,1/16W,EMPTY,G2A"
					( Origin gPackager )
				)
				( objectStatus "R8E29" )
				( pin "a"
					( attribute "PN" "1"
						( Origin gPackager )
					)
					( objectStatus "R8E29.1" )
				)
				( pin "b"
					( attribute "PN" "2"
						( Origin gPackager )
					)
					( objectStatus "R8E29.2" )
				)
			)
			( gate "@baseboard_fab2_lib.baseboard_fab2(sch_1):page142_i20"
				( attribute "BOM_COST" "SB"
					( Origin gFrontEnd )
				)
				( attribute "CDS_LIB" "dev_discrete"
					( Origin gPackager )
				)
				( attribute "CDS_LOCATION" "C8E5"
					( Origin gPackager )
				)
				( attribute "CDS_SEC" "1"
					( Origin gPackager )
				)
				( attribute "LOCATION" "C8E5"
					( Origin gFrontEnd )
				)
				( attribute "MATERIAL" "X7R"
					( Origin gFrontEnd )
				)
				( attribute "PACK_TYPE" "0402V"
					( Origin gFrontEnd )
				)
				( attribute "PART_NUMBER" "A36096-030"
					( Origin gFrontEnd )
				)
				( attribute "PHYS_PAGE" "142"
					( Origin gFrontEnd )
				)
				( attribute "ROOM" "PCIE_WAKE_BUFFER"
					( Origin gFrontEnd )
				)
				( attribute "ROT" "0"
					( Origin gFrontEnd )
				)
				( attribute "SEC" "1"
					( Origin gFrontEnd )
				)
				( attribute "SEC_TYPE" "0402V"
					( Origin gFrontEnd )
				)
				( attribute "TOLERANCE" "10%"
					( Origin gFrontEnd )
				)
				( attribute "VALUE" "0.1UF"
					( Origin gFrontEnd )
				)
				( attribute "VER" "1"
					( Origin gFrontEnd )
				)
				( attribute "VOLTAGE" "16V"
					( Units "uVoltage" "V" 1.000000)
					( Origin gFrontEnd )
				)
				( attribute "XY" "(-3500,1550)"
					( Origin gFrontEnd )
				)
				( attribute "CHIPS_PART_NAME" "CAP_A"
					( Origin gPackager )
				)
				( attribute "CDS_PART_NAME" "CAP_A_0402V-0.1UF,16V,10%,X7R,A"
					( Origin gPackager )
				)
				( objectStatus "C8E5" )
				( pin "a"
					( attribute "PN" "1"
						( Origin gPackager )
					)
					( objectStatus "C8E5.1" )
				)
				( pin "b"
					( attribute "PN" "2"
						( Origin gPackager )
					)
					( objectStatus "C8E5.2" )
				)
			)
			( gate "@baseboard_fab2_lib.baseboard_fab2(sch_1):page142_i23"
				( attribute "CDS_LIB" "mstr_discrete"
					( Origin gPackager )
				)
				( attribute "CDS_LOCATION" "R8E30"
					( Origin gPackager )
				)
				( attribute "CDS_SEC" "1"
					( Origin gPackager )
				)
				( attribute "LOCATION" "R8E30"
					( Origin gFrontEnd )
				)
				( attribute "MATERIAL" "CHIP"
					( Origin gFrontEnd )
				)
				( attribute "PACK_TYPE" "0402"
					( Origin gFrontEnd )
				)
				( attribute "PART_NUMBER" "G21796-016"
					( Origin gFrontEnd )
				)
				( attribute "PHYS_PAGE" "142"
					( Origin gFrontEnd )
				)
				( attribute "ROOM" "PCIE_WAKE_BUFFER"
					( Origin gFrontEnd )
				)
				( attribute "ROT" "0"
					( Origin gFrontEnd )
				)
				( attribute "SEC" "1"
					( Origin gFrontEnd )
				)
				( attribute "SEC_TYPE" "0402"
					( Origin gFrontEnd )
				)
				( attribute "TOLERANCE" "1%"
					( Origin gFrontEnd )
				)
				( attribute "VALUE" "10.0K"
					( Origin gFrontEnd )
				)
				( attribute "VER" "2"
					( Origin gFrontEnd )
				)
				( attribute "WATTAGE" "1/16W"
					( Origin gFrontEnd )
				)
				( attribute "XY" "(-3825,3425)"
					( Origin gFrontEnd )
				)
				( attribute "CHIPS_PART_NAME" "RES"
					( Origin gPackager )
				)
				( attribute "CDS_PART_NAME" "RES_0402-10.0K,1%,1/16W,CHIP,GA"
					( Origin gPackager )
				)
				( objectStatus "R8E30" )
				( pin "a"
					( attribute "PN" "1"
						( Origin gPackager )
					)
					( objectStatus "R8E30.1" )
				)
				( pin "b"
					( attribute "PN" "2"
						( Origin gPackager )
					)
					( objectStatus "R8E30.2" )
				)
			)
			( gate "@baseboard_fab2_lib.baseboard_fab2(sch_1):page142_i28"
				( attribute "CDS_LIB" "mstr_discrete"
					( Origin gPackager )
				)
				( attribute "CDS_LOCATION" "R8E36"
					( Origin gPackager )
				)
				( attribute "CDS_SEC" "1"
					( Origin gPackager )
				)
				( attribute "LOCATION" "R8E36"
					( Origin gFrontEnd )
				)
				( attribute "MATERIAL" "CHIP"
					( Origin gFrontEnd )
				)
				( attribute "PACK_TYPE" "0402"
					( Origin gFrontEnd )
				)
				( attribute "PART_NUMBER" "G21796-016"
					( Origin gFrontEnd )
				)
				( attribute "PHYS_PAGE" "142"
					( Origin gFrontEnd )
				)
				( attribute "ROOM" "PCIE_WAKE_BUFFER"
					( Origin gFrontEnd )
				)
				( attribute "ROT" "0"
					( Origin gFrontEnd )
				)
				( attribute "SEC" "1"
					( Origin gFrontEnd )
				)
				( attribute "SEC_TYPE" "0402"
					( Origin gFrontEnd )
				)
				( attribute "TOLERANCE" "1%"
					( Origin gFrontEnd )
				)
				( attribute "VALUE" "10.0K"
					( Origin gFrontEnd )
				)
				( attribute "VER" "2"
					( Origin gFrontEnd )
				)
				( attribute "WATTAGE" "1/16W"
					( Origin gFrontEnd )
				)
				( attribute "XY" "(-4650,3425)"
					( Origin gFrontEnd )
				)
				( attribute "CHIPS_PART_NAME" "RES"
					( Origin gPackager )
				)
				( attribute "CDS_PART_NAME" "RES_0402-10.0K,1%,1/16W,CHIP,GA"
					( Origin gPackager )
				)
				( objectStatus "R8E36" )
				( pin "a"
					( attribute "PN" "1"
						( Origin gPackager )
					)
					( objectStatus "R8E36.1" )
				)
				( pin "b"
					( attribute "PN" "2"
						( Origin gPackager )
					)
					( objectStatus "R8E36.2" )
				)
			)
			( gate "@baseboard_fab2_lib.baseboard_fab2(sch_1):page142_i30"
				( attribute "CDS_LIB" "mstr_discrete"
					( Origin gPackager )
				)
				( attribute "CDS_LOCATION" "R8E26"
					( Origin gPackager )
				)
				( attribute "CDS_SEC" "1"
					( Origin gPackager )
				)
				( attribute "LOCATION" "R8E26"
					( Origin gFrontEnd )
				)
				( attribute "MATERIAL" "CHIP"
					( Origin gFrontEnd )
				)
				( attribute "PACK_TYPE" "0402"
					( Origin gFrontEnd )
				)
				( attribute "PART_NUMBER" "G21497-005"
					( Origin gFrontEnd )
				)
				( attribute "PHYS_PAGE" "142"
					( Origin gFrontEnd )
				)
				( attribute "ROOM" "PCIE_WAKE_BUFFER"
					( Origin gFrontEnd )
				)
				( attribute "ROT" "0"
					( Origin gFrontEnd )
				)
				( attribute "SEC" "1"
					( Origin gFrontEnd )
				)
				( attribute "SEC_TYPE" "0402"
					( Origin gFrontEnd )
				)
				( attribute "TOLERANCE" "5%"
					( Origin gFrontEnd )
				)
				( attribute "VALUE" "0.0"
					( Origin gFrontEnd )
				)
				( attribute "VER" "1"
					( Origin gFrontEnd )
				)
				( attribute "WATTAGE" "1/16W"
					( Origin gFrontEnd )
				)
				( attribute "XY" "(-4350,2275)"
					( Origin gFrontEnd )
				)
				( attribute "CHIPS_PART_NAME" "RES"
					( Origin gPackager )
				)
				( attribute "CDS_PART_NAME" "RES_0402-0.0,5%,1/16W,CHIP,G21A"
					( Origin gPackager )
				)
				( objectStatus "R8E26" )
				( pin "a"
					( attribute "PN" "1"
						( Origin gPackager )
					)
					( objectStatus "R8E26.1" )
				)
				( pin "b"
					( attribute "PN" "2"
						( Origin gPackager )
					)
					( objectStatus "R8E26.2" )
				)
			)
			( gate "@baseboard_fab2_lib.baseboard_fab2(sch_1):page142_i31"
				( attribute "CDS_LIB" "mstr_discrete"
					( Origin gPackager )
				)
				( attribute "CDS_LOCATION" "R8E28"
					( Origin gPackager )
				)
				( attribute "CDS_SEC" "1"
					( Origin gPackager )
				)
				( attribute "LOCATION" "R8E28"
					( Origin gFrontEnd )
				)
				( attribute "MATERIAL" "CHIP"
					( Origin gFrontEnd )
				)
				( attribute "PACK_TYPE" "0402"
					( Origin gFrontEnd )
				)
				( attribute "PART_NUMBER" "G21497-005"
					( Origin gFrontEnd )
				)
				( attribute "PHYS_PAGE" "142"
					( Origin gFrontEnd )
				)
				( attribute "ROOM" "PCIE_WAKE_BUFFER"
					( Origin gFrontEnd )
				)
				( attribute "ROT" "0"
					( Origin gFrontEnd )
				)
				( attribute "SEC" "1"
					( Origin gFrontEnd )
				)
				( attribute "SEC_TYPE" "0402"
					( Origin gFrontEnd )
				)
				( attribute "TOLERANCE" "5%"
					( Origin gFrontEnd )
				)
				( attribute "VALUE" "0.0"
					( Origin gFrontEnd )
				)
				( attribute "VER" "1"
					( Origin gFrontEnd )
				)
				( attribute "WATTAGE" "1/16W"
					( Origin gFrontEnd )
				)
				( attribute "XY" "(-4075,2475)"
					( Origin gFrontEnd )
				)
				( attribute "CHIPS_PART_NAME" "RES"
					( Origin gPackager )
				)
				( attribute "CDS_PART_NAME" "RES_0402-0.0,5%,1/16W,CHIP,G21A"
					( Origin gPackager )
				)
				( objectStatus "R8E28" )
				( pin "a"
					( attribute "PN" "1"
						( Origin gPackager )
					)
					( objectStatus "R8E28.1" )
				)
				( pin "b"
					( attribute "PN" "2"
						( Origin gPackager )
					)
					( objectStatus "R8E28.2" )
				)
			)
			( gate "@baseboard_fab2_lib.baseboard_fab2(sch_1):page142_i32"
				( attribute "CDS_LIB" "mstr_discrete"
					( Origin gPackager )
				)
				( attribute "CDS_LOCATION" "R8E27"
					( Origin gPackager )
				)
				( attribute "CDS_SEC" "1"
					( Origin gPackager )
				)
				( attribute "LOCATION" "R8E27"
					( Origin gFrontEnd )
				)
				( attribute "MATERIAL" "CHIP"
					( Origin gFrontEnd )
				)
				( attribute "PACK_TYPE" "0402"
					( Origin gFrontEnd )
				)
				( attribute "PART_NUMBER" "G21497-005"
					( Origin gFrontEnd )
				)
				( attribute "PHYS_PAGE" "142"
					( Origin gFrontEnd )
				)
				( attribute "ROOM" "PCIE_WAKE_BUFFER"
					( Origin gFrontEnd )
				)
				( attribute "ROT" "0"
					( Origin gFrontEnd )
				)
				( attribute "SEC" "1"
					( Origin gFrontEnd )
				)
				( attribute "SEC_TYPE" "0402"
					( Origin gFrontEnd )
				)
				( attribute "TOLERANCE" "5%"
					( Origin gFrontEnd )
				)
				( attribute "VALUE" "0.0"
					( Origin gFrontEnd )
				)
				( attribute "VER" "1"
					( Origin gFrontEnd )
				)
				( attribute "WATTAGE" "1/16W"
					( Origin gFrontEnd )
				)
				( attribute "XY" "(-4350,2675)"
					( Origin gFrontEnd )
				)
				( attribute "CHIPS_PART_NAME" "RES"
					( Origin gPackager )
				)
				( attribute "CDS_PART_NAME" "RES_0402-0.0,5%,1/16W,CHIP,G21A"
					( Origin gPackager )
				)
				( objectStatus "R8E27" )
				( pin "a"
					( attribute "PN" "1"
						( Origin gPackager )
					)
					( objectStatus "R8E27.1" )
				)
				( pin "b"
					( attribute "PN" "2"
						( Origin gPackager )
					)
					( objectStatus "R8E27.2" )
				)
			)
			( gate "@baseboard_fab2_lib.baseboard_fab2(sch_1):page142_i33"
				( attribute "CDS_LIB" "mstr_discrete"
					( Origin gPackager )
				)
				( attribute "CDS_LOCATION" "R8E21"
					( Origin gPackager )
				)
				( attribute "CDS_SEC" "1"
					( Origin gPackager )
				)
				( attribute "LOCATION" "R8E21"
					( Origin gFrontEnd )
				)
				( attribute "MATERIAL" "CHIP"
					( Origin gFrontEnd )
				)
				( attribute "PACK_TYPE" "0402"
					( Origin gFrontEnd )
				)
				( attribute "PART_NUMBER" "G21497-005"
					( Origin gFrontEnd )
				)
				( attribute "PHYS_PAGE" "142"
					( Origin gFrontEnd )
				)
				( attribute "ROOM" "PCIE_WAKE_BUFFER"
					( Origin gFrontEnd )
				)
				( attribute "ROT" "0"
					( Origin gFrontEnd )
				)
				( attribute "SEC" "1"
					( Origin gFrontEnd )
				)
				( attribute "SEC_TYPE" "0402"
					( Origin gFrontEnd )
				)
				( attribute "TOLERANCE" "5%"
					( Origin gFrontEnd )
				)
				( attribute "VALUE" "0.0"
					( Origin gFrontEnd )
				)
				( attribute "VER" "1"
					( Origin gFrontEnd )
				)
				( attribute "WATTAGE" "1/16W"
					( Origin gFrontEnd )
				)
				( attribute "XY" "(-4075,2900)"
					( Origin gFrontEnd )
				)
				( attribute "CHIPS_PART_NAME" "RES"
					( Origin gPackager )
				)
				( attribute "CDS_PART_NAME" "RES_0402-0.0,5%,1/16W,CHIP,G21A"
					( Origin gPackager )
				)
				( objectStatus "R8E21" )
				( pin "a"
					( attribute "PN" "1"
						( Origin gPackager )
					)
					( objectStatus "R8E21.1" )
				)
				( pin "b"
					( attribute "PN" "2"
						( Origin gPackager )
					)
					( objectStatus "R8E21.2" )
				)
			)
			( gate "@baseboard_fab2_lib.baseboard_fab2(sch_1):page150_i73"
				( attribute "BOM_COST" "SM_CONTROLLER"
					( Origin gFrontEnd )
				)
				( attribute "CDS_LIB" "mstr_discrete"
					( Origin gPackager )
				)
				( attribute "CDS_LOCATION" "C25W24"
					( Origin gPackager )
				)
				( attribute "CDS_SEC" "1"
					( Origin gPackager )
				)
				( attribute "LOCATION" "C25W24"
					( Origin gFrontEnd )
				)
				( attribute "MATERIAL" "X6S"
					( Origin gFrontEnd )
				)
				( attribute "PACK_TYPE" "0402"
					( Origin gFrontEnd )
				)
				( attribute "PART_NUMBER" "D97712-004"
					( Origin gFrontEnd )
				)
				( attribute "PHYS_PAGE" "150"
					( Origin gFrontEnd )
				)
				( attribute "ROOM" "BMC"
					( Origin gFrontEnd )
				)
				( attribute "ROT" "0"
					( Origin gFrontEnd )
				)
				( attribute "SEC" "1"
					( Origin gFrontEnd )
				)
				( attribute "SEC_TYPE" "0402"
					( Origin gFrontEnd )
				)
				( attribute "TOLERANCE" "10%"
					( Origin gFrontEnd )
				)
				( attribute "VALUE" "1.0UF"
					( Origin gFrontEnd )
				)
				( attribute "VER" "1"
					( Origin gFrontEnd )
				)
				( attribute "VOLTAGE" "6.3V"
					( Units "uVoltage" "V" 1.000000)
					( Origin gFrontEnd )
				)
				( attribute "XY" "(-6075,4975)"
					( Origin gFrontEnd )
				)
				( attribute "CHIPS_PART_NAME" "CAP"
					( Origin gPackager )
				)
				( attribute "CDS_PART_NAME" "CAP_0402-1.0UF,6.3V,10%,X6S,D9A"
					( Origin gPackager )
				)
				( objectStatus "C25W24" )
				( pin "a"
					( attribute "PN" "1"
						( Origin gPackager )
					)
					( objectStatus "C25W24.1" )
				)
				( pin "b"
					( attribute "PN" "2"
						( Origin gPackager )
					)
					( objectStatus "C25W24.2" )
				)
			)
			( gate "@baseboard_fab2_lib.baseboard_fab2(sch_1):page149_i195"
				( attribute "CDS_LIB" "w_hdl"
					( Origin gPackager )
				)
				( attribute "CDS_LMAN_SYM_OUTLINE" "-50,75,50,-75"
					( Origin gPackager )
				)
				( attribute "LOCATION" "R25W36"
					( Origin gFrontEnd )
				)
				( attribute "PACK_TYPE" "RCL_GP"
					( Origin gFrontEnd )
				)
				( attribute "PART_NUMBER" "64.12005.6DL"
					( Origin gFrontEnd )
				)
				( attribute "PHYS_PAGE" "149"
					( Origin gFrontEnd )
				)
				( attribute "ROT" "1"
					( Origin gFrontEnd )
				)
				( attribute "VALUE" "120R2F-GP"
					( Origin gFrontEnd )
				)
				( attribute "VER" "1"
					( Origin gFrontEnd )
				)
				( attribute "XY" "(-6150,3850)"
					( Origin gFrontEnd )
				)
				( attribute "CHIPS_PART_NAME" "120R2F-GP"
					( Origin gPackager )
				)
				( attribute "CDS_PART_NAME" "120R2F-GP_RCL_GP-120R2F-GP,64.A"
					( Origin gPackager )
				)
				( attribute "CDS_LOCATION" "R25W36"
					( Origin gPackager )
				)
				( attribute "CDS_SEC" "1"
					( Origin gPackager )
				)
				( attribute "SEC" "1"
					( Origin gPackager )
				)
				( objectStatus "R25W36" )
				( pin "\1\"
					( attribute "PN" "1"
						( Origin gPackager )
					)
					( objectStatus "R25W36.1" )
				)
				( pin "\2\"
					( attribute "PN" "2"
						( Origin gPackager )
					)
					( objectStatus "R25W36.2" )
				)
			)
			( gate "@baseboard_fab2_lib.baseboard_fab2(sch_1):page145_i117"
				( attribute "CDS_LIB" "w_hdl"
					( Origin gPackager )
				)
				( attribute "CDS_LMAN_SYM_OUTLINE" "-1150,1400,1150,-1400"
					( Origin gPackager )
				)
				( attribute "LOCATION" "U25W4"
					( Origin gFrontEnd )
				)
				( attribute "PACK_TYPE" "ASIC2-GB1"
					( Origin gFrontEnd )
				)
				( attribute "PART_NUMBER" "071.2520A.M001"
					( Origin gFrontEnd )
				)
				( attribute "PHYS_PAGE" "145"
					( Origin gFrontEnd )
				)
				( attribute "ROT" "0"
					( Origin gFrontEnd )
				)
				( attribute "VALUE" "AST2520A1-GP-GP"
					( Origin gFrontEnd )
				)
				( attribute "VER" "3"
					( Origin gFrontEnd )
				)
				( attribute "XY" "(-3800,-2550)"
					( Origin gFrontEnd )
				)
				( attribute "CHIPS_PART_NAME" "AST2520A1-GP-GP"
					( Origin gPackager )
				)
				( attribute "CDS_PART_NAME" "AST2520A1-GP-GP_ASIC2-GB1-AST2A"
					( Origin gPackager )
				)
				( attribute "CDS_LOCATION" "U25W4"
					( Origin gPackager )
				)
				( attribute "CDS_SEC" "3"
					( Origin gPackager )
				)
				( attribute "SEC" "3"
					( Origin gPackager )
				)
				( objectStatus "U25W4" )
				( pin "clkin"
					( attribute "PN" "W18"
						( Origin gPackager )
					)
					( objectStatus "U25W4.W18" )
				)
				( pin "gpioa0_mac1link"
					( attribute "PN" "B14"
						( Origin gPackager )
					)
					( objectStatus "U25W4.B14" )
				)
				( pin "gpioa1_mac2link"
					( attribute "PN" "D14"
						( Origin gPackager )
					)
					( objectStatus "U25W4.D14" )
				)
				( pin "\gpioa2_timer3_spi1cs1#\"
					( attribute "PN" "D13"
						( Origin gPackager )
					)
					( objectStatus "U25W4.D13" )
				)
				( pin "gpioa3_timer4"
					( attribute "PN" "E13"
						( Origin gPackager )
					)
					( objectStatus "U25W4.E13" )
				)
				( pin "gpioc0_sd1clk_scl10"
					( attribute "PN" "C12"
						( Origin gPackager )
					)
					( objectStatus "U25W4.C12" )
				)
				( pin "gpioc1_sd1cmd_sda10"
					( attribute "PN" "A12"
						( Origin gPackager )
					)
					( objectStatus "U25W4.A12" )
				)
				( pin "gpioc2_sd1dat0_scl11"
					( attribute "PN" "B12"
						( Origin gPackager )
					)
					( objectStatus "U25W4.B12" )
				)
				( pin "gpioc3_sd1dat1_sda11"
					( attribute "PN" "D9"
						( Origin gPackager )
					)
					( objectStatus "U25W4.D9" )
				)
				( pin "gpioc4_sd1dat2_scl12"
					( attribute "PN" "D10"
						( Origin gPackager )
					)
					( objectStatus "U25W4.D10" )
				)
				( pin "gpioc5_sd1dat3_sda12"
					( attribute "PN" "E12"
						( Origin gPackager )
					)
					( objectStatus "U25W4.E12" )
				)
				( pin "\gpioc6_sd1cd#_scl13\"
					( attribute "PN" "C11"
						( Origin gPackager )
					)
					( objectStatus "U25W4.C11" )
				)
				( pin "\gpioc7_sd1wp#_sda13\"
					( attribute "PN" "B11"
						( Origin gPackager )
					)
					( objectStatus "U25W4.B11" )
				)
				( pin "gpiod0_sd2clk"
					( attribute "PN" "F19"
						( Origin gPackager )
					)
					( objectStatus "U25W4.F19" )
				)
				( pin "gpiod1_sd2cmd"
					( attribute "PN" "E21"
						( Origin gPackager )
					)
					( objectStatus "U25W4.E21" )
				)
				( pin "gpiod2_sd2dat0"
					( attribute "PN" "F20"
						( Origin gPackager )
					)
					( objectStatus "U25W4.F20" )
				)
				( pin "gpiod3_sd2dat1"
					( attribute "PN" "D20"
						( Origin gPackager )
					)
					( objectStatus "U25W4.D20" )
				)
				( pin "gpiod4_sd2dat2"
					( attribute "PN" "D21"
						( Origin gPackager )
					)
					( objectStatus "U25W4.D21" )
				)
				( pin "gpiod5_sd2dat3"
					( attribute "PN" "E20"
						( Origin gPackager )
					)
					( objectStatus "U25W4.E20" )
				)
				( pin "\gpiod6_sd2cd#\"
					( attribute "PN" "G18"
						( Origin gPackager )
					)
					( objectStatus "U25W4.G18" )
				)
				( pin "\gpiod7_sd2wp#\"
					( attribute "PN" "C21"
						( Origin gPackager )
					)
					( objectStatus "U25W4.C21" )
				)
				( pin "gpioe0_ncts3"
					( attribute "PN" "B20"
						( Origin gPackager )
					)
					( objectStatus "U25W4.B20" )
				)
				( pin "gpioe1_ndcd3"
					( attribute "PN" "C20"
						( Origin gPackager )
					)
					( objectStatus "U25W4.C20" )
				)
				( pin "gpioe2_ndsr3"
					( attribute "PN" "F18"
						( Origin gPackager )
					)
					( objectStatus "U25W4.F18" )
				)
				( pin "gpioe3_nri3"
					( attribute "PN" "F17"
						( Origin gPackager )
					)
					( objectStatus "U25W4.F17" )
				)
				( pin "gpioe4_ndtr3"
					( attribute "PN" "E18"
						( Origin gPackager )
					)
					( objectStatus "U25W4.E18" )
				)
				( pin "gpioe5_nrts3"
					( attribute "PN" "D19"
						( Origin gPackager )
					)
					( objectStatus "U25W4.D19" )
				)
				( pin "gpioe6_txd3"
					( attribute "PN" "A20"
						( Origin gPackager )
					)
					( objectStatus "U25W4.A20" )
				)
				( pin "gpioe7_rxd3"
					( attribute "PN" "B19"
						( Origin gPackager )
					)
					( objectStatus "U25W4.B19" )
				)
				( pin "gpiof0_ncts4_lhad0"
					( attribute "PN" "J19"
						( Origin gPackager )
					)
					( objectStatus "U25W4.J19" )
				)
				( pin "gpiof1_ndcd4_lhad1"
					( attribute "PN" "J18"
						( Origin gPackager )
					)
					( objectStatus "U25W4.J18" )
				)
				( pin "gpiof2_ndsr4_lhad2"
					( attribute "PN" "B22"
						( Origin gPackager )
					)
					( objectStatus "U25W4.B22" )
				)
				( pin "gpiof3_nri4_lhad3"
					( attribute "PN" "B21"
						( Origin gPackager )
					)
					( objectStatus "U25W4.B21" )
				)
				( pin "gpiof4_ndtr4_lhclk"
					( attribute "PN" "A21"
						( Origin gPackager )
					)
					( objectStatus "U25W4.A21" )
				)
				( pin "\gpiof5_nrts4_lhframe#\"
					( attribute "PN" "H19"
						( Origin gPackager )
					)
					( objectStatus "U25W4.H19" )
				)
				( pin "\gpiof6_txd4_lhsirq#\"
					( attribute "PN" "G17"
						( Origin gPackager )
					)
					( objectStatus "U25W4.G17" )
				)
				( pin "\gpiof7_rxd4_lhrst#\"
					( attribute "PN" "H18"
						( Origin gPackager )
					)
					( objectStatus "U25W4.H18" )
				)
				( pin "gpiog4_sgps2ck_salt1"
					( attribute "PN" "E17"
						( Origin gPackager )
					)
					( objectStatus "U25W4.E17" )
				)
				( pin "gpiog5_sgps2ld_salt2"
					( attribute "PN" "D16"
						( Origin gPackager )
					)
					( objectStatus "U25W4.D16" )
				)
				( pin "gpiog6_sgps2i0_salt3"
					( attribute "PN" "D15"
						( Origin gPackager )
					)
					( objectStatus "U25W4.D15" )
				)
				( pin "gpiog7_sgps2i1_salt4"
					( attribute "PN" "E14"
						( Origin gPackager )
					)
					( objectStatus "U25W4.E14" )
				)
				( pin "gpiol0_ncts1"
					( attribute "PN" "T2"
						( Origin gPackager )
					)
					( objectStatus "U25W4.T2" )
				)
				( pin "gpiol1_ndcd1_vpide"
					( attribute "PN" "T1"
						( Origin gPackager )
					)
					( objectStatus "U25W4.T1" )
				)
				( pin "gpiol2_ndsr1"
					( attribute "PN" "U1"
						( Origin gPackager )
					)
					( objectStatus "U25W4.U1" )
				)
				( pin "gpiol3_nri1_vpihs"
					( attribute "PN" "U2"
						( Origin gPackager )
					)
					( objectStatus "U25W4.U2" )
				)
				( pin "gpiol4_ndtr1_vpivs"
					( attribute "PN" "P4"
						( Origin gPackager )
					)
					( objectStatus "U25W4.P4" )
				)
				( pin "gpiol5_nrts1_vpiclk"
					( attribute "PN" "P3"
						( Origin gPackager )
					)
					( objectStatus "U25W4.P3" )
				)
				( pin "gpiol6_txd1"
					( attribute "PN" "V1"
						( Origin gPackager )
					)
					( objectStatus "U25W4.V1" )
				)
				( pin "gpiol7_rxd1"
					( attribute "PN" "W1"
						( Origin gPackager )
					)
					( objectStatus "U25W4.W1" )
				)
				( pin "gpiom0_ncts2_vpib2"
					( attribute "PN" "Y1"
						( Origin gPackager )
					)
					( objectStatus "U25W4.Y1" )
				)
				( pin "gpiom1_ndcd2_vpib3"
					( attribute "PN" "AB2"
						( Origin gPackager )
					)
					( objectStatus "U25W4.AB2" )
				)
				( pin "gpiom2_ndsr2_vpib4"
					( attribute "PN" "AA1"
						( Origin gPackager )
					)
					( objectStatus "U25W4.AA1" )
				)
				( pin "gpiom3_nri2_vpib5"
					( attribute "PN" "Y2"
						( Origin gPackager )
					)
					( objectStatus "U25W4.Y2" )
				)
				( pin "gpiom4_ndtr2_vpib6"
					( attribute "PN" "AA2"
						( Origin gPackager )
					)
					( objectStatus "U25W4.AA2" )
				)
				( pin "gpiom5_nrts2_vpib7"
					( attribute "PN" "P5"
						( Origin gPackager )
					)
					( objectStatus "U25W4.P5" )
				)
				( pin "gpiom6_txd2_vpib8"
					( attribute "PN" "R5"
						( Origin gPackager )
					)
					( objectStatus "U25W4.R5" )
				)
				( pin "gpiom7_rxd2_vpib9"
					( attribute "PN" "T5"
						( Origin gPackager )
					)
					( objectStatus "U25W4.T5" )
				)
				( pin "\gpioy3_sioonctrl#\"
					( attribute "PN" "P21"
						( Origin gPackager )
					)
					( objectStatus "U25W4.P21" )
				)
				( pin "peci"
					( attribute "PN" "AB18"
						( Origin gPackager )
					)
					( objectStatus "U25W4.AB18" )
				)
				( pin "perefclkn"
					( attribute "PN" "K22"
						( Origin gPackager )
					)
					( objectStatus "U25W4.K22" )
				)
				( pin "perefclkp"
					( attribute "PN" "K21"
						( Origin gPackager )
					)
					( objectStatus "U25W4.K21" )
				)
				( pin "perext"
					( attribute "PN" "K20"
						( Origin gPackager )
					)
					( objectStatus "U25W4.K20" )
				)
				( pin "\perst#\"
					( attribute "PN" "L20"
						( Origin gPackager )
					)
					( objectStatus "U25W4.L20" )
				)
				( pin "perxn"
					( attribute "PN" "M22"
						( Origin gPackager )
					)
					( objectStatus "U25W4.M22" )
				)
				( pin "perxp"
					( attribute "PN" "M21"
						( Origin gPackager )
					)
					( objectStatus "U25W4.M21" )
				)
				( pin "petxn"
					( attribute "PN" "L22"
						( Origin gPackager )
					)
					( objectStatus "U25W4.L22" )
				)
				( pin "petxp"
					( attribute "PN" "L21"
						( Origin gPackager )
					)
					( objectStatus "U25W4.L21" )
				)
				( pin "rxd5"
					( attribute "PN" "K2"
						( Origin gPackager )
					)
					( objectStatus "U25W4.K2" )
				)
				( pin "\srst#\"
					( attribute "PN" "U18"
						( Origin gPackager )
					)
					( objectStatus "U25W4.U18" )
				)
				( pin "txd5"
					( attribute "PN" "K1"
						( Origin gPackager )
					)
					( objectStatus "U25W4.K1" )
				)
			)
			( gate "@baseboard_fab2_lib.baseboard_fab2(sch_1):page150_i76"
				( attribute "CDS_LIB" "w_hdl"
					( Origin gPackager )
				)
				( attribute "CDS_LMAN_SYM_OUTLINE" "-50,100,50,-100"
					( Origin gPackager )
				)
				( attribute "LOCATION" "FB2T3"
					( Origin gFrontEnd )
				)
				( attribute "PACK_TYPE" "DISCRET-G9"
					( Origin gFrontEnd )
				)
				( attribute "PART_NUMBER" "68.00230.231"
					( Origin gFrontEnd )
				)
				( attribute "PHYS_PAGE" "150"
					( Origin gFrontEnd )
				)
				( attribute "ROT" "1"
					( Origin gFrontEnd )
				)
				( attribute "VALUE" "HCB1608KF-800T30-GP"
					( Origin gFrontEnd )
				)
				( attribute "VER" "1"
					( Origin gFrontEnd )
				)
				( attribute "XY" "(-6300,3975)"
					( Origin gFrontEnd )
				)
				( attribute "CHIPS_PART_NAME" "HCB1608KF-800T30-GP"
					( Origin gPackager )
				)
				( attribute "CDS_PART_NAME" "HCB1608KF-800T30-GP_DISCRET-G9A"
					( Origin gPackager )
				)
				( attribute "CDS_LOCATION" "FB2T3"
					( Origin gPackager )
				)
				( attribute "CDS_SEC" "1"
					( Origin gPackager )
				)
				( attribute "SEC" "1"
					( Origin gPackager )
				)
				( objectStatus "FB2T3" )
				( pin "\1\"
					( attribute "PN" "1"
						( Origin gPackager )
					)
					( objectStatus "FB2T3.1" )
				)
				( pin "\2\"
					( attribute "PN" "2"
						( Origin gPackager )
					)
					( objectStatus "FB2T3.2" )
				)
			)
			( gate "@baseboard_fab2_lib.baseboard_fab2(sch_1):page150_i75"
				( attribute "BOM_COST" "SM_CONTROLLER"
					( Origin gFrontEnd )
				)
				( attribute "CDS_LIB" "mstr_discrete"
					( Origin gPackager )
				)
				( attribute "CDS_LOCATION" "C25W23"
					( Origin gPackager )
				)
				( attribute "CDS_SEC" "1"
					( Origin gPackager )
				)
				( attribute "LOCATION" "C25W23"
					( Origin gFrontEnd )
				)
				( attribute "MATERIAL" "X6S"
					( Origin gFrontEnd )
				)
				( attribute "PACK_TYPE" "0402"
					( Origin gFrontEnd )
				)
				( attribute "PART_NUMBER" "D97712-004"
					( Origin gFrontEnd )
				)
				( attribute "PHYS_PAGE" "150"
					( Origin gFrontEnd )
				)
				( attribute "ROOM" "BMC"
					( Origin gFrontEnd )
				)
				( attribute "ROT" "0"
					( Origin gFrontEnd )
				)
				( attribute "SEC" "1"
					( Origin gFrontEnd )
				)
				( attribute "SEC_TYPE" "0402"
					( Origin gFrontEnd )
				)
				( attribute "TOLERANCE" "10%"
					( Origin gFrontEnd )
				)
				( attribute "VALUE" "1.0UF"
					( Origin gFrontEnd )
				)
				( attribute "VER" "1"
					( Origin gFrontEnd )
				)
				( attribute "VOLTAGE" "6.3V"
					( Units "uVoltage" "V" 1.000000)
					( Origin gFrontEnd )
				)
				( attribute "XY" "(-6475,4975)"
					( Origin gFrontEnd )
				)
				( attribute "CHIPS_PART_NAME" "CAP"
					( Origin gPackager )
				)
				( attribute "CDS_PART_NAME" "CAP_0402-1.0UF,6.3V,10%,X6S,D9A"
					( Origin gPackager )
				)
				( objectStatus "C25W23" )
				( pin "a"
					( attribute "PN" "1"
						( Origin gPackager )
					)
					( objectStatus "C25W23.1" )
				)
				( pin "b"
					( attribute "PN" "2"
						( Origin gPackager )
					)
					( objectStatus "C25W23.2" )
				)
			)
			( gate "@baseboard_fab2_lib.baseboard_fab2(sch_1):page150_i54"
				( attribute "CDS_LIB" "w_hdl"
					( Origin gPackager )
				)
				( attribute "CDS_LMAN_SYM_OUTLINE" "-50,25,50,-25"
					( Origin gPackager )
				)
				( attribute "LOCATION" "C25W47"
					( Origin gFrontEnd )
				)
				( attribute "PACK_TYPE" "SMD-BCG"
					( Origin gFrontEnd )
				)
				( attribute "PART_NUMBER" "78.47523.5BL"
					( Origin gFrontEnd )
				)
				( attribute "PHYS_PAGE" "150"
					( Origin gFrontEnd )
				)
				( attribute "ROT" "0"
					( Origin gFrontEnd )
				)
				( attribute "VALUE" "SC4D7U10V3KX-GP"
					( Origin gFrontEnd )
				)
				( attribute "VER" "1"
					( Origin gFrontEnd )
				)
				( attribute "XY" "(-3675,2500)"
					( Origin gFrontEnd )
				)
				( attribute "CHIPS_PART_NAME" "SC4D7U10V3KX-GP"
					( Origin gPackager )
				)
				( attribute "CDS_PART_NAME" "SC4D7U10V3KX-GP_SMD-BCG-SC4D7UA"
					( Origin gPackager )
				)
				( attribute "CDS_LOCATION" "C25W47"
					( Origin gPackager )
				)
				( attribute "CDS_SEC" "1"
					( Origin gPackager )
				)
				( attribute "SEC" "1"
					( Origin gPackager )
				)
				( objectStatus "C25W47" )
				( pin "\1\"
					( attribute "PN" "1"
						( Origin gPackager )
					)
					( objectStatus "C25W47.1" )
				)
				( pin "\2\"
					( attribute "PN" "2"
						( Origin gPackager )
					)
					( objectStatus "C25W47.2" )
				)
			)
			( gate "@baseboard_fab2_lib.baseboard_fab2(sch_1):page150_i55"
				( attribute "BOM_COST" "SM_CONTROLLER"
					( Origin gFrontEnd )
				)
				( attribute "CDS_LIB" "mstr_discrete"
					( Origin gPackager )
				)
				( attribute "LOCATION" "C25W46"
					( Origin gFrontEnd )
				)
				( attribute "MATERIAL" "X6S"
					( Origin gFrontEnd )
				)
				( attribute "PACK_TYPE" "0805"
					( Origin gFrontEnd )
				)
				( attribute "PART_NUMBER" "C95333-007"
					( Origin gFrontEnd )
				)
				( attribute "PHYS_PAGE" "150"
					( Origin gFrontEnd )
				)
				( attribute "ROOM" "BMC"
					( Origin gFrontEnd )
				)
				( attribute "ROT" "0"
					( Origin gFrontEnd )
				)
				( attribute "TOLERANCE" "10%"
					( Origin gFrontEnd )
				)
				( attribute "VALUE" "10UF"
					( Origin gFrontEnd )
				)
				( attribute "VER" "1"
					( Origin gFrontEnd )
				)
				( attribute "VOLTAGE" "16V"
					( Units "uVoltage" "V" 1.000000)
					( Origin gFrontEnd )
				)
				( attribute "XY" "(-3975,2475)"
					( Origin gFrontEnd )
				)
				( attribute "CHIPS_PART_NAME" "CAP"
					( Origin gPackager )
				)
				( attribute "CDS_PART_NAME" "CAP_0805-10UF,16V,10%,X6S,C953A"
					( Origin gPackager )
				)
				( attribute "CDS_LOCATION" "C25W46"
					( Origin gPackager )
				)
				( attribute "CDS_SEC" "1"
					( Origin gPackager )
				)
				( attribute "SEC" "1"
					( Origin gPackager )
				)
				( objectStatus "C25W46" )
				( pin "a"
					( attribute "PN" "1"
						( Origin gPackager )
					)
					( objectStatus "C25W46.1" )
				)
				( pin "b"
					( attribute "PN" "2"
						( Origin gPackager )
					)
					( objectStatus "C25W46.2" )
				)
			)
			( gate "@baseboard_fab2_lib.baseboard_fab2(sch_1):page149_i188"
				( attribute "CDS_LIB" "w_hdl"
					( Origin gPackager )
				)
				( attribute "CDS_LMAN_SYM_OUTLINE" "-50,75,50,-75"
					( Origin gPackager )
				)
				( attribute "LOCATION" "R25W30"
					( Origin gFrontEnd )
				)
				( attribute "PACK_TYPE" "RCL_GP"
					( Origin gFrontEnd )
				)
				( attribute "PART_NUMBER" "64.12005.6DL"
					( Origin gFrontEnd )
				)
				( attribute "PHYS_PAGE" "149"
					( Origin gFrontEnd )
				)
				( attribute "ROT" "1"
					( Origin gFrontEnd )
				)
				( attribute "VALUE" "120R2F-GP"
					( Origin gFrontEnd )
				)
				( attribute "VER" "1"
					( Origin gFrontEnd )
				)
				( attribute "XY" "(-6150,4150)"
					( Origin gFrontEnd )
				)
				( attribute "CHIPS_PART_NAME" "120R2F-GP"
					( Origin gPackager )
				)
				( attribute "CDS_PART_NAME" "120R2F-GP_RCL_GP-120R2F-GP,64.A"
					( Origin gPackager )
				)
				( attribute "CDS_LOCATION" "R25W30"
					( Origin gPackager )
				)
				( attribute "CDS_SEC" "1"
					( Origin gPackager )
				)
				( attribute "SEC" "1"
					( Origin gPackager )
				)
				( objectStatus "R25W30" )
				( pin "\1\"
					( attribute "PN" "1"
						( Origin gPackager )
					)
					( objectStatus "R25W30.1" )
				)
				( pin "\2\"
					( attribute "PN" "2"
						( Origin gPackager )
					)
					( objectStatus "R25W30.2" )
				)
			)
			( gate "@baseboard_fab2_lib.baseboard_fab2(sch_1):page149_i189"
				( attribute "CDS_LIB" "w_hdl"
					( Origin gPackager )
				)
				( attribute "CDS_LMAN_SYM_OUTLINE" "-50,75,50,-75"
					( Origin gPackager )
				)
				( attribute "LOCATION" "R25W29"
					( Origin gFrontEnd )
				)
				( attribute "PACK_TYPE" "RCL_GP"
					( Origin gFrontEnd )
				)
				( attribute "PART_NUMBER" "64.12005.6DL"
					( Origin gFrontEnd )
				)
				( attribute "PHYS_PAGE" "149"
					( Origin gFrontEnd )
				)
				( attribute "ROT" "1"
					( Origin gFrontEnd )
				)
				( attribute "VALUE" "120R2F-GP"
					( Origin gFrontEnd )
				)
				( attribute "VER" "1"
					( Origin gFrontEnd )
				)
				( attribute "XY" "(-6150,4200)"
					( Origin gFrontEnd )
				)
				( attribute "CHIPS_PART_NAME" "120R2F-GP"
					( Origin gPackager )
				)
				( attribute "CDS_PART_NAME" "120R2F-GP_RCL_GP-120R2F-GP,64.A"
					( Origin gPackager )
				)
				( attribute "CDS_LOCATION" "R25W29"
					( Origin gPackager )
				)
				( attribute "CDS_SEC" "1"
					( Origin gPackager )
				)
				( attribute "SEC" "1"
					( Origin gPackager )
				)
				( objectStatus "R25W29" )
				( pin "\1\"
					( attribute "PN" "1"
						( Origin gPackager )
					)
					( objectStatus "R25W29.1" )
				)
				( pin "\2\"
					( attribute "PN" "2"
						( Origin gPackager )
					)
					( objectStatus "R25W29.2" )
				)
			)
			( gate "@baseboard_fab2_lib.baseboard_fab2(sch_1):page149_i190"
				( attribute "CDS_LIB" "w_hdl"
					( Origin gPackager )
				)
				( attribute "CDS_LMAN_SYM_OUTLINE" "-50,75,50,-75"
					( Origin gPackager )
				)
				( attribute "LOCATION" "R25W31"
					( Origin gFrontEnd )
				)
				( attribute "PACK_TYPE" "RCL_GP"
					( Origin gFrontEnd )
				)
				( attribute "PART_NUMBER" "64.12005.6DL"
					( Origin gFrontEnd )
				)
				( attribute "PHYS_PAGE" "149"
					( Origin gFrontEnd )
				)
				( attribute "ROT" "1"
					( Origin gFrontEnd )
				)
				( attribute "VALUE" "120R2F-GP"
					( Origin gFrontEnd )
				)
				( attribute "VER" "1"
					( Origin gFrontEnd )
				)
				( attribute "XY" "(-6150,4100)"
					( Origin gFrontEnd )
				)
				( attribute "CHIPS_PART_NAME" "120R2F-GP"
					( Origin gPackager )
				)
				( attribute "CDS_PART_NAME" "120R2F-GP_RCL_GP-120R2F-GP,64.A"
					( Origin gPackager )
				)
				( attribute "CDS_LOCATION" "R25W31"
					( Origin gPackager )
				)
				( attribute "CDS_SEC" "1"
					( Origin gPackager )
				)
				( attribute "SEC" "1"
					( Origin gPackager )
				)
				( objectStatus "R25W31" )
				( pin "\1\"
					( attribute "PN" "1"
						( Origin gPackager )
					)
					( objectStatus "R25W31.1" )
				)
				( pin "\2\"
					( attribute "PN" "2"
						( Origin gPackager )
					)
					( objectStatus "R25W31.2" )
				)
			)
			( gate "@baseboard_fab2_lib.baseboard_fab2(sch_1):page143_i58"
				( attribute "BOM_COST" "SM_MEM"
					( Origin gFrontEnd )
				)
				( attribute "CDS_LIB" "mstr_discrete"
					( Origin gPackager )
				)
				( attribute "LOCATION" "R1T27"
					( Origin gFrontEnd )
				)
				( attribute "MATERIAL" "CHIP"
					( Origin gFrontEnd )
				)
				( attribute "PACK_TYPE" "0402"
					( Origin gFrontEnd )
				)
				( attribute "PART_NUMBER" "G21796-294"
					( Origin gFrontEnd )
				)
				( attribute "PHYS_PAGE" "143"
					( Origin gFrontEnd )
				)
				( attribute "ROOM" "BMC_MEMORY"
					( Origin gFrontEnd )
				)
				( attribute "ROT" "7"
					( Origin gFrontEnd )
				)
				( attribute "TOLERANCE" "1.0%"
					( Origin gFrontEnd )
				)
				( attribute "VALUE" "240"
					( Origin gFrontEnd )
				)
				( attribute "VER" "2"
					( Origin gFrontEnd )
				)
				( attribute "WATTAGE" "1/16W"
					( Origin gFrontEnd )
				)
				( attribute "XY" "(-10925,-2150)"
					( Origin gFrontEnd )
				)
				( attribute "CHIPS_PART_NAME" "RES"
					( Origin gPackager )
				)
				( attribute "CDS_PART_NAME" "RES_0402-240,1.0%,1/16W,CHIP,GA"
					( Origin gPackager )
				)
				( attribute "CDS_LOCATION" "R1T27"
					( Origin gPackager )
				)
				( attribute "CDS_SEC" "1"
					( Origin gPackager )
				)
				( attribute "SEC" "1"
					( Origin gPackager )
				)
				( objectStatus "R1T27" )
				( pin "a"
					( attribute "PN" "1"
						( Origin gPackager )
					)
					( objectStatus "R1T27.1" )
				)
				( pin "b"
					( attribute "PN" "2"
						( Origin gPackager )
					)
					( objectStatus "R1T27.2" )
				)
			)
			( gate "@baseboard_fab2_lib.baseboard_fab2(sch_1):page149_i187"
				( attribute "CDS_LIB" "w_hdl"
					( Origin gPackager )
				)
				( attribute "CDS_LMAN_SYM_OUTLINE" "-50,75,50,-75"
					( Origin gPackager )
				)
				( attribute "LOCATION" "R25W28"
					( Origin gFrontEnd )
				)
				( attribute "PACK_TYPE" "RCL_GP"
					( Origin gFrontEnd )
				)
				( attribute "PART_NUMBER" "64.12005.6DL"
					( Origin gFrontEnd )
				)
				( attribute "PHYS_PAGE" "149"
					( Origin gFrontEnd )
				)
				( attribute "ROT" "1"
					( Origin gFrontEnd )
				)
				( attribute "VALUE" "120R2F-GP"
					( Origin gFrontEnd )
				)
				( attribute "VER" "1"
					( Origin gFrontEnd )
				)
				( attribute "XY" "(-6150,4250)"
					( Origin gFrontEnd )
				)
				( attribute "CHIPS_PART_NAME" "120R2F-GP"
					( Origin gPackager )
				)
				( attribute "CDS_PART_NAME" "120R2F-GP_RCL_GP-120R2F-GP,64.A"
					( Origin gPackager )
				)
				( attribute "CDS_LOCATION" "R25W28"
					( Origin gPackager )
				)
				( attribute "CDS_SEC" "1"
					( Origin gPackager )
				)
				( attribute "SEC" "1"
					( Origin gPackager )
				)
				( objectStatus "R25W28" )
				( pin "\1\"
					( attribute "PN" "1"
						( Origin gPackager )
					)
					( objectStatus "R25W28.1" )
				)
				( pin "\2\"
					( attribute "PN" "2"
						( Origin gPackager )
					)
					( objectStatus "R25W28.2" )
				)
			)
			( gate "@baseboard_fab2_lib.baseboard_fab2(sch_1):page149_i186"
				( attribute "CDS_LIB" "w_hdl"
					( Origin gPackager )
				)
				( attribute "CDS_LMAN_SYM_OUTLINE" "-50,75,50,-75"
					( Origin gPackager )
				)
				( attribute "LOCATION" "R25W27"
					( Origin gFrontEnd )
				)
				( attribute "PACK_TYPE" "RCL_GP"
					( Origin gFrontEnd )
				)
				( attribute "PART_NUMBER" "64.12005.6DL"
					( Origin gFrontEnd )
				)
				( attribute "PHYS_PAGE" "149"
					( Origin gFrontEnd )
				)
				( attribute "ROT" "1"
					( Origin gFrontEnd )
				)
				( attribute "VALUE" "120R2F-GP"
					( Origin gFrontEnd )
				)
				( attribute "VER" "1"
					( Origin gFrontEnd )
				)
				( attribute "XY" "(-6150,4300)"
					( Origin gFrontEnd )
				)
				( attribute "CHIPS_PART_NAME" "120R2F-GP"
					( Origin gPackager )
				)
				( attribute "CDS_PART_NAME" "120R2F-GP_RCL_GP-120R2F-GP,64.A"
					( Origin gPackager )
				)
				( attribute "CDS_LOCATION" "R25W27"
					( Origin gPackager )
				)
				( attribute "CDS_SEC" "1"
					( Origin gPackager )
				)
				( attribute "SEC" "1"
					( Origin gPackager )
				)
				( objectStatus "R25W27" )
				( pin "\1\"
					( attribute "PN" "1"
						( Origin gPackager )
					)
					( objectStatus "R25W27.1" )
				)
				( pin "\2\"
					( attribute "PN" "2"
						( Origin gPackager )
					)
					( objectStatus "R25W27.2" )
				)
			)
			( gate "@baseboard_fab2_lib.baseboard_fab2(sch_1):page249_i32"
				( attribute "BOM_COST" "NT_GBE_BASE"
					( Origin gFrontEnd )
				)
				( attribute "CDS_LIB" "mstr_discrete"
					( Origin gPackager )
				)
				( attribute "LOCATION" "C8W1"
					( Origin gFrontEnd )
				)
				( attribute "MATERIAL" "X6S"
					( Origin gFrontEnd )
				)
				( attribute "PACK_TYPE" "0603"
					( Origin gFrontEnd )
				)
				( attribute "PART_NUMBER" "E15431-002"
					( Origin gFrontEnd )
				)
				( attribute "PHYS_PAGE" "249"
					( Origin gFrontEnd )
				)
				( attribute "ROOM" "NIC_SPRV"
					( Origin gFrontEnd )
				)
				( attribute "ROT" "1"
					( Origin gFrontEnd )
				)
				( attribute "TOLERANCE" "20%"
					( Origin gFrontEnd )
				)
				( attribute "VALUE" "10UF"
					( Origin gFrontEnd )
				)
				( attribute "VER" "1"
					( Origin gFrontEnd )
				)
				( attribute "VOLTAGE" "6.3V"
					( Units "uVoltage" "V" 1.000000)
					( Origin gFrontEnd )
				)
				( attribute "XY" "(-6800,2150)"
					( Origin gFrontEnd )
				)
				( attribute "CHIPS_PART_NAME" "CAP"
					( Origin gPackager )
				)
				( attribute "CDS_PART_NAME" "CAP_0603-10UF,6.3V,20%,X6S,E15A"
					( Origin gPackager )
				)
				( attribute "CDS_LOCATION" "C8W1"
					( Origin gPackager )
				)
				( attribute "CDS_SEC" "1"
					( Origin gPackager )
				)
				( attribute "SEC" "1"
					( Origin gPackager )
				)
				( objectStatus "C8W1" )
				( pin "a"
					( attribute "PN" "1"
						( Origin gPackager )
					)
					( objectStatus "C8W1.1" )
				)
				( pin "b"
					( attribute "PN" "2"
						( Origin gPackager )
					)
					( objectStatus "C8W1.2" )
				)
			)
			( gate "@baseboard_fab2_lib.baseboard_fab2(sch_1):page149_i156"
				( attribute "BOM_COST" "SM_CONTROLLER"
					( Origin gFrontEnd )
				)
				( attribute "CDS_LIB" "mstr_discrete"
					( Origin gPackager )
				)
				( attribute "CDS_LOCATION" "R8B25"
					( Origin gPackager )
				)
				( attribute "CDS_SEC" "1"
					( Origin gPackager )
				)
				( attribute "LOCATION" "R8B25"
					( Origin gFrontEnd )
				)
				( attribute "MATERIAL" "CHIP"
					( Origin gFrontEnd )
				)
				( attribute "PACK_TYPE" "0402"
					( Origin gFrontEnd )
				)
				( attribute "PART_NUMBER" "G21796-072"
					( Origin gFrontEnd )
				)
				( attribute "PHYS_PAGE" "149"
					( Origin gFrontEnd )
				)
				( attribute "ROOM" "BMC"
					( Origin gFrontEnd )
				)
				( attribute "ROT" "0"
					( Origin gFrontEnd )
				)
				( attribute "SEC" "1"
					( Origin gFrontEnd )
				)
				( attribute "SEC_TYPE" "0402"
					( Origin gFrontEnd )
				)
				( attribute "TOLERANCE" "1%"
					( Origin gFrontEnd )
				)
				( attribute "VALUE" "4.75K"
					( Origin gFrontEnd )
				)
				( attribute "VER" "2"
					( Origin gFrontEnd )
				)
				( attribute "WATTAGE" "1/16W"
					( Origin gFrontEnd )
				)
				( attribute "XY" "(-6675,2150)"
					( Origin gFrontEnd )
				)
				( attribute "CHIPS_PART_NAME" "RES"
					( Origin gPackager )
				)
				( attribute "CDS_PART_NAME" "RES_0402-4.75K,1%,1/16W,CHIP,GA"
					( Origin gPackager )
				)
				( objectStatus "R8B25" )
				( pin "a"
					( attribute "PN" "1"
						( Origin gPackager )
					)
					( objectStatus "R8B25.1" )
				)
				( pin "b"
					( attribute "PN" "2"
						( Origin gPackager )
					)
					( objectStatus "R8B25.2" )
				)
			)
			( gate "@baseboard_fab2_lib.baseboard_fab2(sch_1):page149_i158"
				( attribute "BOM_COST" "SM_MEM"
					( Origin gFrontEnd )
				)
				( attribute "CDS_LIB" "mstr_discrete"
					( Origin gPackager )
				)
				( attribute "CDS_LOCATION" "C25W10"
					( Origin gPackager )
				)
				( attribute "CDS_SEC" "1"
					( Origin gPackager )
				)
				( attribute "LOCATION" "C25W10"
					( Origin gFrontEnd )
				)
				( attribute "MATERIAL" "X7R"
					( Origin gFrontEnd )
				)
				( attribute "PACK_TYPE" "0402LF"
					( Origin gFrontEnd )
				)
				( attribute "PART_NUMBER" "A36096-045"
					( Origin gFrontEnd )
				)
				( attribute "PHYS_PAGE" "149"
					( Origin gFrontEnd )
				)
				( attribute "ROOM" "BMC_MEMORY"
					( Origin gFrontEnd )
				)
				( attribute "ROT" "0"
					( Origin gFrontEnd )
				)
				( attribute "SEC" "1"
					( Origin gFrontEnd )
				)
				( attribute "SEC_TYPE" "0402LF"
					( Origin gFrontEnd )
				)
				( attribute "TOLERANCE" "10%"
					( Origin gFrontEnd )
				)
				( attribute "VALUE" "0.01UF"
					( Origin gFrontEnd )
				)
				( attribute "VER" "1"
					( Origin gFrontEnd )
				)
				( attribute "VOLTAGE" "25V"
					( Units "uVoltage" "V" 1.000000)
					( Origin gFrontEnd )
				)
				( attribute "XY" "(-6775,1025)"
					( Origin gFrontEnd )
				)
				( attribute "CHIPS_PART_NAME" "CAP"
					( Origin gPackager )
				)
				( attribute "CDS_PART_NAME" "CAP_0402LF-0.01UF,25V,10%,X7R,A"
					( Origin gPackager )
				)
				( objectStatus "C25W10" )
				( pin "a"
					( attribute "PN" "1"
						( Origin gPackager )
					)
					( objectStatus "C25W10.1" )
				)
				( pin "b"
					( attribute "PN" "2"
						( Origin gPackager )
					)
					( objectStatus "C25W10.2" )
				)
			)
			( gate "@baseboard_fab2_lib.baseboard_fab2(sch_1):page149_i200"
				( attribute "CDS_LIB" "w_hdl"
					( Origin gPackager )
				)
				( attribute "CDS_LMAN_SYM_OUTLINE" "-50,75,50,-75"
					( Origin gPackager )
				)
				( attribute "LOCATION" "R25W40"
					( Origin gFrontEnd )
				)
				( attribute "PACK_TYPE" "RCL_GP"
					( Origin gFrontEnd )
				)
				( attribute "PART_NUMBER" "64.12005.6DL"
					( Origin gFrontEnd )
				)
				( attribute "PHYS_PAGE" "149"
					( Origin gFrontEnd )
				)
				( attribute "ROT" "1"
					( Origin gFrontEnd )
				)
				( attribute "VALUE" "120R2F-GP"
					( Origin gFrontEnd )
				)
				( attribute "VER" "1"
					( Origin gFrontEnd )
				)
				( attribute "XY" "(-6150,3650)"
					( Origin gFrontEnd )
				)
				( attribute "CHIPS_PART_NAME" "120R2F-GP"
					( Origin gPackager )
				)
				( attribute "CDS_PART_NAME" "120R2F-GP_RCL_GP-120R2F-GP,64.A"
					( Origin gPackager )
				)
				( attribute "CDS_LOCATION" "R25W40"
					( Origin gPackager )
				)
				( attribute "CDS_SEC" "1"
					( Origin gPackager )
				)
				( attribute "SEC" "1"
					( Origin gPackager )
				)
				( objectStatus "R25W40" )
				( pin "\1\"
					( attribute "PN" "1"
						( Origin gPackager )
					)
					( objectStatus "R25W40.1" )
				)
				( pin "\2\"
					( attribute "PN" "2"
						( Origin gPackager )
					)
					( objectStatus "R25W40.2" )
				)
			)
			( gate "@baseboard_fab2_lib.baseboard_fab2(sch_1):page149_i199"
				( attribute "CDS_LIB" "w_hdl"
					( Origin gPackager )
				)
				( attribute "CDS_LMAN_SYM_OUTLINE" "-50,75,50,-75"
					( Origin gPackager )
				)
				( attribute "LOCATION" "R25W41"
					( Origin gFrontEnd )
				)
				( attribute "PACK_TYPE" "RCL_GP"
					( Origin gFrontEnd )
				)
				( attribute "PART_NUMBER" "64.12005.6DL"
					( Origin gFrontEnd )
				)
				( attribute "PHYS_PAGE" "149"
					( Origin gFrontEnd )
				)
				( attribute "ROT" "1"
					( Origin gFrontEnd )
				)
				( attribute "VALUE" "120R2F-GP"
					( Origin gFrontEnd )
				)
				( attribute "VER" "1"
					( Origin gFrontEnd )
				)
				( attribute "XY" "(-6150,3600)"
					( Origin gFrontEnd )
				)
				( attribute "CHIPS_PART_NAME" "120R2F-GP"
					( Origin gPackager )
				)
				( attribute "CDS_PART_NAME" "120R2F-GP_RCL_GP-120R2F-GP,64.A"
					( Origin gPackager )
				)
				( attribute "CDS_LOCATION" "R25W41"
					( Origin gPackager )
				)
				( attribute "CDS_SEC" "1"
					( Origin gPackager )
				)
				( attribute "SEC" "1"
					( Origin gPackager )
				)
				( objectStatus "R25W41" )
				( pin "\1\"
					( attribute "PN" "1"
						( Origin gPackager )
					)
					( objectStatus "R25W41.1" )
				)
				( pin "\2\"
					( attribute "PN" "2"
						( Origin gPackager )
					)
					( objectStatus "R25W41.2" )
				)
			)
			( gate "@baseboard_fab2_lib.baseboard_fab2(sch_1):page149_i198"
				( attribute "CDS_LIB" "w_hdl"
					( Origin gPackager )
				)
				( attribute "CDS_LMAN_SYM_OUTLINE" "-50,75,50,-75"
					( Origin gPackager )
				)
				( attribute "LOCATION" "R25W39"
					( Origin gFrontEnd )
				)
				( attribute "PACK_TYPE" "RCL_GP"
					( Origin gFrontEnd )
				)
				( attribute "PART_NUMBER" "64.12005.6DL"
					( Origin gFrontEnd )
				)
				( attribute "PHYS_PAGE" "149"
					( Origin gFrontEnd )
				)
				( attribute "ROT" "1"
					( Origin gFrontEnd )
				)
				( attribute "VALUE" "120R2F-GP"
					( Origin gFrontEnd )
				)
				( attribute "VER" "1"
					( Origin gFrontEnd )
				)
				( attribute "XY" "(-6150,3700)"
					( Origin gFrontEnd )
				)
				( attribute "CHIPS_PART_NAME" "120R2F-GP"
					( Origin gPackager )
				)
				( attribute "CDS_PART_NAME" "120R2F-GP_RCL_GP-120R2F-GP,64.A"
					( Origin gPackager )
				)
				( attribute "CDS_LOCATION" "R25W39"
					( Origin gPackager )
				)
				( attribute "CDS_SEC" "1"
					( Origin gPackager )
				)
				( attribute "SEC" "1"
					( Origin gPackager )
				)
				( objectStatus "R25W39" )
				( pin "\1\"
					( attribute "PN" "1"
						( Origin gPackager )
					)
					( objectStatus "R25W39.1" )
				)
				( pin "\2\"
					( attribute "PN" "2"
						( Origin gPackager )
					)
					( objectStatus "R25W39.2" )
				)
			)
			( gate "@baseboard_fab2_lib.baseboard_fab2(sch_1):page149_i197"
				( attribute "CDS_LIB" "w_hdl"
					( Origin gPackager )
				)
				( attribute "CDS_LMAN_SYM_OUTLINE" "-50,75,50,-75"
					( Origin gPackager )
				)
				( attribute "LOCATION" "R25W38"
					( Origin gFrontEnd )
				)
				( attribute "PACK_TYPE" "RCL_GP"
					( Origin gFrontEnd )
				)
				( attribute "PART_NUMBER" "64.12005.6DL"
					( Origin gFrontEnd )
				)
				( attribute "PHYS_PAGE" "149"
					( Origin gFrontEnd )
				)
				( attribute "ROT" "1"
					( Origin gFrontEnd )
				)
				( attribute "VALUE" "120R2F-GP"
					( Origin gFrontEnd )
				)
				( attribute "VER" "1"
					( Origin gFrontEnd )
				)
				( attribute "XY" "(-6150,3750)"
					( Origin gFrontEnd )
				)
				( attribute "CHIPS_PART_NAME" "120R2F-GP"
					( Origin gPackager )
				)
				( attribute "CDS_PART_NAME" "120R2F-GP_RCL_GP-120R2F-GP,64.A"
					( Origin gPackager )
				)
				( attribute "CDS_LOCATION" "R25W38"
					( Origin gPackager )
				)
				( attribute "CDS_SEC" "1"
					( Origin gPackager )
				)
				( attribute "SEC" "1"
					( Origin gPackager )
				)
				( objectStatus "R25W38" )
				( pin "\1\"
					( attribute "PN" "1"
						( Origin gPackager )
					)
					( objectStatus "R25W38.1" )
				)
				( pin "\2\"
					( attribute "PN" "2"
						( Origin gPackager )
					)
					( objectStatus "R25W38.2" )
				)
			)
			( gate "@baseboard_fab2_lib.baseboard_fab2(sch_1):page149_i196"
				( attribute "CDS_LIB" "w_hdl"
					( Origin gPackager )
				)
				( attribute "CDS_LMAN_SYM_OUTLINE" "-50,75,50,-75"
					( Origin gPackager )
				)
				( attribute "LOCATION" "R25W37"
					( Origin gFrontEnd )
				)
				( attribute "PACK_TYPE" "RCL_GP"
					( Origin gFrontEnd )
				)
				( attribute "PART_NUMBER" "64.12005.6DL"
					( Origin gFrontEnd )
				)
				( attribute "PHYS_PAGE" "149"
					( Origin gFrontEnd )
				)
				( attribute "ROT" "1"
					( Origin gFrontEnd )
				)
				( attribute "VALUE" "120R2F-GP"
					( Origin gFrontEnd )
				)
				( attribute "VER" "1"
					( Origin gFrontEnd )
				)
				( attribute "XY" "(-6150,3800)"
					( Origin gFrontEnd )
				)
				( attribute "CHIPS_PART_NAME" "120R2F-GP"
					( Origin gPackager )
				)
				( attribute "CDS_PART_NAME" "120R2F-GP_RCL_GP-120R2F-GP,64.A"
					( Origin gPackager )
				)
				( attribute "CDS_LOCATION" "R25W37"
					( Origin gPackager )
				)
				( attribute "CDS_SEC" "1"
					( Origin gPackager )
				)
				( attribute "SEC" "1"
					( Origin gPackager )
				)
				( objectStatus "R25W37" )
				( pin "\1\"
					( attribute "PN" "1"
						( Origin gPackager )
					)
					( objectStatus "R25W37.1" )
				)
				( pin "\2\"
					( attribute "PN" "2"
						( Origin gPackager )
					)
					( objectStatus "R25W37.2" )
				)
			)
			( gate "@baseboard_fab2_lib.baseboard_fab2(sch_1):page150_i45"
				( attribute "BOM_COST" "SM_CONTROLLER"
					( Origin gFrontEnd )
				)
				( attribute "CDS_LIB" "mstr_discrete"
					( Origin gPackager )
				)
				( attribute "CDS_LOCATION" "C25W29"
					( Origin gPackager )
				)
				( attribute "CDS_SEC" "1"
					( Origin gPackager )
				)
				( attribute "LOCATION" "C25W29"
					( Origin gFrontEnd )
				)
				( attribute "MATERIAL" "X6S"
					( Origin gFrontEnd )
				)
				( attribute "PACK_TYPE" "0805"
					( Origin gFrontEnd )
				)
				( attribute "PART_NUMBER" "C95333-007"
					( Origin gFrontEnd )
				)
				( attribute "PHYS_PAGE" "150"
					( Origin gFrontEnd )
				)
				( attribute "ROOM" "BMC"
					( Origin gFrontEnd )
				)
				( attribute "ROT" "0"
					( Origin gFrontEnd )
				)
				( attribute "SEC" "1"
					( Origin gFrontEnd )
				)
				( attribute "SEC_TYPE" "0805"
					( Origin gFrontEnd )
				)
				( attribute "TOLERANCE" "10%"
					( Origin gFrontEnd )
				)
				( attribute "VALUE" "10UF"
					( Origin gFrontEnd )
				)
				( attribute "VER" "1"
					( Origin gFrontEnd )
				)
				( attribute "VOLTAGE" "16V"
					( Units "uVoltage" "V" 1.000000)
					( Origin gFrontEnd )
				)
				( attribute "XY" "(-4075,4975)"
					( Origin gFrontEnd )
				)
				( attribute "CHIPS_PART_NAME" "CAP"
					( Origin gPackager )
				)
				( attribute "CDS_PART_NAME" "CAP_0805-10UF,16V,10%,X6S,C953A"
					( Origin gPackager )
				)
				( objectStatus "C25W29" )
				( pin "a"
					( attribute "PN" "1"
						( Origin gPackager )
					)
					( objectStatus "C25W29.1" )
				)
				( pin "b"
					( attribute "PN" "2"
						( Origin gPackager )
					)
					( objectStatus "C25W29.2" )
				)
			)
			( gate "@baseboard_fab2_lib.baseboard_fab2(sch_1):page150_i46"
				( attribute "BOM_COST" "SM_CONTROLLER"
					( Origin gFrontEnd )
				)
				( attribute "CDS_LIB" "mstr_discrete"
					( Origin gPackager )
				)
				( attribute "LOCATION" "C25W28"
					( Origin gFrontEnd )
				)
				( attribute "MATERIAL" "X6S"
					( Origin gFrontEnd )
				)
				( attribute "PACK_TYPE" "0402"
					( Origin gFrontEnd )
				)
				( attribute "PART_NUMBER" "D97712-004"
					( Origin gFrontEnd )
				)
				( attribute "PHYS_PAGE" "150"
					( Origin gFrontEnd )
				)
				( attribute "ROOM" "BMC"
					( Origin gFrontEnd )
				)
				( attribute "ROT" "0"
					( Origin gFrontEnd )
				)
				( attribute "TOLERANCE" "10%"
					( Origin gFrontEnd )
				)
				( attribute "VALUE" "1.0UF"
					( Origin gFrontEnd )
				)
				( attribute "VER" "1"
					( Origin gFrontEnd )
				)
				( attribute "VOLTAGE" "6.3V"
					( Units "uVoltage" "V" 1.000000)
					( Origin gFrontEnd )
				)
				( attribute "XY" "(-4475,4975)"
					( Origin gFrontEnd )
				)
				( attribute "CHIPS_PART_NAME" "CAP"
					( Origin gPackager )
				)
				( attribute "CDS_PART_NAME" "CAP_0402-1.0UF,6.3V,10%,X6S,D9A"
					( Origin gPackager )
				)
				( attribute "CDS_LOCATION" "C25W28"
					( Origin gPackager )
				)
				( attribute "CDS_SEC" "1"
					( Origin gPackager )
				)
				( attribute "SEC" "1"
					( Origin gPackager )
				)
				( objectStatus "C25W28" )
				( pin "a"
					( attribute "PN" "1"
						( Origin gPackager )
					)
					( objectStatus "C25W28.1" )
				)
				( pin "b"
					( attribute "PN" "2"
						( Origin gPackager )
					)
					( objectStatus "C25W28.2" )
				)
			)
			( gate "@baseboard_fab2_lib.baseboard_fab2(sch_1):page150_i48"
				( attribute "BOM_COST" "SM_CONTROLLER"
					( Origin gFrontEnd )
				)
				( attribute "CDS_LIB" "mstr_discrete"
					( Origin gPackager )
				)
				( attribute "LOCATION" "C25W27"
					( Origin gFrontEnd )
				)
				( attribute "MATERIAL" "X6S"
					( Origin gFrontEnd )
				)
				( attribute "PACK_TYPE" "0402"
					( Origin gFrontEnd )
				)
				( attribute "PART_NUMBER" "D97712-004"
					( Origin gFrontEnd )
				)
				( attribute "PHYS_PAGE" "150"
					( Origin gFrontEnd )
				)
				( attribute "ROOM" "BMC"
					( Origin gFrontEnd )
				)
				( attribute "ROT" "0"
					( Origin gFrontEnd )
				)
				( attribute "TOLERANCE" "10%"
					( Origin gFrontEnd )
				)
				( attribute "VALUE" "1.0UF"
					( Origin gFrontEnd )
				)
				( attribute "VER" "1"
					( Origin gFrontEnd )
				)
				( attribute "VOLTAGE" "6.3V"
					( Units "uVoltage" "V" 1.000000)
					( Origin gFrontEnd )
				)
				( attribute "XY" "(-4875,4975)"
					( Origin gFrontEnd )
				)
				( attribute "CHIPS_PART_NAME" "CAP"
					( Origin gPackager )
				)
				( attribute "CDS_PART_NAME" "CAP_0402-1.0UF,6.3V,10%,X6S,D9A"
					( Origin gPackager )
				)
				( attribute "CDS_LOCATION" "C25W27"
					( Origin gPackager )
				)
				( attribute "CDS_SEC" "1"
					( Origin gPackager )
				)
				( attribute "SEC" "1"
					( Origin gPackager )
				)
				( objectStatus "C25W27" )
				( pin "a"
					( attribute "PN" "1"
						( Origin gPackager )
					)
					( objectStatus "C25W27.1" )
				)
				( pin "b"
					( attribute "PN" "2"
						( Origin gPackager )
					)
					( objectStatus "C25W27.2" )
				)
			)
			( gate "@baseboard_fab2_lib.baseboard_fab2(sch_1):page150_i50"
				( attribute "CDS_LIB" "w_hdl"
					( Origin gPackager )
				)
				( attribute "CDS_LMAN_SYM_OUTLINE" "-50,25,50,-25"
					( Origin gPackager )
				)
				( attribute "LOCATION" "C25W36"
					( Origin gFrontEnd )
				)
				( attribute "PACK_TYPE" "SMD-BCG"
					( Origin gFrontEnd )
				)
				( attribute "PART_NUMBER" "78.47523.5BL"
					( Origin gFrontEnd )
				)
				( attribute "PHYS_PAGE" "150"
					( Origin gFrontEnd )
				)
				( attribute "ROT" "0"
					( Origin gFrontEnd )
				)
				( attribute "VALUE" "SC4D7U10V3KX-GP"
					( Origin gFrontEnd )
				)
				( attribute "VER" "1"
					( Origin gFrontEnd )
				)
				( attribute "XY" "(-3100,3600)"
					( Origin gFrontEnd )
				)
				( attribute "CHIPS_PART_NAME" "SC4D7U10V3KX-GP"
					( Origin gPackager )
				)
				( attribute "CDS_PART_NAME" "SC4D7U10V3KX-GP_SMD-BCG-SC4D7UA"
					( Origin gPackager )
				)
				( attribute "CDS_LOCATION" "C25W36"
					( Origin gPackager )
				)
				( attribute "CDS_SEC" "1"
					( Origin gPackager )
				)
				( attribute "SEC" "1"
					( Origin gPackager )
				)
				( objectStatus "C25W36" )
				( pin "\1\"
					( attribute "PN" "1"
						( Origin gPackager )
					)
					( objectStatus "C25W36.1" )
				)
				( pin "\2\"
					( attribute "PN" "2"
						( Origin gPackager )
					)
					( objectStatus "C25W36.2" )
				)
			)
			( gate "@baseboard_fab2_lib.baseboard_fab2(sch_1):page150_i51"
				( attribute "BOM_COST" "SM_CONTROLLER"
					( Origin gFrontEnd )
				)
				( attribute "CDS_LIB" "mstr_discrete"
					( Origin gPackager )
				)
				( attribute "LOCATION" "C25W35"
					( Origin gFrontEnd )
				)
				( attribute "MATERIAL" "X6S"
					( Origin gFrontEnd )
				)
				( attribute "PACK_TYPE" "0402"
					( Origin gFrontEnd )
				)
				( attribute "PART_NUMBER" "D97712-004"
					( Origin gFrontEnd )
				)
				( attribute "PHYS_PAGE" "150"
					( Origin gFrontEnd )
				)
				( attribute "ROOM" "BMC"
					( Origin gFrontEnd )
				)
				( attribute "ROT" "0"
					( Origin gFrontEnd )
				)
				( attribute "TOLERANCE" "10%"
					( Origin gFrontEnd )
				)
				( attribute "VALUE" "1.0UF"
					( Origin gFrontEnd )
				)
				( attribute "VER" "1"
					( Origin gFrontEnd )
				)
				( attribute "VOLTAGE" "6.3V"
					( Units "uVoltage" "V" 1.000000)
					( Origin gFrontEnd )
				)
				( attribute "XY" "(-3450,3600)"
					( Origin gFrontEnd )
				)
				( attribute "CHIPS_PART_NAME" "CAP"
					( Origin gPackager )
				)
				( attribute "CDS_PART_NAME" "CAP_0402-1.0UF,6.3V,10%,X6S,D9A"
					( Origin gPackager )
				)
				( attribute "CDS_LOCATION" "C25W35"
					( Origin gPackager )
				)
				( attribute "CDS_SEC" "1"
					( Origin gPackager )
				)
				( attribute "SEC" "1"
					( Origin gPackager )
				)
				( objectStatus "C25W35" )
				( pin "a"
					( attribute "PN" "1"
						( Origin gPackager )
					)
					( objectStatus "C25W35.1" )
				)
				( pin "b"
					( attribute "PN" "2"
						( Origin gPackager )
					)
					( objectStatus "C25W35.2" )
				)
			)
			( gate "@baseboard_fab2_lib.baseboard_fab2(sch_1):page150_i53"
				( attribute "CDS_LIB" "w_hdl"
					( Origin gPackager )
				)
				( attribute "CDS_LMAN_SYM_OUTLINE" "-50,25,50,-25"
					( Origin gPackager )
				)
				( attribute "LOCATION" "C25W34"
					( Origin gFrontEnd )
				)
				( attribute "PACK_TYPE" "SMD-BCG"
					( Origin gFrontEnd )
				)
				( attribute "PART_NUMBER" "78.10421.2FL"
					( Origin gFrontEnd )
				)
				( attribute "PHYS_PAGE" "150"
					( Origin gFrontEnd )
				)
				( attribute "ROT" "0"
					( Origin gFrontEnd )
				)
				( attribute "VALUE" "SCD1U16V2KX-3GP"
					( Origin gFrontEnd )
				)
				( attribute "VER" "1"
					( Origin gFrontEnd )
				)
				( attribute "XY" "(-3800,3575)"
					( Origin gFrontEnd )
				)
				( attribute "CHIPS_PART_NAME" "SCD1U16V2KX-3GP"
					( Origin gPackager )
				)
				( attribute "CDS_PART_NAME" "SCD1U16V2KX-3GP_SMD-BCG-SCD1U1A"
					( Origin gPackager )
				)
				( attribute "CDS_LOCATION" "C25W34"
					( Origin gPackager )
				)
				( attribute "CDS_SEC" "1"
					( Origin gPackager )
				)
				( attribute "SEC" "1"
					( Origin gPackager )
				)
				( objectStatus "C25W34" )
				( pin "\1\"
					( attribute "PN" "1"
						( Origin gPackager )
					)
					( objectStatus "C25W34.1" )
				)
				( pin "\2\"
					( attribute "PN" "2"
						( Origin gPackager )
					)
					( objectStatus "C25W34.2" )
				)
			)
			( gate "@baseboard_fab2_lib.baseboard_fab2(sch_1):page249_i33"
				( attribute "CDS_LIB" "w_hdl"
					( Origin gPackager )
				)
				( attribute "CDS_LMAN_SYM_OUTLINE" "-50,75,50,-75"
					( Origin gPackager )
				)
				( attribute "LOCATION" "R3W5"
					( Origin gFrontEnd )
				)
				( attribute "PACK_TYPE" "SMD-RG"
					( Origin gFrontEnd )
				)
				( attribute "PART_NUMBER" "64.82525.6DL"
					( Origin gFrontEnd )
				)
				( attribute "PHYS_PAGE" "249"
					( Origin gFrontEnd )
				)
				( attribute "ROT" "0"
					( Origin gFrontEnd )
				)
				( attribute "VALUE" "82K5R2F-GP"
					( Origin gFrontEnd )
				)
				( attribute "VER" "1"
					( Origin gFrontEnd )
				)
				( attribute "XY" "(-4550,4400)"
					( Origin gFrontEnd )
				)
				( attribute "CHIPS_PART_NAME" "82K5R2F-GP"
					( Origin gPackager )
				)
				( attribute "CDS_PART_NAME" "82K5R2F-GP_SMD-RG-82K5R2F-GP,6A"
					( Origin gPackager )
				)
				( attribute "CDS_LOCATION" "R3W5"
					( Origin gPackager )
				)
				( attribute "CDS_SEC" "1"
					( Origin gPackager )
				)
				( attribute "SEC" "1"
					( Origin gPackager )
				)
				( objectStatus "R3W5" )
				( pin "\1\"
					( attribute "PN" "1"
						( Origin gPackager )
					)
					( objectStatus "R3W5.1" )
				)
				( pin "\2\"
					( attribute "PN" "2"
						( Origin gPackager )
					)
					( objectStatus "R3W5.2" )
				)
			)
			( gate "@baseboard_fab2_lib.baseboard_fab2(sch_1):page250_i38"
				( attribute "CHIPS_PART_NAME" "TTL1G07_A"
					( Origin gPackager )
				)
			)
			( gate "@baseboard_fab2_lib.baseboard_fab2(sch_1):page155_i195"
				( attribute "BOM_COST" "IO_SLOT"
					( Origin gFrontEnd )
				)
				( attribute "CDS_LIB" "mstr_discrete"
					( Origin gPackager )
				)
				( attribute "LOCATION" "R9A5"
					( Origin gFrontEnd )
				)
				( attribute "MATERIAL" "CHIP"
					( Origin gFrontEnd )
				)
				( attribute "PACK_TYPE" "0402"
					( Origin gFrontEnd )
				)
				( attribute "PART_NUMBER" "G21796-107"
					( Origin gFrontEnd )
				)
				( attribute "PHYS_PAGE" "155"
					( Origin gFrontEnd )
				)
				( attribute "ROOM" "IO_SLOT"
					( Origin gFrontEnd )
				)
				( attribute "ROT" "2"
					( Origin gFrontEnd )
				)
				( attribute "TOLERANCE" "1%"
					( Origin gFrontEnd )
				)
				( attribute "VALUE" "15.0K"
					( Origin gFrontEnd )
				)
				( attribute "VER" "2"
					( Origin gFrontEnd )
				)
				( attribute "WATTAGE" "1/16W"
					( Origin gFrontEnd )
				)
				( attribute "XY" "(-3325,1725)"
					( Origin gFrontEnd )
				)
				( attribute "CHIPS_PART_NAME" "RES"
					( Origin gPackager )
				)
				( attribute "CDS_PART_NAME" "RES_0402-15.0K,1%,1/16W,CHIP,GA"
					( Origin gPackager )
				)
				( attribute "CDS_LOCATION" "R9A5"
					( Origin gPackager )
				)
				( attribute "CDS_SEC" "1"
					( Origin gPackager )
				)
				( attribute "SEC" "1"
					( Origin gPackager )
				)
				( objectStatus "R9A5" )
				( pin "a"
					( attribute "PN" "1"
						( Origin gPackager )
					)
					( objectStatus "R9A5.1" )
				)
				( pin "b"
					( attribute "PN" "2"
						( Origin gPackager )
					)
					( objectStatus "R9A5.2" )
				)
			)
			( gate "@baseboard_fab2_lib.baseboard_fab2(sch_1):page150_i82"
				( attribute "BOM_COST" "SM_CONTROLLER"
					( Origin gFrontEnd )
				)
				( attribute "CDS_LIB" "mstr_discrete"
					( Origin gPackager )
				)
				( attribute "LOCATION" "C25W40"
					( Origin gFrontEnd )
				)
				( attribute "MATERIAL" "X6S"
					( Origin gFrontEnd )
				)
				( attribute "PACK_TYPE" "0402"
					( Origin gFrontEnd )
				)
				( attribute "PART_NUMBER" "D97712-004"
					( Origin gFrontEnd )
				)
				( attribute "PHYS_PAGE" "150"
					( Origin gFrontEnd )
				)
				( attribute "ROOM" "BMC"
					( Origin gFrontEnd )
				)
				( attribute "ROT" "0"
					( Origin gFrontEnd )
				)
				( attribute "TOLERANCE" "10%"
					( Origin gFrontEnd )
				)
				( attribute "VALUE" "1.0UF"
					( Origin gFrontEnd )
				)
				( attribute "VER" "1"
					( Origin gFrontEnd )
				)
				( attribute "VOLTAGE" "6.3V"
					( Units "uVoltage" "V" 1.000000)
					( Origin gFrontEnd )
				)
				( attribute "XY" "(-5675,2475)"
					( Origin gFrontEnd )
				)
				( attribute "CHIPS_PART_NAME" "CAP"
					( Origin gPackager )
				)
				( attribute "CDS_PART_NAME" "CAP_0402-1.0UF,6.3V,10%,X6S,D9A"
					( Origin gPackager )
				)
				( attribute "CDS_LOCATION" "C25W40"
					( Origin gPackager )
				)
				( attribute "CDS_SEC" "1"
					( Origin gPackager )
				)
				( attribute "SEC" "1"
					( Origin gPackager )
				)
				( objectStatus "C25W40" )
				( pin "a"
					( attribute "PN" "1"
						( Origin gPackager )
					)
					( objectStatus "C25W40.1" )
				)
				( pin "b"
					( attribute "PN" "2"
						( Origin gPackager )
					)
					( objectStatus "C25W40.2" )
				)
			)
			( gate "@baseboard_fab2_lib.baseboard_fab2(sch_1):page145_i22"
				( attribute "BOM_COST" "SM_CONTROLLER"
					( Origin gFrontEnd )
				)
				( attribute "CDS_LIB" "mstr_discrete"
					( Origin gPackager )
				)
				( attribute "CDS_LOCATION" "R9F20"
					( Origin gPackager )
				)
				( attribute "CDS_SEC" "1"
					( Origin gPackager )
				)
				( attribute "LOCATION" "R9F20"
					( Origin gFrontEnd )
				)
				( attribute "MATERIAL" "EMPTY"
					( Origin gFrontEnd )
				)
				( attribute "PACK_TYPE" "0402"
					( Origin gFrontEnd )
				)
				( attribute "PART_NUMBER" "G21796-340"
					( Origin gFrontEnd )
				)
				( attribute "PHYS_PAGE" "145"
					( Origin gFrontEnd )
				)
				( attribute "ROOM" "BMC"
					( Origin gFrontEnd )
				)
				( attribute "ROT" "0"
					( Origin gFrontEnd )
				)
				( attribute "SEC" "1"
					( Origin gFrontEnd )
				)
				( attribute "SEC_TYPE" "0402"
					( Origin gFrontEnd )
				)
				( attribute "TOLERANCE" "1%"
					( Origin gFrontEnd )
				)
				( attribute "VALUE" "348"
					( Origin gFrontEnd )
				)
				( attribute "VER" "2"
					( Origin gFrontEnd )
				)
				( attribute "WATTAGE" "1/16W"
					( Origin gFrontEnd )
				)
				( attribute "XY" "(-7475,-3575)"
					( Origin gFrontEnd )
				)
				( attribute "CHIPS_PART_NAME" "RES"
					( Origin gPackager )
				)
				( attribute "CDS_PART_NAME" "RES_0402-348,1%,1/16W,EMPTY,G2A"
					( Origin gPackager )
				)
				( objectStatus "R9F20" )
				( pin "a"
					( attribute "PN" "1"
						( Origin gPackager )
					)
					( objectStatus "R9F20.1" )
				)
				( pin "b"
					( attribute "PN" "2"
						( Origin gPackager )
					)
					( objectStatus "R9F20.2" )
				)
			)
			( gate "@baseboard_fab2_lib.baseboard_fab2(sch_1):page146_i64"
				( attribute "BOM_COST" "SM_CONTROLLER"
					( Origin gFrontEnd )
				)
				( attribute "CDS_LIB" "mstr_discrete"
					( Origin gPackager )
				)
				( attribute "CDS_LOCATION" "R25W70"
					( Origin gPackager )
				)
				( attribute "CDS_SEC" "1"
					( Origin gPackager )
				)
				( attribute "LOCATION" "R25W70"
					( Origin gFrontEnd )
				)
				( attribute "MATERIAL" "CHIP"
					( Origin gFrontEnd )
				)
				( attribute "PACK_TYPE" "0402"
					( Origin gFrontEnd )
				)
				( attribute "PART_NUMBER" "G21796-074"
					( Origin gFrontEnd )
				)
				( attribute "PHYS_PAGE" "146"
					( Origin gFrontEnd )
				)
				( attribute "ROOM" "BMC"
					( Origin gFrontEnd )
				)
				( attribute "ROT" "0"
					( Origin gFrontEnd )
				)
				( attribute "SEC" "1"
					( Origin gFrontEnd )
				)
				( attribute "SEC_TYPE" "0402"
					( Origin gFrontEnd )
				)
				( attribute "TOLERANCE" "1%"
					( Origin gFrontEnd )
				)
				( attribute "VALUE" "33.2"
					( Origin gFrontEnd )
				)
				( attribute "VER" "1"
					( Origin gFrontEnd )
				)
				( attribute "WATTAGE" "1/16W"
					( Origin gFrontEnd )
				)
				( attribute "XY" "(-1275,1525)"
					( Origin gFrontEnd )
				)
				( attribute "CHIPS_PART_NAME" "RES"
					( Origin gPackager )
				)
				( attribute "CDS_PART_NAME" "RES_0402-33.2,1%,1/16W,CHIP,G2A"
					( Origin gPackager )
				)
				( objectStatus "R25W70" )
				( pin "a"
					( attribute "PN" "1"
						( Origin gPackager )
					)
					( objectStatus "R25W70.1" )
				)
				( pin "b"
					( attribute "PN" "2"
						( Origin gPackager )
					)
					( objectStatus "R25W70.2" )
				)
			)
			( gate "@baseboard_fab2_lib.baseboard_fab2(sch_1):page247_i68"
				( attribute "CDS_LIB" "mstr_discrete"
					( Origin gPackager )
				)
				( attribute "LOCATION" "R6W12"
					( Origin gFrontEnd )
				)
				( attribute "MATERIAL" "EMPTY"
					( Origin gFrontEnd )
				)
				( attribute "NO_XNET_CONNECTION" "1"
					( Origin gFrontEnd )
				)
				( attribute "PACK_TYPE" "0402"
					( Origin gFrontEnd )
				)
				( attribute "PART_NUMBER" "G21796-072"
					( Origin gFrontEnd )
				)
				( attribute "PHYS_PAGE" "247"
					( Origin gFrontEnd )
				)
				( attribute "ROOM" "HOT_SWAP"
					( Origin gFrontEnd )
				)
				( attribute "ROT" "0"
					( Origin gFrontEnd )
				)
				( attribute "TOLERANCE" "1%"
					( Origin gFrontEnd )
				)
				( attribute "VALUE" "4.75K"
					( Origin gFrontEnd )
				)
				( attribute "VER" "2"
					( Origin gFrontEnd )
				)
				( attribute "WATTAGE" "1/16W"
					( Origin gFrontEnd )
				)
				( attribute "XY" "(-6850,3800)"
					( Origin gFrontEnd )
				)
				( attribute "CHIPS_PART_NAME" "RES"
					( Origin gPackager )
				)
				( attribute "CDS_PART_NAME" "RES_0402-4.75K,1%,1/16W,EMPTY,A"
					( Origin gPackager )
				)
				( attribute "CDS_LOCATION" "R6W12"
					( Origin gPackager )
				)
				( attribute "CDS_SEC" "1"
					( Origin gPackager )
				)
				( attribute "SEC" "1"
					( Origin gPackager )
				)
				( objectStatus "R6W12" )
				( pin "a"
					( attribute "PN" "1"
						( Origin gPackager )
					)
					( objectStatus "R6W12.1" )
				)
				( pin "b"
					( attribute "PN" "2"
						( Origin gPackager )
					)
					( objectStatus "R6W12.2" )
				)
			)
			( gate "@baseboard_fab2_lib.baseboard_fab2(sch_1):page247_i67"
				( attribute "CDS_LIB" "mstr_discrete"
					( Origin gPackager )
				)
				( attribute "LOCATION" "R6W11"
					( Origin gFrontEnd )
				)
				( attribute "MATERIAL" "EMPTY"
					( Origin gFrontEnd )
				)
				( attribute "NO_XNET_CONNECTION" "1"
					( Origin gFrontEnd )
				)
				( attribute "PACK_TYPE" "0402"
					( Origin gFrontEnd )
				)
				( attribute "PART_NUMBER" "G21796-072"
					( Origin gFrontEnd )
				)
				( attribute "PHYS_PAGE" "247"
					( Origin gFrontEnd )
				)
				( attribute "ROOM" "HOT_SWAP"
					( Origin gFrontEnd )
				)
				( attribute "ROT" "0"
					( Origin gFrontEnd )
				)
				( attribute "TOLERANCE" "1%"
					( Origin gFrontEnd )
				)
				( attribute "VALUE" "4.75K"
					( Origin gFrontEnd )
				)
				( attribute "VER" "2"
					( Origin gFrontEnd )
				)
				( attribute "WATTAGE" "1/16W"
					( Origin gFrontEnd )
				)
				( attribute "XY" "(-7150,3800)"
					( Origin gFrontEnd )
				)
				( attribute "CHIPS_PART_NAME" "RES"
					( Origin gPackager )
				)
				( attribute "CDS_PART_NAME" "RES_0402-4.75K,1%,1/16W,EMPTY,A"
					( Origin gPackager )
				)
				( attribute "CDS_LOCATION" "R6W11"
					( Origin gPackager )
				)
				( attribute "CDS_SEC" "1"
					( Origin gPackager )
				)
				( attribute "SEC" "1"
					( Origin gPackager )
				)
				( objectStatus "R6W11" )
				( pin "a"
					( attribute "PN" "1"
						( Origin gPackager )
					)
					( objectStatus "R6W11.1" )
				)
				( pin "b"
					( attribute "PN" "2"
						( Origin gPackager )
					)
					( objectStatus "R6W11.2" )
				)
			)
			( gate "@baseboard_fab2_lib.baseboard_fab2(sch_1):page149_i71"
				( attribute "CDS_LIB" "mstr_discrete"
					( Origin gPackager )
				)
				( attribute "LOCATION" "C25W1"
					( Origin gFrontEnd )
				)
				( attribute "MATERIAL" "X6S"
					( Origin gFrontEnd )
				)
				( attribute "PACK_TYPE" "0402"
					( Origin gFrontEnd )
				)
				( attribute "PART_NUMBER" "D97712-011"
					( Origin gFrontEnd )
				)
				( attribute "PHYS_PAGE" "149"
					( Origin gFrontEnd )
				)
				( attribute "ROOM" "VDDQ_KLM_PWR_VR"
					( Origin gFrontEnd )
				)
				( attribute "ROT" "1"
					( Origin gFrontEnd )
				)
				( attribute "TOLERANCE" "10%"
					( Origin gFrontEnd )
				)
				( attribute "VALUE" "1.0UF"
					( Origin gFrontEnd )
				)
				( attribute "VER" "1"
					( Origin gFrontEnd )
				)
				( attribute "VOLTAGE" "16V"
					( Units "uVoltage" "V" 1.000000)
					( Origin gFrontEnd )
				)
				( attribute "XY" "(-5300,4300)"
					( Origin gFrontEnd )
				)
				( attribute "CHIPS_PART_NAME" "CAP"
					( Origin gPackager )
				)
				( attribute "CDS_PART_NAME" "CAP_0402-1.0UF,16V,10%,X6S,D97A"
					( Origin gPackager )
				)
				( attribute "CDS_LOCATION" "C25W1"
					( Origin gPackager )
				)
				( attribute "CDS_SEC" "1"
					( Origin gPackager )
				)
				( attribute "SEC" "1"
					( Origin gPackager )
				)
				( objectStatus "C25W1" )
				( pin "a"
					( attribute "PN" "1"
						( Origin gPackager )
					)
					( objectStatus "C25W1.1" )
				)
				( pin "b"
					( attribute "PN" "2"
						( Origin gPackager )
					)
					( objectStatus "C25W1.2" )
				)
			)
			( gate "@baseboard_fab2_lib.baseboard_fab2(sch_1):page149_i69"
				( attribute "CDS_LIB" "w_hdl"
					( Origin gPackager )
				)
				( attribute "CDS_LMAN_SYM_OUTLINE" "-50,25,50,-25"
					( Origin gPackager )
				)
				( attribute "LOCATION" "C25W19"
					( Origin gFrontEnd )
				)
				( attribute "PACK_TYPE" "SMD-BCG"
					( Origin gFrontEnd )
				)
				( attribute "PART_NUMBER" "78.47523.5BL"
					( Origin gFrontEnd )
				)
				( attribute "PHYS_PAGE" "149"
					( Origin gFrontEnd )
				)
				( attribute "ROT" "0"
					( Origin gFrontEnd )
				)
				( attribute "VALUE" "SC4D7U10V3KX-GP"
					( Origin gFrontEnd )
				)
				( attribute "VER" "1"
					( Origin gFrontEnd )
				)
				( attribute "XY" "(-4950,4700)"
					( Origin gFrontEnd )
				)
				( attribute "CHIPS_PART_NAME" "SC4D7U10V3KX-GP"
					( Origin gPackager )
				)
				( attribute "CDS_PART_NAME" "SC4D7U10V3KX-GP_SMD-BCG-SC4D7UA"
					( Origin gPackager )
				)
				( attribute "CDS_LOCATION" "C25W19"
					( Origin gPackager )
				)
				( attribute "CDS_SEC" "1"
					( Origin gPackager )
				)
				( attribute "SEC" "1"
					( Origin gPackager )
				)
				( objectStatus "C25W19" )
				( pin "\1\"
					( attribute "PN" "1"
						( Origin gPackager )
					)
					( objectStatus "C25W19.1" )
				)
				( pin "\2\"
					( attribute "PN" "2"
						( Origin gPackager )
					)
					( objectStatus "C25W19.2" )
				)
			)
			( gate "@baseboard_fab2_lib.baseboard_fab2(sch_1):page149_i68"
				( attribute "CDS_LIB" "w_hdl"
					( Origin gPackager )
				)
				( attribute "CDS_LMAN_SYM_OUTLINE" "-50,25,50,-25"
					( Origin gPackager )
				)
				( attribute "LOCATION" "C25W18"
					( Origin gFrontEnd )
				)
				( attribute "PACK_TYPE" "SMD-BCG"
					( Origin gFrontEnd )
				)
				( attribute "PART_NUMBER" "78.10521.5BL"
					( Origin gFrontEnd )
				)
				( attribute "PHYS_PAGE" "149"
					( Origin gFrontEnd )
				)
				( attribute "ROT" "0"
					( Origin gFrontEnd )
				)
				( attribute "VALUE" "SC1U16V3KX-2GP"
					( Origin gFrontEnd )
				)
				( attribute "VER" "1"
					( Origin gFrontEnd )
				)
				( attribute "XY" "(-4775,4700)"
					( Origin gFrontEnd )
				)
				( attribute "CHIPS_PART_NAME" "SC1U16V3KX-2GP"
					( Origin gPackager )
				)
				( attribute "CDS_PART_NAME" "SC1U16V3KX-2GP_SMD-BCG-SC1U16VA"
					( Origin gPackager )
				)
				( attribute "CDS_LOCATION" "C25W18"
					( Origin gPackager )
				)
				( attribute "CDS_SEC" "1"
					( Origin gPackager )
				)
				( attribute "SEC" "1"
					( Origin gPackager )
				)
				( objectStatus "C25W18" )
				( pin "\1\"
					( attribute "PN" "1"
						( Origin gPackager )
					)
					( objectStatus "C25W18.1" )
				)
				( pin "\2\"
					( attribute "PN" "2"
						( Origin gPackager )
					)
					( objectStatus "C25W18.2" )
				)
			)
			( gate "@baseboard_fab2_lib.baseboard_fab2(sch_1):page149_i65"
				( attribute "BOM_COST" "SM_CONTROLLER"
					( Origin gFrontEnd )
				)
				( attribute "CDS_LIB" "mstr_discrete"
					( Origin gPackager )
				)
				( attribute "LOCATION" "C25W13"
					( Origin gFrontEnd )
				)
				( attribute "MATERIAL" "X7R"
					( Origin gFrontEnd )
				)
				( attribute "PACK_TYPE" "0402LF"
					( Origin gFrontEnd )
				)
				( attribute "PART_NUMBER" "A36096-030"
					( Origin gFrontEnd )
				)
				( attribute "PHYS_PAGE" "149"
					( Origin gFrontEnd )
				)
				( attribute "ROOM" "BMC"
					( Origin gFrontEnd )
				)
				( attribute "ROT" "0"
					( Origin gFrontEnd )
				)
				( attribute "TOLERANCE" "10%"
					( Origin gFrontEnd )
				)
				( attribute "VALUE" "0.1UF"
					( Origin gFrontEnd )
				)
				( attribute "VER" "1"
					( Origin gFrontEnd )
				)
				( attribute "VOLTAGE" "16V"
					( Units "uVoltage" "V" 1.000000)
					( Origin gFrontEnd )
				)
				( attribute "XY" "(-3800,2475)"
					( Origin gFrontEnd )
				)
				( attribute "CHIPS_PART_NAME" "CAP"
					( Origin gPackager )
				)
				( attribute "CDS_PART_NAME" "CAP_0402LF-0.1UF,16V,10%,X7R,AA"
					( Origin gPackager )
				)
				( attribute "CDS_LOCATION" "C25W13"
					( Origin gPackager )
				)
				( attribute "CDS_SEC" "1"
					( Origin gPackager )
				)
				( attribute "SEC" "1"
					( Origin gPackager )
				)
				( objectStatus "C25W13" )
				( pin "a"
					( attribute "PN" "1"
						( Origin gPackager )
					)
					( objectStatus "C25W13.1" )
				)
				( pin "b"
					( attribute "PN" "2"
						( Origin gPackager )
					)
					( objectStatus "C25W13.2" )
				)
			)
			( gate "@baseboard_fab2_lib.baseboard_fab2(sch_1):page149_i55"
				( attribute "BOM_COST" "SM_MEM"
					( Origin gFrontEnd )
				)
				( attribute "CDS_LIB" "mstr_discrete"
					( Origin gPackager )
				)
				( attribute "LOCATION" "R25W117"
					( Origin gFrontEnd )
				)
				( attribute "MATERIAL" "CHIP"
					( Origin gFrontEnd )
				)
				( attribute "PACK_TYPE" "0402"
					( Origin gFrontEnd )
				)
				( attribute "PART_NUMBER" "G21796-294"
					( Origin gFrontEnd )
				)
				( attribute "PHYS_PAGE" "149"
					( Origin gFrontEnd )
				)
				( attribute "ROOM" "BMC_MEMORY"
					( Origin gFrontEnd )
				)
				( attribute "ROT" "0"
					( Origin gFrontEnd )
				)
				( attribute "TOLERANCE" "1.0%"
					( Origin gFrontEnd )
				)
				( attribute "VALUE" "240"
					( Origin gFrontEnd )
				)
				( attribute "VER" "2"
					( Origin gFrontEnd )
				)
				( attribute "WATTAGE" "1/16W"
					( Origin gFrontEnd )
				)
				( attribute "XY" "(-3550,2425)"
					( Origin gFrontEnd )
				)
				( attribute "CHIPS_PART_NAME" "RES"
					( Origin gPackager )
				)
				( attribute "CDS_PART_NAME" "RES_0402-240,1.0%,1/16W,CHIP,GA"
					( Origin gPackager )
				)
				( attribute "CDS_LOCATION" "R25W117"
					( Origin gPackager )
				)
				( attribute "CDS_SEC" "1"
					( Origin gPackager )
				)
				( attribute "SEC" "1"
					( Origin gPackager )
				)
				( objectStatus "R25W117" )
				( pin "a"
					( attribute "PN" "1"
						( Origin gPackager )
					)
					( objectStatus "R25W117.1" )
				)
				( pin "b"
					( attribute "PN" "2"
						( Origin gPackager )
					)
					( objectStatus "R25W117.2" )
				)
			)
			( gate "@baseboard_fab2_lib.baseboard_fab2(sch_1):page149_i44"
				( attribute "CDS_LIB" "w_hdl"
					( Origin gPackager )
				)
				( attribute "CDS_LMAN_SYM_OUTLINE" "-50,25,50,-25"
					( Origin gPackager )
				)
				( attribute "LOCATION" "C25W14"
					( Origin gFrontEnd )
				)
				( attribute "PACK_TYPE" "SMD-BCG"
					( Origin gFrontEnd )
				)
				( attribute "PART_NUMBER" "78.10421.2FL"
					( Origin gFrontEnd )
				)
				( attribute "PHYS_PAGE" "149"
					( Origin gFrontEnd )
				)
				( attribute "ROT" "0"
					( Origin gFrontEnd )
				)
				( attribute "VALUE" "SCD1U16V2KX-3GP"
					( Origin gFrontEnd )
				)
				( attribute "VER" "1"
					( Origin gFrontEnd )
				)
				( attribute "XY" "(-3400,3075)"
					( Origin gFrontEnd )
				)
				( attribute "CHIPS_PART_NAME" "SCD1U16V2KX-3GP"
					( Origin gPackager )
				)
				( attribute "CDS_PART_NAME" "SCD1U16V2KX-3GP_SMD-BCG-SCD1U1A"
					( Origin gPackager )
				)
				( attribute "CDS_LOCATION" "C25W14"
					( Origin gPackager )
				)
				( attribute "CDS_SEC" "1"
					( Origin gPackager )
				)
				( attribute "SEC" "1"
					( Origin gPackager )
				)
				( objectStatus "C25W14" )
				( pin "\1\"
					( attribute "PN" "1"
						( Origin gPackager )
					)
					( objectStatus "C25W14.1" )
				)
				( pin "\2\"
					( attribute "PN" "2"
						( Origin gPackager )
					)
					( objectStatus "C25W14.2" )
				)
			)
			( gate "@baseboard_fab2_lib.baseboard_fab2(sch_1):page149_i159"
				( attribute "BOM_COST" "SM_MEM"
					( Origin gFrontEnd )
				)
				( attribute "CDS_LIB" "mstr_discrete"
					( Origin gPackager )
				)
				( attribute "CDS_LOCATION" "C25W11"
					( Origin gPackager )
				)
				( attribute "CDS_SEC" "1"
					( Origin gPackager )
				)
				( attribute "LOCATION" "C25W11"
					( Origin gFrontEnd )
				)
				( attribute "MATERIAL" "X7R"
					( Origin gFrontEnd )
				)
				( attribute "PACK_TYPE" "0402LF"
					( Origin gFrontEnd )
				)
				( attribute "PART_NUMBER" "A36096-045"
					( Origin gFrontEnd )
				)
				( attribute "PHYS_PAGE" "149"
					( Origin gFrontEnd )
				)
				( attribute "ROOM" "BMC_MEMORY"
					( Origin gFrontEnd )
				)
				( attribute "ROT" "0"
					( Origin gFrontEnd )
				)
				( attribute "SEC" "1"
					( Origin gFrontEnd )
				)
				( attribute "SEC_TYPE" "0402LF"
					( Origin gFrontEnd )
				)
				( attribute "TOLERANCE" "10%"
					( Origin gFrontEnd )
				)
				( attribute "VALUE" "0.01UF"
					( Origin gFrontEnd )
				)
				( attribute "VER" "1"
					( Origin gFrontEnd )
				)
				( attribute "VOLTAGE" "25V"
					( Units "uVoltage" "V" 1.000000)
					( Origin gFrontEnd )
				)
				( attribute "XY" "(-6775,625)"
					( Origin gFrontEnd )
				)
				( attribute "CHIPS_PART_NAME" "CAP"
					( Origin gPackager )
				)
				( attribute "CDS_PART_NAME" "CAP_0402LF-0.01UF,25V,10%,X7R,A"
					( Origin gPackager )
				)
				( objectStatus "C25W11" )
				( pin "a"
					( attribute "PN" "1"
						( Origin gPackager )
					)
					( objectStatus "C25W11.1" )
				)
				( pin "b"
					( attribute "PN" "2"
						( Origin gPackager )
					)
					( objectStatus "C25W11.2" )
				)
			)
			( gate "@baseboard_fab2_lib.baseboard_fab2(sch_1):page152_i1"
				( attribute "BOM_COST" "PROC_SIDEBAND"
					( Origin gFrontEnd )
				)
				( attribute "CDS_LIB" "mstr_digital"
					( Origin gPackager )
				)
				( attribute "CDS_LOCATION" "U9G1"
					( Origin gPackager )
				)
				( attribute "CDS_SEC" "1"
					( Origin gPackager )
				)
				( attribute "LOCATION" "U9G1"
					( Origin gFrontEnd )
				)
				( attribute "MATERIAL" "IC"
					( Origin gFrontEnd )
				)
				( attribute "PACK_TYPE" "SM"
					( Origin gFrontEnd )
				)
				( attribute "PART_NUMBER" "D66151-001"
					( Origin gFrontEnd )
				)
				( attribute "PHYS_PAGE" "152"
					( Origin gFrontEnd )
				)
				( attribute "ROOM" "PROC_SIDEBAND"
					( Origin gFrontEnd )
				)
				( attribute "ROT" "2"
					( Origin gFrontEnd )
				)
				( attribute "SEC" "1"
					( Origin gFrontEnd )
				)
				( attribute "SEC_TYPE" "SM"
					( Origin gFrontEnd )
				)
				( attribute "VER" "1"
					( Origin gFrontEnd )
				)
				( attribute "XY" "(-5400,4050)"
					( Origin gFrontEnd )
				)
				( attribute "CHIPS_PART_NAME" "GTL2014"
					( Origin gPackager )
				)
				( attribute "CDS_PART_NAME" "GTL2014_SM-IC,D66151-001"
					( Origin gPackager )
				)
				( objectStatus "U9G1" )
				( pin "a0"
					( attribute "PN" "13"
						( Origin gPackager )
					)
					( objectStatus "U9G1.13" )
				)
				( pin "a1"
					( attribute "PN" "12"
						( Origin gPackager )
					)
					( objectStatus "U9G1.12" )
				)
				( pin "a2"
					( attribute "PN" "10"
						( Origin gPackager )
					)
					( objectStatus "U9G1.10" )
				)
				( pin "a3"
					( attribute "PN" "9"
						( Origin gPackager )
					)
					( objectStatus "U9G1.9" )
				)
				( pin "b0"
					( attribute "PN" "2"
						( Origin gPackager )
					)
					( objectStatus "U9G1.2" )
				)
				( pin "b1"
					( attribute "PN" "3"
						( Origin gPackager )
					)
					( objectStatus "U9G1.3" )
				)
				( pin "b2"
					( attribute "PN" "5"
						( Origin gPackager )
					)
					( objectStatus "U9G1.5" )
				)
				( pin "b3"
					( attribute "PN" "6"
						( Origin gPackager )
					)
					( objectStatus "U9G1.6" )
				)
				( pin "dir"
					( attribute "PN" "1"
						( Origin gPackager )
					)
					( objectStatus "U9G1.1" )
				)
				( pin "gnd(0)"
					( attribute "PN" "7"
						( Origin gPackager )
					)
					( objectStatus "U9G1.7" )
				)
				( pin "gnd(1)"
					( attribute "PN" "8"
						( Origin gPackager )
					)
					( objectStatus "U9G1.8" )
				)
				( pin "gnd(2)"
					( attribute "PN" "11"
						( Origin gPackager )
					)
					( objectStatus "U9G1.11" )
				)
				( pin "vcc"
					( attribute "PN" "14"
						( Origin gPackager )
					)
					( objectStatus "U9G1.14" )
				)
				( pin "vref"
					( attribute "PN" "4"
						( Origin gPackager )
					)
					( objectStatus "U9G1.4" )
				)
			)
			( gate "@baseboard_fab2_lib.baseboard_fab2(sch_1):page152_i2"
				( attribute "BOM_COST" "PROC_SIDEBAND"
					( Origin gFrontEnd )
				)
				( attribute "CDS_LIB" "mstr_discrete"
					( Origin gPackager )
				)
				( attribute "CDS_LOCATION" "R1U30"
					( Origin gPackager )
				)
				( attribute "CDS_SEC" "1"
					( Origin gPackager )
				)
				( attribute "LOCATION" "R1U30"
					( Origin gFrontEnd )
				)
				( attribute "MATERIAL" "CHIP"
					( Origin gFrontEnd )
				)
				( attribute "PACK_TYPE" "0402"
					( Origin gFrontEnd )
				)
				( attribute "PART_NUMBER" "G21796-026"
					( Origin gFrontEnd )
				)
				( attribute "PHYS_PAGE" "152"
					( Origin gFrontEnd )
				)
				( attribute "ROOM" "PROC_TRANSLATORS"
					( Origin gFrontEnd )
				)
				( attribute "ROT" "0"
					( Origin gFrontEnd )
				)
				( attribute "SEC" "1"
					( Origin gFrontEnd )
				)
				( attribute "SEC_TYPE" "0402"
					( Origin gFrontEnd )
				)
				( attribute "TOLERANCE" "1%"
					( Origin gFrontEnd )
				)
				( attribute "VALUE" "1.00K"
					( Origin gFrontEnd )
				)
				( attribute "VER" "1"
					( Origin gFrontEnd )
				)
				( attribute "WATTAGE" "1/16W"
					( Origin gFrontEnd )
				)
				( attribute "XY" "(-4350,4200)"
					( Origin gFrontEnd )
				)
				( attribute "CHIPS_PART_NAME" "RES"
					( Origin gPackager )
				)
				( attribute "CDS_PART_NAME" "RES_0402-1.00K,1%,1/16W,CHIP,GA"
					( Origin gPackager )
				)
				( objectStatus "R1U30" )
				( pin "a"
					( attribute "PN" "1"
						( Origin gPackager )
					)
					( objectStatus "R1U30.1" )
				)
				( pin "b"
					( attribute "PN" "2"
						( Origin gPackager )
					)
					( objectStatus "R1U30.2" )
				)
			)
			( gate "@baseboard_fab2_lib.baseboard_fab2(sch_1):page152_i6"
				( attribute "BOM_COST" "PROC_SIDEBAND"
					( Origin gFrontEnd )
				)
				( attribute "CDS_LIB" "mstr_discrete"
					( Origin gPackager )
				)
				( attribute "CDS_LOCATION" "R1U46"
					( Origin gPackager )
				)
				( attribute "CDS_SEC" "1"
					( Origin gPackager )
				)
				( attribute "LOCATION" "R1U46"
					( Origin gFrontEnd )
				)
				( attribute "MATERIAL" "CHIP"
					( Origin gFrontEnd )
				)
				( attribute "PACK_TYPE" "0402"
					( Origin gFrontEnd )
				)
				( attribute "PART_NUMBER" "G21796-074"
					( Origin gFrontEnd )
				)
				( attribute "PHYS_PAGE" "152"
					( Origin gFrontEnd )
				)
				( attribute "ROOM" "PROC_SIDEBAND"
					( Origin gFrontEnd )
				)
				( attribute "ROT" "0"
					( Origin gFrontEnd )
				)
				( attribute "SEC" "1"
					( Origin gFrontEnd )
				)
				( attribute "SEC_TYPE" "0402"
					( Origin gFrontEnd )
				)
				( attribute "TOLERANCE" "1%"
					( Origin gFrontEnd )
				)
				( attribute "VALUE" "33.2"
					( Origin gFrontEnd )
				)
				( attribute "VER" "1"
					( Origin gFrontEnd )
				)
				( attribute "WATTAGE" "1/16W"
					( Origin gFrontEnd )
				)
				( attribute "XY" "(-2450,4250)"
					( Origin gFrontEnd )
				)
				( attribute "CHIPS_PART_NAME" "RES"
					( Origin gPackager )
				)
				( attribute "CDS_PART_NAME" "RES_0402-33.2,1%,1/16W,CHIP,G2A"
					( Origin gPackager )
				)
				( objectStatus "R1U46" )
				( pin "a"
					( attribute "PN" "1"
						( Origin gPackager )
					)
					( objectStatus "R1U46.1" )
				)
				( pin "b"
					( attribute "PN" "2"
						( Origin gPackager )
					)
					( objectStatus "R1U46.2" )
				)
			)
			( gate "@baseboard_fab2_lib.baseboard_fab2(sch_1):page152_i14"
				( attribute "BOM_COST" "PROC_SIDEBAND"
					( Origin gFrontEnd )
				)
				( attribute "CDS_LIB" "mstr_discrete"
					( Origin gPackager )
				)
				( attribute "CDS_LOCATION" "R9G31"
					( Origin gPackager )
				)
				( attribute "CDS_SEC" "1"
					( Origin gPackager )
				)
				( attribute "LOCATION" "R9G31"
					( Origin gFrontEnd )
				)
				( attribute "MATERIAL" "CHIP"
					( Origin gFrontEnd )
				)
				( attribute "PACK_TYPE" "0402"
					( Origin gFrontEnd )
				)
				( attribute "PART_NUMBER" "G21796-074"
					( Origin gFrontEnd )
				)
				( attribute "PHYS_PAGE" "152"
					( Origin gFrontEnd )
				)
				( attribute "ROOM" "PROC_SIDEBAND"
					( Origin gFrontEnd )
				)
				( attribute "ROT" "0"
					( Origin gFrontEnd )
				)
				( attribute "SEC" "1"
					( Origin gFrontEnd )
				)
				( attribute "SEC_TYPE" "0402"
					( Origin gFrontEnd )
				)
				( attribute "TOLERANCE" "1%"
					( Origin gFrontEnd )
				)
				( attribute "VALUE" "33.2"
					( Origin gFrontEnd )
				)
				( attribute "VER" "1"
					( Origin gFrontEnd )
				)
				( attribute "WATTAGE" "1/16W"
					( Origin gFrontEnd )
				)
				( attribute "XY" "(-2450,4075)"
					( Origin gFrontEnd )
				)
				( attribute "CHIPS_PART_NAME" "RES"
					( Origin gPackager )
				)
				( attribute "CDS_PART_NAME" "RES_0402-33.2,1%,1/16W,CHIP,G2A"
					( Origin gPackager )
				)
				( objectStatus "R9G31" )
				( pin "a"
					( attribute "PN" "1"
						( Origin gPackager )
					)
					( objectStatus "R9G31.1" )
				)
				( pin "b"
					( attribute "PN" "2"
						( Origin gPackager )
					)
					( objectStatus "R9G31.2" )
				)
			)
			( gate "@baseboard_fab2_lib.baseboard_fab2(sch_1):page152_i15"
				( attribute "BOM_COST" "PROC_SIDEBAND"
					( Origin gFrontEnd )
				)
				( attribute "CDS_LIB" "mstr_discrete"
					( Origin gPackager )
				)
				( attribute "CDS_LOCATION" "R1U36"
					( Origin gPackager )
				)
				( attribute "CDS_SEC" "1"
					( Origin gPackager )
				)
				( attribute "LOCATION" "R1U36"
					( Origin gFrontEnd )
				)
				( attribute "MATERIAL" "CHIP"
					( Origin gFrontEnd )
				)
				( attribute "PACK_TYPE" "0402"
					( Origin gFrontEnd )
				)
				( attribute "PART_NUMBER" "G21796-074"
					( Origin gFrontEnd )
				)
				( attribute "PHYS_PAGE" "152"
					( Origin gFrontEnd )
				)
				( attribute "ROOM" "PROC_SIDEBAND"
					( Origin gFrontEnd )
				)
				( attribute "ROT" "0"
					( Origin gFrontEnd )
				)
				( attribute "SEC" "1"
					( Origin gFrontEnd )
				)
				( attribute "SEC_TYPE" "0402"
					( Origin gFrontEnd )
				)
				( attribute "TOLERANCE" "1%"
					( Origin gFrontEnd )
				)
				( attribute "VALUE" "33.2"
					( Origin gFrontEnd )
				)
				( attribute "VER" "1"
					( Origin gFrontEnd )
				)
				( attribute "WATTAGE" "1/16W"
					( Origin gFrontEnd )
				)
				( attribute "XY" "(-2450,3900)"
					( Origin gFrontEnd )
				)
				( attribute "CHIPS_PART_NAME" "RES"
					( Origin gPackager )
				)
				( attribute "CDS_PART_NAME" "RES_0402-33.2,1%,1/16W,CHIP,G2A"
					( Origin gPackager )
				)
				( objectStatus "R1U36" )
				( pin "a"
					( attribute "PN" "1"
						( Origin gPackager )
					)
					( objectStatus "R1U36.1" )
				)
				( pin "b"
					( attribute "PN" "2"
						( Origin gPackager )
					)
					( objectStatus "R1U36.2" )
				)
			)
			( gate "@baseboard_fab2_lib.baseboard_fab2(sch_1):page152_i16"
				( attribute "BOM_COST" "PROC_SIDEBAND"
					( Origin gFrontEnd )
				)
				( attribute "CDS_LIB" "mstr_discrete"
					( Origin gPackager )
				)
				( attribute "CDS_LOCATION" "R1U34"
					( Origin gPackager )
				)
				( attribute "CDS_SEC" "1"
					( Origin gPackager )
				)
				( attribute "LOCATION" "R1U34"
					( Origin gFrontEnd )
				)
				( attribute "MATERIAL" "CHIP"
					( Origin gFrontEnd )
				)
				( attribute "PACK_TYPE" "0402"
					( Origin gFrontEnd )
				)
				( attribute "PART_NUMBER" "G21796-074"
					( Origin gFrontEnd )
				)
				( attribute "PHYS_PAGE" "152"
					( Origin gFrontEnd )
				)
				( attribute "ROOM" "PROC_TRANSLATORS"
					( Origin gFrontEnd )
				)
				( attribute "ROT" "0"
					( Origin gFrontEnd )
				)
				( attribute "SEC" "1"
					( Origin gFrontEnd )
				)
				( attribute "SEC_TYPE" "0402"
					( Origin gFrontEnd )
				)
				( attribute "TOLERANCE" "1%"
					( Origin gFrontEnd )
				)
				( attribute "VALUE" "33.2"
					( Origin gFrontEnd )
				)
				( attribute "VER" "1"
					( Origin gFrontEnd )
				)
				( attribute "WATTAGE" "1/16W"
					( Origin gFrontEnd )
				)
				( attribute "XY" "(-2450,3725)"
					( Origin gFrontEnd )
				)
				( attribute "CHIPS_PART_NAME" "RES"
					( Origin gPackager )
				)
				( attribute "CDS_PART_NAME" "RES_0402-33.2,1%,1/16W,CHIP,G2A"
					( Origin gPackager )
				)
				( objectStatus "R1U34" )
				( pin "a"
					( attribute "PN" "1"
						( Origin gPackager )
					)
					( objectStatus "R1U34.1" )
				)
				( pin "b"
					( attribute "PN" "2"
						( Origin gPackager )
					)
					( objectStatus "R1U34.2" )
				)
			)
			( gate "@baseboard_fab2_lib.baseboard_fab2(sch_1):page152_i18"
				( attribute "BOM_COST" "PROC_SIDEBAND"
					( Origin gFrontEnd )
				)
				( attribute "CDS_LIB" "mstr_discrete"
					( Origin gPackager )
				)
				( attribute "CDS_LOCATION" "C1U19"
					( Origin gPackager )
				)
				( attribute "CDS_SEC" "1"
					( Origin gPackager )
				)
				( attribute "LOCATION" "C1U19"
					( Origin gFrontEnd )
				)
				( attribute "MATERIAL" "X6S"
					( Origin gFrontEnd )
				)
				( attribute "PACK_TYPE" "0402"
					( Origin gFrontEnd )
				)
				( attribute "PART_NUMBER" "D97712-011"
					( Origin gFrontEnd )
				)
				( attribute "PHYS_PAGE" "152"
					( Origin gFrontEnd )
				)
				( attribute "ROOM" "PROC_SIDEBAND"
					( Origin gFrontEnd )
				)
				( attribute "ROT" "0"
					( Origin gFrontEnd )
				)
				( attribute "SEC" "1"
					( Origin gFrontEnd )
				)
				( attribute "SEC_TYPE" "0402"
					( Origin gFrontEnd )
				)
				( attribute "TOLERANCE" "10%"
					( Origin gFrontEnd )
				)
				( attribute "VALUE" "1.0UF"
					( Origin gFrontEnd )
				)
				( attribute "VER" "1"
					( Origin gFrontEnd )
				)
				( attribute "VOLTAGE" "16V"
					( Units "uVoltage" "V" 1.000000)
					( Origin gFrontEnd )
				)
				( attribute "XY" "(-4525,4650)"
					( Origin gFrontEnd )
				)
				( attribute "CHIPS_PART_NAME" "CAP"
					( Origin gPackager )
				)
				( attribute "CDS_PART_NAME" "CAP_0402-1.0UF,16V,10%,X6S,D97A"
					( Origin gPackager )
				)
				( objectStatus "C1U19" )
				( pin "a"
					( attribute "PN" "1"
						( Origin gPackager )
					)
					( objectStatus "C1U19.1" )
				)
				( pin "b"
					( attribute "PN" "2"
						( Origin gPackager )
					)
					( objectStatus "C1U19.2" )
				)
			)
			( gate "@baseboard_fab2_lib.baseboard_fab2(sch_1):page152_i25"
				( attribute "BOM_COST" "PROC_SIDEBAND"
					( Origin gFrontEnd )
				)
				( attribute "CDS_LIB" "mstr_discrete"
					( Origin gPackager )
				)
				( attribute "CDS_LOCATION" "R1U43"
					( Origin gPackager )
				)
				( attribute "CDS_SEC" "1"
					( Origin gPackager )
				)
				( attribute "LOCATION" "R1U43"
					( Origin gFrontEnd )
				)
				( attribute "MATERIAL" "CHIP"
					( Origin gFrontEnd )
				)
				( attribute "PACK_TYPE" "0402"
					( Origin gFrontEnd )
				)
				( attribute "PART_NUMBER" "G21796-047"
					( Origin gFrontEnd )
				)
				( attribute "PHYS_PAGE" "152"
					( Origin gFrontEnd )
				)
				( attribute "ROOM" "PROC_SIDEBAND"
					( Origin gFrontEnd )
				)
				( attribute "ROT" "0"
					( Origin gFrontEnd )
				)
				( attribute "SEC" "1"
					( Origin gPackager )
				)
				( attribute "TOLERANCE" "1%"
					( Origin gFrontEnd )
				)
				( attribute "VALUE" "49.9"
					( Origin gFrontEnd )
				)
				( attribute "VER" "2"
					( Origin gFrontEnd )
				)
				( attribute "WATTAGE" "1/16W"
					( Origin gFrontEnd )
				)
				( attribute "XY" "(-1775,2000)"
					( Origin gFrontEnd )
				)
				( attribute "CHIPS_PART_NAME" "RES"
					( Origin gPackager )
				)
				( attribute "CDS_PART_NAME" "RES_0402-49.9,1%,1/16W,CHIP,G2A"
					( Origin gPackager )
				)
				( objectStatus "R1U43" )
				( pin "a"
					( attribute "PN" "1"
						( Origin gPackager )
					)
					( objectStatus "R1U43.1" )
				)
				( pin "b"
					( attribute "PN" "2"
						( Origin gPackager )
					)
					( objectStatus "R1U43.2" )
				)
			)
			( gate "@baseboard_fab2_lib.baseboard_fab2(sch_1):page152_i26"
				( attribute "BOM_COST" "PROC_SIDEBAND"
					( Origin gFrontEnd )
				)
				( attribute "CDS_LIB" "mstr_discrete"
					( Origin gPackager )
				)
				( attribute "CDS_LOCATION" "R1U37"
					( Origin gPackager )
				)
				( attribute "CDS_SEC" "1"
					( Origin gPackager )
				)
				( attribute "LOCATION" "R1U37"
					( Origin gFrontEnd )
				)
				( attribute "MATERIAL" "CHIP"
					( Origin gFrontEnd )
				)
				( attribute "PACK_TYPE" "0402"
					( Origin gFrontEnd )
				)
				( attribute "PART_NUMBER" "G21796-017"
					( Origin gFrontEnd )
				)
				( attribute "PHYS_PAGE" "152"
					( Origin gFrontEnd )
				)
				( attribute "ROOM" "PROC_SIDEBAND"
					( Origin gFrontEnd )
				)
				( attribute "ROT" "0"
					( Origin gFrontEnd )
				)
				( attribute "SEC" "1"
					( Origin gPackager )
				)
				( attribute "TOLERANCE" "1%"
					( Origin gFrontEnd )
				)
				( attribute "VALUE" "100.0"
					( Origin gFrontEnd )
				)
				( attribute "VER" "2"
					( Origin gFrontEnd )
				)
				( attribute "WATTAGE" "1/16W"
					( Origin gFrontEnd )
				)
				( attribute "XY" "(-1775,1600)"
					( Origin gFrontEnd )
				)
				( attribute "CHIPS_PART_NAME" "RES"
					( Origin gPackager )
				)
				( attribute "CDS_PART_NAME" "RES_0402-100.0,1%,1/16W,CHIP,GA"
					( Origin gPackager )
				)
				( objectStatus "R1U37" )
				( pin "a"
					( attribute "PN" "1"
						( Origin gPackager )
					)
					( objectStatus "R1U37.1" )
				)
				( pin "b"
					( attribute "PN" "2"
						( Origin gPackager )
					)
					( objectStatus "R1U37.2" )
				)
			)
			( gate "@baseboard_fab2_lib.baseboard_fab2(sch_1):page152_i27"
				( attribute "BOM_COST" "PROC_SIDEBAND"
					( Origin gFrontEnd )
				)
				( attribute "CDS_LIB" "dev_discrete"
					( Origin gPackager )
				)
				( attribute "CDS_LOCATION" "C1U22"
					( Origin gPackager )
				)
				( attribute "CDS_SEC" "1"
					( Origin gPackager )
				)
				( attribute "LOCATION" "C1U22"
					( Origin gFrontEnd )
				)
				( attribute "MATERIAL" "X7R"
					( Origin gFrontEnd )
				)
				( attribute "PACK_TYPE" "0402V"
					( Origin gFrontEnd )
				)
				( attribute "PART_NUMBER" "A36096-030"
					( Origin gFrontEnd )
				)
				( attribute "PHYS_PAGE" "152"
					( Origin gFrontEnd )
				)
				( attribute "ROOM" "PROC_SIDEBAND"
					( Origin gFrontEnd )
				)
				( attribute "ROT" "0"
					( Origin gFrontEnd )
				)
				( attribute "SEC" "1"
					( Origin gPackager )
				)
				( attribute "TOLERANCE" "10%"
					( Origin gFrontEnd )
				)
				( attribute "VALUE" "0.1UF"
					( Origin gFrontEnd )
				)
				( attribute "VER" "1"
					( Origin gFrontEnd )
				)
				( attribute "VOLTAGE" "16V"
					( Units "uVoltage" "V" 1.000000)
					( Origin gFrontEnd )
				)
				( attribute "XY" "(-2150,1600)"
					( Origin gFrontEnd )
				)
				( attribute "CHIPS_PART_NAME" "CAP_A"
					( Origin gPackager )
				)
				( attribute "CDS_PART_NAME" "CAP_A_0402V-0.1UF,16V,10%,X7R,A"
					( Origin gPackager )
				)
				( objectStatus "C1U22" )
				( pin "a"
					( attribute "PN" "1"
						( Origin gPackager )
					)
					( objectStatus "C1U22.1" )
				)
				( pin "b"
					( attribute "PN" "2"
						( Origin gPackager )
					)
					( objectStatus "C1U22.2" )
				)
			)
			( gate "@baseboard_fab2_lib.baseboard_fab2(sch_1):page152_i45"
				( attribute "CDS_LIB" "mstr_discrete"
					( Origin gPackager )
				)
				( attribute "CDS_LOCATION" "R9G34"
					( Origin gPackager )
				)
				( attribute "CDS_SEC" "1"
					( Origin gPackager )
				)
				( attribute "LOCATION" "R9G34"
					( Origin gFrontEnd )
				)
				( attribute "MATERIAL" "CHIP"
					( Origin gFrontEnd )
				)
				( attribute "PACK_TYPE" "0402"
					( Origin gFrontEnd )
				)
				( attribute "PART_NUMBER" "G21497-005"
					( Origin gFrontEnd )
				)
				( attribute "PHYS_PAGE" "152"
					( Origin gFrontEnd )
				)
				( attribute "ROT" "0"
					( Origin gFrontEnd )
				)
				( attribute "SEC" "1"
					( Origin gFrontEnd )
				)
				( attribute "SEC_TYPE" "0402"
					( Origin gFrontEnd )
				)
				( attribute "TOLERANCE" "5%"
					( Origin gFrontEnd )
				)
				( attribute "VALUE" "0.0"
					( Origin gFrontEnd )
				)
				( attribute "VER" "1"
					( Origin gFrontEnd )
				)
				( attribute "WATTAGE" "1/16W"
					( Origin gFrontEnd )
				)
				( attribute "XY" "(-6950,4225)"
					( Origin gFrontEnd )
				)
				( attribute "CHIPS_PART_NAME" "RES"
					( Origin gPackager )
				)
				( attribute "CDS_PART_NAME" "RES_0402-0.0,5%,1/16W,CHIP,G21A"
					( Origin gPackager )
				)
				( objectStatus "R9G34" )
				( pin "a"
					( attribute "PN" "1"
						( Origin gPackager )
					)
					( objectStatus "R9G34.1" )
				)
				( pin "b"
					( attribute "PN" "2"
						( Origin gPackager )
					)
					( objectStatus "R9G34.2" )
				)
			)
			( gate "@baseboard_fab2_lib.baseboard_fab2(sch_1):page152_i47"
				( attribute "CDS_LIB" "mstr_discrete"
					( Origin gPackager )
				)
				( attribute "CDS_LOCATION" "R9G27"
					( Origin gPackager )
				)
				( attribute "CDS_SEC" "1"
					( Origin gPackager )
				)
				( attribute "LOCATION" "R9G27"
					( Origin gFrontEnd )
				)
				( attribute "MATERIAL" "EMPTY"
					( Origin gFrontEnd )
				)
				( attribute "PACK_TYPE" "0402"
					( Origin gFrontEnd )
				)
				( attribute "PART_NUMBER" "G21497-005"
					( Origin gFrontEnd )
				)
				( attribute "PHYS_PAGE" "152"
					( Origin gFrontEnd )
				)
				( attribute "ROT" "0"
					( Origin gFrontEnd )
				)
				( attribute "SEC" "1"
					( Origin gFrontEnd )
				)
				( attribute "SEC_TYPE" "0402"
					( Origin gFrontEnd )
				)
				( attribute "TOLERANCE" "5%"
					( Origin gFrontEnd )
				)
				( attribute "VALUE" "0.0"
					( Origin gFrontEnd )
				)
				( attribute "VER" "2"
					( Origin gFrontEnd )
				)
				( attribute "WATTAGE" "1/16W"
					( Origin gFrontEnd )
				)
				( attribute "XY" "(-3150,4600)"
					( Origin gFrontEnd )
				)
				( attribute "CHIPS_PART_NAME" "RES"
					( Origin gPackager )
				)
				( attribute "CDS_PART_NAME" "RES_0402-0.0,5%,1/16W,EMPTY,G2A"
					( Origin gPackager )
				)
				( objectStatus "R9G27" )
				( pin "a"
					( attribute "PN" "1"
						( Origin gPackager )
					)
					( objectStatus "R9G27.1" )
				)
				( pin "b"
					( attribute "PN" "2"
						( Origin gPackager )
					)
					( objectStatus "R9G27.2" )
				)
			)
			( gate "@baseboard_fab2_lib.baseboard_fab2(sch_1):page152_i49"
				( attribute "CDS_LIB" "mstr_discrete"
					( Origin gPackager )
				)
				( attribute "CDS_LOCATION" "R1U58"
					( Origin gPackager )
				)
				( attribute "CDS_SEC" "1"
					( Origin gPackager )
				)
				( attribute "LOCATION" "R1U58"
					( Origin gFrontEnd )
				)
				( attribute "MATERIAL" "CHIP"
					( Origin gFrontEnd )
				)
				( attribute "PACK_TYPE" "0402"
					( Origin gFrontEnd )
				)
				( attribute "PART_NUMBER" "G21497-005"
					( Origin gFrontEnd )
				)
				( attribute "PHYS_PAGE" "152"
					( Origin gFrontEnd )
				)
				( attribute "ROT" "0"
					( Origin gFrontEnd )
				)
				( attribute "SEC" "1"
					( Origin gFrontEnd )
				)
				( attribute "SEC_TYPE" "0402"
					( Origin gFrontEnd )
				)
				( attribute "TOLERANCE" "5%"
					( Origin gFrontEnd )
				)
				( attribute "VALUE" "0.0"
					( Origin gFrontEnd )
				)
				( attribute "VER" "1"
					( Origin gFrontEnd )
				)
				( attribute "WATTAGE" "1/16W"
					( Origin gFrontEnd )
				)
				( attribute "XY" "(-6950,4050)"
					( Origin gFrontEnd )
				)
				( attribute "CHIPS_PART_NAME" "RES"
					( Origin gPackager )
				)
				( attribute "CDS_PART_NAME" "RES_0402-0.0,5%,1/16W,CHIP,G21A"
					( Origin gPackager )
				)
				( objectStatus "R1U58" )
				( pin "a"
					( attribute "PN" "1"
						( Origin gPackager )
					)
					( objectStatus "R1U58.1" )
				)
				( pin "b"
					( attribute "PN" "2"
						( Origin gPackager )
					)
					( objectStatus "R1U58.2" )
				)
			)
			( gate "@baseboard_fab2_lib.baseboard_fab2(sch_1):page152_i50"
				( attribute "CDS_LIB" "mstr_discrete"
					( Origin gPackager )
				)
				( attribute "CDS_LOCATION" "R1U56"
					( Origin gPackager )
				)
				( attribute "CDS_SEC" "1"
					( Origin gPackager )
				)
				( attribute "LOCATION" "R1U56"
					( Origin gFrontEnd )
				)
				( attribute "MATERIAL" "EMPTY"
					( Origin gFrontEnd )
				)
				( attribute "PACK_TYPE" "0402"
					( Origin gFrontEnd )
				)
				( attribute "PART_NUMBER" "G21497-005"
					( Origin gFrontEnd )
				)
				( attribute "PHYS_PAGE" "152"
					( Origin gFrontEnd )
				)
				( attribute "ROT" "0"
					( Origin gFrontEnd )
				)
				( attribute "SEC" "1"
					( Origin gFrontEnd )
				)
				( attribute "SEC_TYPE" "0402"
					( Origin gFrontEnd )
				)
				( attribute "TOLERANCE" "5%"
					( Origin gFrontEnd )
				)
				( attribute "VALUE" "0.0"
					( Origin gFrontEnd )
				)
				( attribute "VER" "2"
					( Origin gFrontEnd )
				)
				( attribute "WATTAGE" "1/16W"
					( Origin gFrontEnd )
				)
				( attribute "XY" "(-7175,4525)"
					( Origin gFrontEnd )
				)
				( attribute "CHIPS_PART_NAME" "RES"
					( Origin gPackager )
				)
				( attribute "CDS_PART_NAME" "RES_0402-0.0,5%,1/16W,EMPTY,G2A"
					( Origin gPackager )
				)
				( objectStatus "R1U56" )
				( pin "a"
					( attribute "PN" "1"
						( Origin gPackager )
					)
					( objectStatus "R1U56.1" )
				)
				( pin "b"
					( attribute "PN" "2"
						( Origin gPackager )
					)
					( objectStatus "R1U56.2" )
				)
			)
			( gate "@baseboard_fab2_lib.baseboard_fab2(sch_1):page152_i51"
				( attribute "CDS_LIB" "mstr_discrete"
					( Origin gPackager )
				)
				( attribute "CDS_LOCATION" "R2U51"
					( Origin gPackager )
				)
				( attribute "CDS_SEC" "1"
					( Origin gPackager )
				)
				( attribute "LOCATION" "R2U51"
					( Origin gFrontEnd )
				)
				( attribute "MATERIAL" "EMPTY"
					( Origin gFrontEnd )
				)
				( attribute "PACK_TYPE" "0402"
					( Origin gFrontEnd )
				)
				( attribute "PART_NUMBER" "G21497-005"
					( Origin gFrontEnd )
				)
				( attribute "PHYS_PAGE" "152"
					( Origin gFrontEnd )
				)
				( attribute "ROT" "0"
					( Origin gFrontEnd )
				)
				( attribute "SEC" "1"
					( Origin gFrontEnd )
				)
				( attribute "SEC_TYPE" "0402"
					( Origin gFrontEnd )
				)
				( attribute "TOLERANCE" "5%"
					( Origin gFrontEnd )
				)
				( attribute "VALUE" "0.0"
					( Origin gFrontEnd )
				)
				( attribute "VER" "2"
					( Origin gFrontEnd )
				)
				( attribute "WATTAGE" "1/16W"
					( Origin gFrontEnd )
				)
				( attribute "XY" "(-7450,4525)"
					( Origin gFrontEnd )
				)
				( attribute "CHIPS_PART_NAME" "RES"
					( Origin gPackager )
				)
				( attribute "CDS_PART_NAME" "RES_0402-0.0,5%,1/16W,EMPTY,G2A"
					( Origin gPackager )
				)
				( objectStatus "R2U51" )
				( pin "a"
					( attribute "PN" "1"
						( Origin gPackager )
					)
					( objectStatus "R2U51.1" )
				)
				( pin "b"
					( attribute "PN" "2"
						( Origin gPackager )
					)
					( objectStatus "R2U51.2" )
				)
			)
			( gate "@baseboard_fab2_lib.baseboard_fab2(sch_1):page152_i53"
				( attribute "BOM_COST" "PROC_SIDEBAND"
					( Origin gFrontEnd )
				)
				( attribute "CDS_LIB" "mstr_discrete"
					( Origin gPackager )
				)
				( attribute "CDS_LOCATION" "R2U40"
					( Origin gPackager )
				)
				( attribute "CDS_SEC" "1"
					( Origin gPackager )
				)
				( attribute "LOCATION" "R2U40"
					( Origin gFrontEnd )
				)
				( attribute "MATERIAL" "CHIP"
					( Origin gFrontEnd )
				)
				( attribute "PACK_TYPE" "0402"
					( Origin gFrontEnd )
				)
				( attribute "PART_NUMBER" "G21796-009"
					( Origin gFrontEnd )
				)
				( attribute "PHYS_PAGE" "152"
					( Origin gFrontEnd )
				)
				( attribute "ROOM" "PROC_SIDEBAND"
					( Origin gFrontEnd )
				)
				( attribute "ROT" "0"
					( Origin gFrontEnd )
				)
				( attribute "SEC" "1"
					( Origin gFrontEnd )
				)
				( attribute "SEC_TYPE" "0402"
					( Origin gFrontEnd )
				)
				( attribute "TOLERANCE" "1%"
					( Origin gFrontEnd )
				)
				( attribute "VALUE" "150.0"
					( Origin gFrontEnd )
				)
				( attribute "VER" "2"
					( Origin gFrontEnd )
				)
				( attribute "WATTAGE" "1/16W"
					( Origin gFrontEnd )
				)
				( attribute "XY" "(-7875,4650)"
					( Origin gFrontEnd )
				)
				( attribute "CHIPS_PART_NAME" "RES"
					( Origin gPackager )
				)
				( attribute "CDS_PART_NAME" "RES_0402-150.0,1%,1/16W,CHIP,GA"
					( Origin gPackager )
				)
				( objectStatus "R2U40" )
				( pin "a"
					( attribute "PN" "1"
						( Origin gPackager )
					)
					( objectStatus "R2U40.1" )
				)
				( pin "b"
					( attribute "PN" "2"
						( Origin gPackager )
					)
					( objectStatus "R2U40.2" )
				)
			)
			( gate "@baseboard_fab2_lib.baseboard_fab2(sch_1):page152_i54"
				( attribute "BOM_COST" "PROC_SIDEBAND"
					( Origin gFrontEnd )
				)
				( attribute "CDS_LIB" "mstr_discrete"
					( Origin gPackager )
				)
				( attribute "CDS_LOCATION" "R2U41"
					( Origin gPackager )
				)
				( attribute "CDS_SEC" "1"
					( Origin gPackager )
				)
				( attribute "LOCATION" "R2U41"
					( Origin gFrontEnd )
				)
				( attribute "MATERIAL" "CHIP"
					( Origin gFrontEnd )
				)
				( attribute "PACK_TYPE" "0402"
					( Origin gFrontEnd )
				)
				( attribute "PART_NUMBER" "G21796-009"
					( Origin gFrontEnd )
				)
				( attribute "PHYS_PAGE" "152"
					( Origin gFrontEnd )
				)
				( attribute "ROOM" "PROC_SIDEBAND"
					( Origin gFrontEnd )
				)
				( attribute "ROT" "2"
					( Origin gFrontEnd )
				)
				( attribute "SEC" "1"
					( Origin gFrontEnd )
				)
				( attribute "SEC_TYPE" "0402"
					( Origin gFrontEnd )
				)
				( attribute "TOLERANCE" "1%"
					( Origin gFrontEnd )
				)
				( attribute "VALUE" "150.0"
					( Origin gFrontEnd )
				)
				( attribute "VER" "2"
					( Origin gFrontEnd )
				)
				( attribute "WATTAGE" "1/16W"
					( Origin gFrontEnd )
				)
				( attribute "XY" "(-7975,4650)"
					( Origin gFrontEnd )
				)
				( attribute "CHIPS_PART_NAME" "RES"
					( Origin gPackager )
				)
				( attribute "CDS_PART_NAME" "RES_0402-150.0,1%,1/16W,CHIP,GA"
					( Origin gPackager )
				)
				( objectStatus "R2U41" )
				( pin "a"
					( attribute "PN" "1"
						( Origin gPackager )
					)
					( objectStatus "R2U41.1" )
				)
				( pin "b"
					( attribute "PN" "2"
						( Origin gPackager )
					)
					( objectStatus "R2U41.2" )
				)
			)
			( gate "@baseboard_fab2_lib.baseboard_fab2(sch_1):page152_i56"
				( attribute "BOM_COST" "PROC_SIDEBAND"
					( Origin gFrontEnd )
				)
				( attribute "CDS_LIB" "mstr_discrete"
					( Origin gPackager )
				)
				( attribute "CDS_LOCATION" "R1U41"
					( Origin gPackager )
				)
				( attribute "CDS_SEC" "1"
					( Origin gPackager )
				)
				( attribute "LOCATION" "R1U41"
					( Origin gFrontEnd )
				)
				( attribute "MATERIAL" "CHIP"
					( Origin gFrontEnd )
				)
				( attribute "PACK_TYPE" "0402"
					( Origin gFrontEnd )
				)
				( attribute "PART_NUMBER" "G21796-009"
					( Origin gFrontEnd )
				)
				( attribute "PHYS_PAGE" "152"
					( Origin gFrontEnd )
				)
				( attribute "ROOM" "PROC_SIDEBAND"
					( Origin gFrontEnd )
				)
				( attribute "ROT" "0"
					( Origin gFrontEnd )
				)
				( attribute "SEC" "1"
					( Origin gFrontEnd )
				)
				( attribute "SEC_TYPE" "0402"
					( Origin gFrontEnd )
				)
				( attribute "TOLERANCE" "1%"
					( Origin gFrontEnd )
				)
				( attribute "VALUE" "150.0"
					( Origin gFrontEnd )
				)
				( attribute "VER" "2"
					( Origin gFrontEnd )
				)
				( attribute "WATTAGE" "1/16W"
					( Origin gFrontEnd )
				)
				( attribute "XY" "(-8325,4650)"
					( Origin gFrontEnd )
				)
				( attribute "CHIPS_PART_NAME" "RES"
					( Origin gPackager )
				)
				( attribute "CDS_PART_NAME" "RES_0402-150.0,1%,1/16W,CHIP,GA"
					( Origin gPackager )
				)
				( objectStatus "R1U41" )
				( pin "a"
					( attribute "PN" "1"
						( Origin gPackager )
					)
					( objectStatus "R1U41.1" )
				)
				( pin "b"
					( attribute "PN" "2"
						( Origin gPackager )
					)
					( objectStatus "R1U41.2" )
				)
			)
			( gate "@baseboard_fab2_lib.baseboard_fab2(sch_1):page152_i57"
				( attribute "BOM_COST" "PROC_SIDEBAND"
					( Origin gFrontEnd )
				)
				( attribute "CDS_LIB" "mstr_discrete"
					( Origin gPackager )
				)
				( attribute "CDS_LOCATION" "R1U35"
					( Origin gPackager )
				)
				( attribute "CDS_SEC" "1"
					( Origin gPackager )
				)
				( attribute "LOCATION" "R1U35"
					( Origin gFrontEnd )
				)
				( attribute "MATERIAL" "CHIP"
					( Origin gFrontEnd )
				)
				( attribute "PACK_TYPE" "0402"
					( Origin gFrontEnd )
				)
				( attribute "PART_NUMBER" "G21796-009"
					( Origin gFrontEnd )
				)
				( attribute "PHYS_PAGE" "152"
					( Origin gFrontEnd )
				)
				( attribute "ROOM" "PROC_SIDEBAND"
					( Origin gFrontEnd )
				)
				( attribute "ROT" "2"
					( Origin gFrontEnd )
				)
				( attribute "SEC" "1"
					( Origin gFrontEnd )
				)
				( attribute "SEC_TYPE" "0402"
					( Origin gFrontEnd )
				)
				( attribute "TOLERANCE" "1%"
					( Origin gFrontEnd )
				)
				( attribute "VALUE" "150.0"
					( Origin gFrontEnd )
				)
				( attribute "VER" "2"
					( Origin gFrontEnd )
				)
				( attribute "WATTAGE" "1/16W"
					( Origin gFrontEnd )
				)
				( attribute "XY" "(-8425,4650)"
					( Origin gFrontEnd )
				)
				( attribute "CHIPS_PART_NAME" "RES"
					( Origin gPackager )
				)
				( attribute "CDS_PART_NAME" "RES_0402-150.0,1%,1/16W,CHIP,GA"
					( Origin gPackager )
				)
				( objectStatus "R1U35" )
				( pin "a"
					( attribute "PN" "1"
						( Origin gPackager )
					)
					( objectStatus "R1U35.1" )
				)
				( pin "b"
					( attribute "PN" "2"
						( Origin gPackager )
					)
					( objectStatus "R1U35.2" )
				)
			)
			( gate "@baseboard_fab2_lib.baseboard_fab2(sch_1):page152_i58"
				( attribute "BOM_COST" "PROC_SIDEBAND"
					( Origin gFrontEnd )
				)
				( attribute "CDS_LIB" "mstr_discrete"
					( Origin gPackager )
				)
				( attribute "CDS_LOCATION" "R4P17"
					( Origin gPackager )
				)
				( attribute "CDS_SEC" "1"
					( Origin gPackager )
				)
				( attribute "LOCATION" "R4P17"
					( Origin gFrontEnd )
				)
				( attribute "MATERIAL" "CHIP"
					( Origin gFrontEnd )
				)
				( attribute "PACK_TYPE" "0402"
					( Origin gFrontEnd )
				)
				( attribute "PART_NUMBER" "G21796-009"
					( Origin gFrontEnd )
				)
				( attribute "PHYS_PAGE" "152"
					( Origin gFrontEnd )
				)
				( attribute "ROOM" "PROC_SIDEBAND"
					( Origin gFrontEnd )
				)
				( attribute "ROT" "0"
					( Origin gFrontEnd )
				)
				( attribute "SEC" "1"
					( Origin gFrontEnd )
				)
				( attribute "SEC_TYPE" "0402"
					( Origin gFrontEnd )
				)
				( attribute "TOLERANCE" "1%"
					( Origin gFrontEnd )
				)
				( attribute "VALUE" "150.0"
					( Origin gFrontEnd )
				)
				( attribute "VER" "2"
					( Origin gFrontEnd )
				)
				( attribute "WATTAGE" "1/16W"
					( Origin gFrontEnd )
				)
				( attribute "XY" "(-7800,3250)"
					( Origin gFrontEnd )
				)
				( attribute "CHIPS_PART_NAME" "RES"
					( Origin gPackager )
				)
				( attribute "CDS_PART_NAME" "RES_0402-150.0,1%,1/16W,CHIP,GA"
					( Origin gPackager )
				)
				( objectStatus "R4P17" )
				( pin "a"
					( attribute "PN" "1"
						( Origin gPackager )
					)
					( objectStatus "R4P17.1" )
				)
				( pin "b"
					( attribute "PN" "2"
						( Origin gPackager )
					)
					( objectStatus "R4P17.2" )
				)
			)
			( gate "@baseboard_fab2_lib.baseboard_fab2(sch_1):page152_i59"
				( attribute "BOM_COST" "PROC_SIDEBAND"
					( Origin gFrontEnd )
				)
				( attribute "CDS_LIB" "mstr_discrete"
					( Origin gPackager )
				)
				( attribute "CDS_LOCATION" "R4P20"
					( Origin gPackager )
				)
				( attribute "CDS_SEC" "1"
					( Origin gPackager )
				)
				( attribute "LOCATION" "R4P20"
					( Origin gFrontEnd )
				)
				( attribute "MATERIAL" "CHIP"
					( Origin gFrontEnd )
				)
				( attribute "PACK_TYPE" "0402"
					( Origin gFrontEnd )
				)
				( attribute "PART_NUMBER" "G21796-009"
					( Origin gFrontEnd )
				)
				( attribute "PHYS_PAGE" "152"
					( Origin gFrontEnd )
				)
				( attribute "ROOM" "PROC_SIDEBAND"
					( Origin gFrontEnd )
				)
				( attribute "ROT" "2"
					( Origin gFrontEnd )
				)
				( attribute "SEC" "1"
					( Origin gFrontEnd )
				)
				( attribute "SEC_TYPE" "0402"
					( Origin gFrontEnd )
				)
				( attribute "TOLERANCE" "1%"
					( Origin gFrontEnd )
				)
				( attribute "VALUE" "150.0"
					( Origin gFrontEnd )
				)
				( attribute "VER" "2"
					( Origin gFrontEnd )
				)
				( attribute "WATTAGE" "1/16W"
					( Origin gFrontEnd )
				)
				( attribute "XY" "(-7900,3250)"
					( Origin gFrontEnd )
				)
				( attribute "CHIPS_PART_NAME" "RES"
					( Origin gPackager )
				)
				( attribute "CDS_PART_NAME" "RES_0402-150.0,1%,1/16W,CHIP,GA"
					( Origin gPackager )
				)
				( objectStatus "R4P20" )
				( pin "a"
					( attribute "PN" "1"
						( Origin gPackager )
					)
					( objectStatus "R4P20.1" )
				)
				( pin "b"
					( attribute "PN" "2"
						( Origin gPackager )
					)
					( objectStatus "R4P20.2" )
				)
			)
			( gate "@baseboard_fab2_lib.baseboard_fab2(sch_1):page152_i61"
				( attribute "BOM_COST" "PROC_SIDEBAND"
					( Origin gFrontEnd )
				)
				( attribute "CDS_LIB" "mstr_discrete"
					( Origin gPackager )
				)
				( attribute "CDS_LOCATION" "R7P5"
					( Origin gPackager )
				)
				( attribute "CDS_SEC" "1"
					( Origin gPackager )
				)
				( attribute "LOCATION" "R7P5"
					( Origin gFrontEnd )
				)
				( attribute "MATERIAL" "CHIP"
					( Origin gFrontEnd )
				)
				( attribute "PACK_TYPE" "0402"
					( Origin gFrontEnd )
				)
				( attribute "PART_NUMBER" "G21796-009"
					( Origin gFrontEnd )
				)
				( attribute "PHYS_PAGE" "152"
					( Origin gFrontEnd )
				)
				( attribute "ROOM" "PROC_SIDEBAND"
					( Origin gFrontEnd )
				)
				( attribute "ROT" "0"
					( Origin gFrontEnd )
				)
				( attribute "SEC" "1"
					( Origin gFrontEnd )
				)
				( attribute "SEC_TYPE" "0402"
					( Origin gFrontEnd )
				)
				( attribute "TOLERANCE" "1%"
					( Origin gFrontEnd )
				)
				( attribute "VALUE" "150.0"
					( Origin gFrontEnd )
				)
				( attribute "VER" "2"
					( Origin gFrontEnd )
				)
				( attribute "WATTAGE" "1/16W"
					( Origin gFrontEnd )
				)
				( attribute "XY" "(-8250,3275)"
					( Origin gFrontEnd )
				)
				( attribute "CHIPS_PART_NAME" "RES"
					( Origin gPackager )
				)
				( attribute "CDS_PART_NAME" "RES_0402-150.0,1%,1/16W,CHIP,GA"
					( Origin gPackager )
				)
				( objectStatus "R7P5" )
				( pin "a"
					( attribute "PN" "1"
						( Origin gPackager )
					)
					( objectStatus "R7P5.1" )
				)
				( pin "b"
					( attribute "PN" "2"
						( Origin gPackager )
					)
					( objectStatus "R7P5.2" )
				)
			)
			( gate "@baseboard_fab2_lib.baseboard_fab2(sch_1):page152_i62"
				( attribute "BOM_COST" "PROC_SIDEBAND"
					( Origin gFrontEnd )
				)
				( attribute "CDS_LIB" "mstr_discrete"
					( Origin gPackager )
				)
				( attribute "CDS_LOCATION" "R7P21"
					( Origin gPackager )
				)
				( attribute "CDS_SEC" "1"
					( Origin gPackager )
				)
				( attribute "LOCATION" "R7P21"
					( Origin gFrontEnd )
				)
				( attribute "MATERIAL" "CHIP"
					( Origin gFrontEnd )
				)
				( attribute "PACK_TYPE" "0402"
					( Origin gFrontEnd )
				)
				( attribute "PART_NUMBER" "G21796-009"
					( Origin gFrontEnd )
				)
				( attribute "PHYS_PAGE" "152"
					( Origin gFrontEnd )
				)
				( attribute "ROOM" "PROC_SIDEBAND"
					( Origin gFrontEnd )
				)
				( attribute "ROT" "2"
					( Origin gFrontEnd )
				)
				( attribute "SEC" "1"
					( Origin gFrontEnd )
				)
				( attribute "SEC_TYPE" "0402"
					( Origin gFrontEnd )
				)
				( attribute "TOLERANCE" "1%"
					( Origin gFrontEnd )
				)
				( attribute "VALUE" "150.0"
					( Origin gFrontEnd )
				)
				( attribute "VER" "2"
					( Origin gFrontEnd )
				)
				( attribute "WATTAGE" "1/16W"
					( Origin gFrontEnd )
				)
				( attribute "XY" "(-8350,3275)"
					( Origin gFrontEnd )
				)
				( attribute "CHIPS_PART_NAME" "RES"
					( Origin gPackager )
				)
				( attribute "CDS_PART_NAME" "RES_0402-150.0,1%,1/16W,CHIP,GA"
					( Origin gPackager )
				)
				( objectStatus "R7P21" )
				( pin "a"
					( attribute "PN" "1"
						( Origin gPackager )
					)
					( objectStatus "R7P21.1" )
				)
				( pin "b"
					( attribute "PN" "2"
						( Origin gPackager )
					)
					( objectStatus "R7P21.2" )
				)
			)
			( gate "@baseboard_fab2_lib.baseboard_fab2(sch_1):page152_i64"
				( attribute "CDS_LIB" "mstr_discrete"
					( Origin gPackager )
				)
				( attribute "CDS_LOCATION" "R1U53"
					( Origin gPackager )
				)
				( attribute "CDS_SEC" "1"
					( Origin gPackager )
				)
				( attribute "LOCATION" "R1U53"
					( Origin gFrontEnd )
				)
				( attribute "MATERIAL" "CHIP"
					( Origin gFrontEnd )
				)
				( attribute "PACK_TYPE" "0402"
					( Origin gFrontEnd )
				)
				( attribute "PART_NUMBER" "G21497-005"
					( Origin gFrontEnd )
				)
				( attribute "PHYS_PAGE" "152"
					( Origin gFrontEnd )
				)
				( attribute "ROT" "0"
					( Origin gFrontEnd )
				)
				( attribute "SEC" "1"
					( Origin gFrontEnd )
				)
				( attribute "SEC_TYPE" "0402"
					( Origin gFrontEnd )
				)
				( attribute "TOLERANCE" "5%"
					( Origin gFrontEnd )
				)
				( attribute "VALUE" "0.0"
					( Origin gFrontEnd )
				)
				( attribute "VER" "1"
					( Origin gFrontEnd )
				)
				( attribute "WATTAGE" "1/16W"
					( Origin gFrontEnd )
				)
				( attribute "XY" "(-6950,3900)"
					( Origin gFrontEnd )
				)
				( attribute "CHIPS_PART_NAME" "RES"
					( Origin gPackager )
				)
				( attribute "CDS_PART_NAME" "RES_0402-0.0,5%,1/16W,CHIP,G21A"
					( Origin gPackager )
				)
				( objectStatus "R1U53" )
				( pin "a"
					( attribute "PN" "1"
						( Origin gPackager )
					)
					( objectStatus "R1U53.1" )
				)
				( pin "b"
					( attribute "PN" "2"
						( Origin gPackager )
					)
					( objectStatus "R1U53.2" )
				)
			)
			( gate "@baseboard_fab2_lib.baseboard_fab2(sch_1):page152_i65"
				( attribute "CDS_LIB" "mstr_discrete"
					( Origin gPackager )
				)
				( attribute "CDS_LOCATION" "R1U60"
					( Origin gPackager )
				)
				( attribute "CDS_SEC" "1"
					( Origin gPackager )
				)
				( attribute "LOCATION" "R1U60"
					( Origin gFrontEnd )
				)
				( attribute "MATERIAL" "CHIP"
					( Origin gFrontEnd )
				)
				( attribute "PACK_TYPE" "0402"
					( Origin gFrontEnd )
				)
				( attribute "PART_NUMBER" "G21497-005"
					( Origin gFrontEnd )
				)
				( attribute "PHYS_PAGE" "152"
					( Origin gFrontEnd )
				)
				( attribute "ROT" "0"
					( Origin gFrontEnd )
				)
				( attribute "SEC" "1"
					( Origin gFrontEnd )
				)
				( attribute "SEC_TYPE" "0402"
					( Origin gFrontEnd )
				)
				( attribute "TOLERANCE" "5%"
					( Origin gFrontEnd )
				)
				( attribute "VALUE" "0.0"
					( Origin gFrontEnd )
				)
				( attribute "VER" "1"
					( Origin gFrontEnd )
				)
				( attribute "WATTAGE" "1/16W"
					( Origin gFrontEnd )
				)
				( attribute "XY" "(-6950,3750)"
					( Origin gFrontEnd )
				)
				( attribute "CHIPS_PART_NAME" "RES"
					( Origin gPackager )
				)
				( attribute "CDS_PART_NAME" "RES_0402-0.0,5%,1/16W,CHIP,G21A"
					( Origin gPackager )
				)
				( objectStatus "R1U60" )
				( pin "a"
					( attribute "PN" "1"
						( Origin gPackager )
					)
					( objectStatus "R1U60.1" )
				)
				( pin "b"
					( attribute "PN" "2"
						( Origin gPackager )
					)
					( objectStatus "R1U60.2" )
				)
			)
			( gate "@baseboard_fab2_lib.baseboard_fab2(sch_1):page152_i66"
				( attribute "CDS_LIB" "mstr_discrete"
					( Origin gPackager )
				)
				( attribute "CDS_LOCATION" "R2U49"
					( Origin gPackager )
				)
				( attribute "CDS_SEC" "1"
					( Origin gPackager )
				)
				( attribute "LOCATION" "R2U49"
					( Origin gFrontEnd )
				)
				( attribute "MATERIAL" "EMPTY"
					( Origin gFrontEnd )
				)
				( attribute "PACK_TYPE" "0402"
					( Origin gFrontEnd )
				)
				( attribute "PART_NUMBER" "G21497-005"
					( Origin gFrontEnd )
				)
				( attribute "PHYS_PAGE" "152"
					( Origin gFrontEnd )
				)
				( attribute "ROT" "0"
					( Origin gFrontEnd )
				)
				( attribute "SEC" "1"
					( Origin gFrontEnd )
				)
				( attribute "SEC_TYPE" "0402"
					( Origin gFrontEnd )
				)
				( attribute "TOLERANCE" "5%"
					( Origin gFrontEnd )
				)
				( attribute "VALUE" "0.0"
					( Origin gFrontEnd )
				)
				( attribute "VER" "2"
					( Origin gFrontEnd )
				)
				( attribute "WATTAGE" "1/16W"
					( Origin gFrontEnd )
				)
				( attribute "XY" "(-2850,4600)"
					( Origin gFrontEnd )
				)
				( attribute "CHIPS_PART_NAME" "RES"
					( Origin gPackager )
				)
				( attribute "CDS_PART_NAME" "RES_0402-0.0,5%,1/16W,EMPTY,G2A"
					( Origin gPackager )
				)
				( objectStatus "R2U49" )
				( pin "a"
					( attribute "PN" "1"
						( Origin gPackager )
					)
					( objectStatus "R2U49.1" )
				)
				( pin "b"
					( attribute "PN" "2"
						( Origin gPackager )
					)
					( objectStatus "R2U49.2" )
				)
			)
			( gate "@baseboard_fab2_lib.baseboard_fab2(sch_1):page152_i67"
				( attribute "CDS_LIB" "mstr_discrete"
					( Origin gPackager )
				)
				( attribute "CDS_LOCATION" "R1U55"
					( Origin gPackager )
				)
				( attribute "CDS_SEC" "1"
					( Origin gPackager )
				)
				( attribute "LOCATION" "R1U55"
					( Origin gFrontEnd )
				)
				( attribute "MATERIAL" "EMPTY"
					( Origin gFrontEnd )
				)
				( attribute "PACK_TYPE" "0402"
					( Origin gFrontEnd )
				)
				( attribute "PART_NUMBER" "G21497-005"
					( Origin gFrontEnd )
				)
				( attribute "PHYS_PAGE" "152"
					( Origin gFrontEnd )
				)
				( attribute "ROT" "0"
					( Origin gFrontEnd )
				)
				( attribute "SEC" "1"
					( Origin gFrontEnd )
				)
				( attribute "SEC_TYPE" "0402"
					( Origin gFrontEnd )
				)
				( attribute "TOLERANCE" "5%"
					( Origin gFrontEnd )
				)
				( attribute "VALUE" "0.0"
					( Origin gFrontEnd )
				)
				( attribute "VER" "2"
					( Origin gFrontEnd )
				)
				( attribute "WATTAGE" "1/16W"
					( Origin gFrontEnd )
				)
				( attribute "XY" "(-7175,3500)"
					( Origin gFrontEnd )
				)
				( attribute "CHIPS_PART_NAME" "RES"
					( Origin gPackager )
				)
				( attribute "CDS_PART_NAME" "RES_0402-0.0,5%,1/16W,EMPTY,G2A"
					( Origin gPackager )
				)
				( objectStatus "R1U55" )
				( pin "a"
					( attribute "PN" "1"
						( Origin gPackager )
					)
					( objectStatus "R1U55.1" )
				)
				( pin "b"
					( attribute "PN" "2"
						( Origin gPackager )
					)
					( objectStatus "R1U55.2" )
				)
			)
			( gate "@baseboard_fab2_lib.baseboard_fab2(sch_1):page152_i68"
				( attribute "CDS_LIB" "mstr_discrete"
					( Origin gPackager )
				)
				( attribute "CDS_LOCATION" "R1U62"
					( Origin gPackager )
				)
				( attribute "CDS_SEC" "1"
					( Origin gPackager )
				)
				( attribute "LOCATION" "R1U62"
					( Origin gFrontEnd )
				)
				( attribute "MATERIAL" "EMPTY"
					( Origin gFrontEnd )
				)
				( attribute "PACK_TYPE" "0402"
					( Origin gFrontEnd )
				)
				( attribute "PART_NUMBER" "G21497-005"
					( Origin gFrontEnd )
				)
				( attribute "PHYS_PAGE" "152"
					( Origin gFrontEnd )
				)
				( attribute "ROT" "0"
					( Origin gFrontEnd )
				)
				( attribute "SEC" "1"
					( Origin gFrontEnd )
				)
				( attribute "SEC_TYPE" "0402"
					( Origin gFrontEnd )
				)
				( attribute "TOLERANCE" "5%"
					( Origin gFrontEnd )
				)
				( attribute "VALUE" "0.0"
					( Origin gFrontEnd )
				)
				( attribute "VER" "2"
					( Origin gFrontEnd )
				)
				( attribute "WATTAGE" "1/16W"
					( Origin gFrontEnd )
				)
				( attribute "XY" "(-7450,3500)"
					( Origin gFrontEnd )
				)
				( attribute "CHIPS_PART_NAME" "RES"
					( Origin gPackager )
				)
				( attribute "CDS_PART_NAME" "RES_0402-0.0,5%,1/16W,EMPTY,G2A"
					( Origin gPackager )
				)
				( objectStatus "R1U62" )
				( pin "a"
					( attribute "PN" "1"
						( Origin gPackager )
					)
					( objectStatus "R1U62.1" )
				)
				( pin "b"
					( attribute "PN" "2"
						( Origin gPackager )
					)
					( objectStatus "R1U62.2" )
				)
			)
			( gate "@baseboard_fab2_lib.baseboard_fab2(sch_1):page152_i69"
				( attribute "CDS_LIB" "mstr_discrete"
					( Origin gPackager )
				)
				( attribute "CDS_LOCATION" "R1U57"
					( Origin gPackager )
				)
				( attribute "CDS_SEC" "1"
					( Origin gPackager )
				)
				( attribute "LOCATION" "R1U57"
					( Origin gFrontEnd )
				)
				( attribute "MATERIAL" "EMPTY"
					( Origin gFrontEnd )
				)
				( attribute "PACK_TYPE" "0402"
					( Origin gFrontEnd )
				)
				( attribute "PART_NUMBER" "G21497-005"
					( Origin gFrontEnd )
				)
				( attribute "PHYS_PAGE" "152"
					( Origin gFrontEnd )
				)
				( attribute "ROT" "0"
					( Origin gFrontEnd )
				)
				( attribute "SEC" "1"
					( Origin gFrontEnd )
				)
				( attribute "SEC_TYPE" "0402"
					( Origin gFrontEnd )
				)
				( attribute "TOLERANCE" "5%"
					( Origin gFrontEnd )
				)
				( attribute "VALUE" "0.0"
					( Origin gFrontEnd )
				)
				( attribute "VER" "2"
					( Origin gFrontEnd )
				)
				( attribute "WATTAGE" "1/16W"
					( Origin gFrontEnd )
				)
				( attribute "XY" "(-3175,3425)"
					( Origin gFrontEnd )
				)
				( attribute "CHIPS_PART_NAME" "RES"
					( Origin gPackager )
				)
				( attribute "CDS_PART_NAME" "RES_0402-0.0,5%,1/16W,EMPTY,G2A"
					( Origin gPackager )
				)
				( objectStatus "R1U57" )
				( pin "a"
					( attribute "PN" "1"
						( Origin gPackager )
					)
					( objectStatus "R1U57.1" )
				)
				( pin "b"
					( attribute "PN" "2"
						( Origin gPackager )
					)
					( objectStatus "R1U57.2" )
				)
			)
			( gate "@baseboard_fab2_lib.baseboard_fab2(sch_1):page152_i70"
				( attribute "CDS_LIB" "mstr_discrete"
					( Origin gPackager )
				)
				( attribute "CDS_LOCATION" "R1U61"
					( Origin gPackager )
				)
				( attribute "CDS_SEC" "1"
					( Origin gPackager )
				)
				( attribute "LOCATION" "R1U61"
					( Origin gFrontEnd )
				)
				( attribute "MATERIAL" "EMPTY"
					( Origin gFrontEnd )
				)
				( attribute "PACK_TYPE" "0402"
					( Origin gFrontEnd )
				)
				( attribute "PART_NUMBER" "G21497-005"
					( Origin gFrontEnd )
				)
				( attribute "PHYS_PAGE" "152"
					( Origin gFrontEnd )
				)
				( attribute "ROT" "0"
					( Origin gFrontEnd )
				)
				( attribute "SEC" "1"
					( Origin gFrontEnd )
				)
				( attribute "SEC_TYPE" "0402"
					( Origin gFrontEnd )
				)
				( attribute "TOLERANCE" "5%"
					( Origin gFrontEnd )
				)
				( attribute "VALUE" "0.0"
					( Origin gFrontEnd )
				)
				( attribute "VER" "2"
					( Origin gFrontEnd )
				)
				( attribute "WATTAGE" "1/16W"
					( Origin gFrontEnd )
				)
				( attribute "XY" "(-2875,3425)"
					( Origin gFrontEnd )
				)
				( attribute "CHIPS_PART_NAME" "RES"
					( Origin gPackager )
				)
				( attribute "CDS_PART_NAME" "RES_0402-0.0,5%,1/16W,EMPTY,G2A"
					( Origin gPackager )
				)
				( objectStatus "R1U61" )
				( pin "a"
					( attribute "PN" "1"
						( Origin gPackager )
					)
					( objectStatus "R1U61.1" )
				)
				( pin "b"
					( attribute "PN" "2"
						( Origin gPackager )
					)
					( objectStatus "R1U61.2" )
				)
			)
			( gate "@baseboard_fab2_lib.baseboard_fab2(sch_1):page152_i71"
				( attribute "CDS_LIB" "mstr_discrete"
					( Origin gPackager )
				)
				( attribute "CDS_LOCATION" "R9G28"
					( Origin gPackager )
				)
				( attribute "CDS_SEC" "1"
					( Origin gPackager )
				)
				( attribute "LOCATION" "R9G28"
					( Origin gFrontEnd )
				)
				( attribute "MATERIAL" "CHIP"
					( Origin gFrontEnd )
				)
				( attribute "PACK_TYPE" "0402"
					( Origin gFrontEnd )
				)
				( attribute "PART_NUMBER" "G21497-005"
					( Origin gFrontEnd )
				)
				( attribute "PHYS_PAGE" "152"
					( Origin gFrontEnd )
				)
				( attribute "ROT" "0"
					( Origin gFrontEnd )
				)
				( attribute "SEC" "1"
					( Origin gFrontEnd )
				)
				( attribute "SEC_TYPE" "0402"
					( Origin gFrontEnd )
				)
				( attribute "TOLERANCE" "5%"
					( Origin gFrontEnd )
				)
				( attribute "VALUE" "0.0"
					( Origin gFrontEnd )
				)
				( attribute "VER" "1"
					( Origin gFrontEnd )
				)
				( attribute "WATTAGE" "1/16W"
					( Origin gFrontEnd )
				)
				( attribute "XY" "(-3375,3725)"
					( Origin gFrontEnd )
				)
				( attribute "CHIPS_PART_NAME" "RES"
					( Origin gPackager )
				)
				( attribute "CDS_PART_NAME" "RES_0402-0.0,5%,1/16W,CHIP,G21A"
					( Origin gPackager )
				)
				( objectStatus "R9G28" )
				( pin "a"
					( attribute "PN" "1"
						( Origin gPackager )
					)
					( objectStatus "R9G28.1" )
				)
				( pin "b"
					( attribute "PN" "2"
						( Origin gPackager )
					)
					( objectStatus "R9G28.2" )
				)
			)
			( gate "@baseboard_fab2_lib.baseboard_fab2(sch_1):page152_i72"
				( attribute "CDS_LIB" "mstr_discrete"
					( Origin gPackager )
				)
				( attribute "CDS_LOCATION" "R9G32"
					( Origin gPackager )
				)
				( attribute "CDS_SEC" "1"
					( Origin gPackager )
				)
				( attribute "LOCATION" "R9G32"
					( Origin gFrontEnd )
				)
				( attribute "MATERIAL" "CHIP"
					( Origin gFrontEnd )
				)
				( attribute "PACK_TYPE" "0402"
					( Origin gFrontEnd )
				)
				( attribute "PART_NUMBER" "G21497-005"
					( Origin gFrontEnd )
				)
				( attribute "PHYS_PAGE" "152"
					( Origin gFrontEnd )
				)
				( attribute "ROT" "0"
					( Origin gFrontEnd )
				)
				( attribute "SEC" "1"
					( Origin gFrontEnd )
				)
				( attribute "SEC_TYPE" "0402"
					( Origin gFrontEnd )
				)
				( attribute "TOLERANCE" "5%"
					( Origin gFrontEnd )
				)
				( attribute "VALUE" "0.0"
					( Origin gFrontEnd )
				)
				( attribute "VER" "1"
					( Origin gFrontEnd )
				)
				( attribute "WATTAGE" "1/16W"
					( Origin gFrontEnd )
				)
				( attribute "XY" "(-3375,3900)"
					( Origin gFrontEnd )
				)
				( attribute "CHIPS_PART_NAME" "RES"
					( Origin gPackager )
				)
				( attribute "CDS_PART_NAME" "RES_0402-0.0,5%,1/16W,CHIP,G21A"
					( Origin gPackager )
				)
				( objectStatus "R9G32" )
				( pin "a"
					( attribute "PN" "1"
						( Origin gPackager )
					)
					( objectStatus "R9G32.1" )
				)
				( pin "b"
					( attribute "PN" "2"
						( Origin gPackager )
					)
					( objectStatus "R9G32.2" )
				)
			)
			( gate "@baseboard_fab2_lib.baseboard_fab2(sch_1):page152_i73"
				( attribute "CDS_LIB" "mstr_discrete"
					( Origin gPackager )
				)
				( attribute "CDS_LOCATION" "R9G33"
					( Origin gPackager )
				)
				( attribute "CDS_SEC" "1"
					( Origin gPackager )
				)
				( attribute "LOCATION" "R9G33"
					( Origin gFrontEnd )
				)
				( attribute "MATERIAL" "CHIP"
					( Origin gFrontEnd )
				)
				( attribute "PACK_TYPE" "0402"
					( Origin gFrontEnd )
				)
				( attribute "PART_NUMBER" "G21497-005"
					( Origin gFrontEnd )
				)
				( attribute "PHYS_PAGE" "152"
					( Origin gFrontEnd )
				)
				( attribute "ROT" "0"
					( Origin gFrontEnd )
				)
				( attribute "SEC" "1"
					( Origin gFrontEnd )
				)
				( attribute "SEC_TYPE" "0402"
					( Origin gFrontEnd )
				)
				( attribute "TOLERANCE" "5%"
					( Origin gFrontEnd )
				)
				( attribute "VALUE" "0.0"
					( Origin gFrontEnd )
				)
				( attribute "VER" "1"
					( Origin gFrontEnd )
				)
				( attribute "WATTAGE" "1/16W"
					( Origin gFrontEnd )
				)
				( attribute "XY" "(-3375,4075)"
					( Origin gFrontEnd )
				)
				( attribute "CHIPS_PART_NAME" "RES"
					( Origin gPackager )
				)
				( attribute "CDS_PART_NAME" "RES_0402-0.0,5%,1/16W,CHIP,G21A"
					( Origin gPackager )
				)
				( objectStatus "R9G33" )
				( pin "a"
					( attribute "PN" "1"
						( Origin gPackager )
					)
					( objectStatus "R9G33.1" )
				)
				( pin "b"
					( attribute "PN" "2"
						( Origin gPackager )
					)
					( objectStatus "R9G33.2" )
				)
			)
			( gate "@baseboard_fab2_lib.baseboard_fab2(sch_1):page152_i74"
				( attribute "CDS_LIB" "mstr_discrete"
					( Origin gPackager )
				)
				( attribute "CDS_LOCATION" "R1U59"
					( Origin gPackager )
				)
				( attribute "CDS_SEC" "1"
					( Origin gPackager )
				)
				( attribute "LOCATION" "R1U59"
					( Origin gFrontEnd )
				)
				( attribute "MATERIAL" "CHIP"
					( Origin gFrontEnd )
				)
				( attribute "PACK_TYPE" "0402"
					( Origin gFrontEnd )
				)
				( attribute "PART_NUMBER" "G21497-005"
					( Origin gFrontEnd )
				)
				( attribute "PHYS_PAGE" "152"
					( Origin gFrontEnd )
				)
				( attribute "ROT" "0"
					( Origin gFrontEnd )
				)
				( attribute "SEC" "1"
					( Origin gFrontEnd )
				)
				( attribute "SEC_TYPE" "0402"
					( Origin gFrontEnd )
				)
				( attribute "TOLERANCE" "5%"
					( Origin gFrontEnd )
				)
				( attribute "VALUE" "0.0"
					( Origin gFrontEnd )
				)
				( attribute "VER" "1"
					( Origin gFrontEnd )
				)
				( attribute "WATTAGE" "1/16W"
					( Origin gFrontEnd )
				)
				( attribute "XY" "(-3375,4250)"
					( Origin gFrontEnd )
				)
				( attribute "CHIPS_PART_NAME" "RES"
					( Origin gPackager )
				)
				( attribute "CDS_PART_NAME" "RES_0402-0.0,5%,1/16W,CHIP,G21A"
					( Origin gPackager )
				)
				( objectStatus "R1U59" )
				( pin "a"
					( attribute "PN" "1"
						( Origin gPackager )
					)
					( objectStatus "R1U59.1" )
				)
				( pin "b"
					( attribute "PN" "2"
						( Origin gPackager )
					)
					( objectStatus "R1U59.2" )
				)
			)
			( gate "@baseboard_fab2_lib.baseboard_fab2(sch_1):page152_i79"
				( attribute "CDS_LIB" "mstr_discrete"
					( Origin gPackager )
				)
				( attribute "CDS_LOCATION" "R2U47"
					( Origin gPackager )
				)
				( attribute "CDS_SEC" "1"
					( Origin gPackager )
				)
				( attribute "LOCATION" "R2U47"
					( Origin gFrontEnd )
				)
				( attribute "MATERIAL" "CHIP"
					( Origin gFrontEnd )
				)
				( attribute "PACK_TYPE" "0402"
					( Origin gFrontEnd )
				)
				( attribute "PART_NUMBER" "G21497-005"
					( Origin gFrontEnd )
				)
				( attribute "PHYS_PAGE" "152"
					( Origin gFrontEnd )
				)
				( attribute "ROT" "0"
					( Origin gFrontEnd )
				)
				( attribute "SEC" "1"
					( Origin gFrontEnd )
				)
				( attribute "SEC_TYPE" "0402"
					( Origin gFrontEnd )
				)
				( attribute "TOLERANCE" "5%"
					( Origin gFrontEnd )
				)
				( attribute "VALUE" "0.0"
					( Origin gFrontEnd )
				)
				( attribute "VER" "1"
					( Origin gFrontEnd )
				)
				( attribute "WATTAGE" "1/16W"
					( Origin gFrontEnd )
				)
				( attribute "XY" "(-6700,2475)"
					( Origin gFrontEnd )
				)
				( attribute "CHIPS_PART_NAME" "RES"
					( Origin gPackager )
				)
				( attribute "CDS_PART_NAME" "RES_0402-0.0,5%,1/16W,CHIP,G21A"
					( Origin gPackager )
				)
				( objectStatus "R2U47" )
				( pin "a"
					( attribute "PN" "1"
						( Origin gPackager )
					)
					( objectStatus "R2U47.1" )
				)
				( pin "b"
					( attribute "PN" "2"
						( Origin gPackager )
					)
					( objectStatus "R2U47.2" )
				)
			)
			( gate "@baseboard_fab2_lib.baseboard_fab2(sch_1):page152_i92"
				( attribute "CDS_LIB" "mstr_discrete"
					( Origin gPackager )
				)
				( attribute "CDS_LOCATION" "R9G29"
					( Origin gPackager )
				)
				( attribute "CDS_SEC" "1"
					( Origin gPackager )
				)
				( attribute "LOCATION" "R9G29"
					( Origin gFrontEnd )
				)
				( attribute "MATERIAL" "CHIP"
					( Origin gFrontEnd )
				)
				( attribute "PACK_TYPE" "0402"
					( Origin gFrontEnd )
				)
				( attribute "PART_NUMBER" "G21497-005"
					( Origin gFrontEnd )
				)
				( attribute "PHYS_PAGE" "152"
					( Origin gFrontEnd )
				)
				( attribute "ROT" "0"
					( Origin gFrontEnd )
				)
				( attribute "SEC" "1"
					( Origin gFrontEnd )
				)
				( attribute "SEC_TYPE" "0402"
					( Origin gFrontEnd )
				)
				( attribute "TOLERANCE" "5%"
					( Origin gFrontEnd )
				)
				( attribute "VALUE" "0.0"
					( Origin gFrontEnd )
				)
				( attribute "VER" "1"
					( Origin gFrontEnd )
				)
				( attribute "WATTAGE" "1/16W"
					( Origin gFrontEnd )
				)
				( attribute "XY" "(-6700,2025)"
					( Origin gFrontEnd )
				)
				( attribute "CHIPS_PART_NAME" "RES"
					( Origin gPackager )
				)
				( attribute "CDS_PART_NAME" "RES_0402-0.0,5%,1/16W,CHIP,G21A"
					( Origin gPackager )
				)
				( objectStatus "R9G29" )
				( pin "a"
					( attribute "PN" "1"
						( Origin gPackager )
					)
					( objectStatus "R9G29.1" )
				)
				( pin "b"
					( attribute "PN" "2"
						( Origin gPackager )
					)
					( objectStatus "R9G29.2" )
				)
			)
			( gate "@baseboard_fab2_lib.baseboard_fab2(sch_1):page152_i93"
				( attribute "CDS_LIB" "mstr_discrete"
					( Origin gPackager )
				)
				( attribute "CDS_LOCATION" "R1U54"
					( Origin gPackager )
				)
				( attribute "CDS_SEC" "1"
					( Origin gPackager )
				)
				( attribute "LOCATION" "R1U54"
					( Origin gFrontEnd )
				)
				( attribute "MATERIAL" "CHIP"
					( Origin gFrontEnd )
				)
				( attribute "PACK_TYPE" "0402"
					( Origin gFrontEnd )
				)
				( attribute "PART_NUMBER" "G21497-005"
					( Origin gFrontEnd )
				)
				( attribute "PHYS_PAGE" "152"
					( Origin gFrontEnd )
				)
				( attribute "ROT" "0"
					( Origin gFrontEnd )
				)
				( attribute "SEC" "1"
					( Origin gFrontEnd )
				)
				( attribute "SEC_TYPE" "0402"
					( Origin gFrontEnd )
				)
				( attribute "TOLERANCE" "5%"
					( Origin gFrontEnd )
				)
				( attribute "VALUE" "0.0"
					( Origin gFrontEnd )
				)
				( attribute "VER" "1"
					( Origin gFrontEnd )
				)
				( attribute "WATTAGE" "1/16W"
					( Origin gFrontEnd )
				)
				( attribute "XY" "(-6700,1600)"
					( Origin gFrontEnd )
				)
				( attribute "CHIPS_PART_NAME" "RES"
					( Origin gPackager )
				)
				( attribute "CDS_PART_NAME" "RES_0402-0.0,5%,1/16W,CHIP,G21A"
					( Origin gPackager )
				)
				( objectStatus "R1U54" )
				( pin "a"
					( attribute "PN" "1"
						( Origin gPackager )
					)
					( objectStatus "R1U54.1" )
				)
				( pin "b"
					( attribute "PN" "2"
						( Origin gPackager )
					)
					( objectStatus "R1U54.2" )
				)
			)
			( gate "@baseboard_fab2_lib.baseboard_fab2(sch_1):page152_i94"
				( attribute "CDS_LIB" "mstr_discrete"
					( Origin gPackager )
				)
				( attribute "CDS_LOCATION" "R2U46"
					( Origin gPackager )
				)
				( attribute "CDS_SEC" "1"
					( Origin gPackager )
				)
				( attribute "LOCATION" "R2U46"
					( Origin gFrontEnd )
				)
				( attribute "MATERIAL" "CHIP"
					( Origin gFrontEnd )
				)
				( attribute "PACK_TYPE" "0402"
					( Origin gFrontEnd )
				)
				( attribute "PART_NUMBER" "G21497-005"
					( Origin gFrontEnd )
				)
				( attribute "PHYS_PAGE" "152"
					( Origin gFrontEnd )
				)
				( attribute "ROT" "0"
					( Origin gFrontEnd )
				)
				( attribute "SEC" "1"
					( Origin gFrontEnd )
				)
				( attribute "SEC_TYPE" "0402"
					( Origin gFrontEnd )
				)
				( attribute "TOLERANCE" "5%"
					( Origin gFrontEnd )
				)
				( attribute "VALUE" "0.0"
					( Origin gFrontEnd )
				)
				( attribute "VER" "1"
					( Origin gFrontEnd )
				)
				( attribute "WATTAGE" "1/16W"
					( Origin gFrontEnd )
				)
				( attribute "XY" "(-6700,1175)"
					( Origin gFrontEnd )
				)
				( attribute "CHIPS_PART_NAME" "RES"
					( Origin gPackager )
				)
				( attribute "CDS_PART_NAME" "RES_0402-0.0,5%,1/16W,CHIP,G21A"
					( Origin gPackager )
				)
				( objectStatus "R2U46" )
				( pin "a"
					( attribute "PN" "1"
						( Origin gPackager )
					)
					( objectStatus "R2U46.1" )
				)
				( pin "b"
					( attribute "PN" "2"
						( Origin gPackager )
					)
					( objectStatus "R2U46.2" )
				)
			)
			( gate "@baseboard_fab2_lib.baseboard_fab2(sch_1):page152_i95"
				( attribute "CDS_LIB" "mstr_discrete"
					( Origin gPackager )
				)
				( attribute "CDS_LOCATION" "R3N30"
					( Origin gPackager )
				)
				( attribute "CDS_SEC" "1"
					( Origin gPackager )
				)
				( attribute "LOCATION" "R3N30"
					( Origin gFrontEnd )
				)
				( attribute "MATERIAL" "EMPTY"
					( Origin gFrontEnd )
				)
				( attribute "PACK_TYPE" "0402"
					( Origin gFrontEnd )
				)
				( attribute "PART_NUMBER" "G21497-005"
					( Origin gFrontEnd )
				)
				( attribute "PHYS_PAGE" "152"
					( Origin gFrontEnd )
				)
				( attribute "ROT" "0"
					( Origin gFrontEnd )
				)
				( attribute "SEC" "1"
					( Origin gPackager )
				)
				( attribute "TOLERANCE" "5%"
					( Origin gFrontEnd )
				)
				( attribute "VALUE" "0.0"
					( Origin gFrontEnd )
				)
				( attribute "VER" "1"
					( Origin gFrontEnd )
				)
				( attribute "WATTAGE" "1/16W"
					( Origin gFrontEnd )
				)
				( attribute "XY" "(-6700,2275)"
					( Origin gFrontEnd )
				)
				( attribute "CHIPS_PART_NAME" "RES"
					( Origin gPackager )
				)
				( attribute "CDS_PART_NAME" "RES_0402-0.0,5%,1/16W,EMPTY,G2A"
					( Origin gPackager )
				)
				( objectStatus "R3N30" )
				( pin "a"
					( attribute "PN" "1"
						( Origin gPackager )
					)
					( objectStatus "R3N30.1" )
				)
				( pin "b"
					( attribute "PN" "2"
						( Origin gPackager )
					)
					( objectStatus "R3N30.2" )
				)
			)
			( gate "@baseboard_fab2_lib.baseboard_fab2(sch_1):page152_i98"
				( attribute "CDS_LIB" "mstr_discrete"
					( Origin gPackager )
				)
				( attribute "CDS_LOCATION" "R9G30"
					( Origin gPackager )
				)
				( attribute "CDS_SEC" "1"
					( Origin gPackager )
				)
				( attribute "LOCATION" "R9G30"
					( Origin gFrontEnd )
				)
				( attribute "MATERIAL" "EMPTY"
					( Origin gFrontEnd )
				)
				( attribute "PACK_TYPE" "0402"
					( Origin gFrontEnd )
				)
				( attribute "PART_NUMBER" "G21497-005"
					( Origin gFrontEnd )
				)
				( attribute "PHYS_PAGE" "152"
					( Origin gFrontEnd )
				)
				( attribute "ROT" "0"
					( Origin gFrontEnd )
				)
				( attribute "SEC" "1"
					( Origin gPackager )
				)
				( attribute "TOLERANCE" "5%"
					( Origin gFrontEnd )
				)
				( attribute "VALUE" "0.0"
					( Origin gFrontEnd )
				)
				( attribute "VER" "1"
					( Origin gFrontEnd )
				)
				( attribute "WATTAGE" "1/16W"
					( Origin gFrontEnd )
				)
				( attribute "XY" "(-6700,1825)"
					( Origin gFrontEnd )
				)
				( attribute "CHIPS_PART_NAME" "RES"
					( Origin gPackager )
				)
				( attribute "CDS_PART_NAME" "RES_0402-0.0,5%,1/16W,EMPTY,G2A"
					( Origin gPackager )
				)
				( objectStatus "R9G30" )
				( pin "a"
					( attribute "PN" "1"
						( Origin gPackager )
					)
					( objectStatus "R9G30.1" )
				)
				( pin "b"
					( attribute "PN" "2"
						( Origin gPackager )
					)
					( objectStatus "R9G30.2" )
				)
			)
			( gate "@baseboard_fab2_lib.baseboard_fab2(sch_1):page152_i100"
				( attribute "CDS_LIB" "mstr_discrete"
					( Origin gPackager )
				)
				( attribute "CDS_LOCATION" "R3P63"
					( Origin gPackager )
				)
				( attribute "CDS_SEC" "1"
					( Origin gPackager )
				)
				( attribute "LOCATION" "R3P63"
					( Origin gFrontEnd )
				)
				( attribute "MATERIAL" "EMPTY"
					( Origin gFrontEnd )
				)
				( attribute "PACK_TYPE" "0402"
					( Origin gFrontEnd )
				)
				( attribute "PART_NUMBER" "G21497-005"
					( Origin gFrontEnd )
				)
				( attribute "PHYS_PAGE" "152"
					( Origin gFrontEnd )
				)
				( attribute "ROT" "0"
					( Origin gFrontEnd )
				)
				( attribute "SEC" "1"
					( Origin gPackager )
				)
				( attribute "TOLERANCE" "5%"
					( Origin gFrontEnd )
				)
				( attribute "VALUE" "0.0"
					( Origin gFrontEnd )
				)
				( attribute "VER" "1"
					( Origin gFrontEnd )
				)
				( attribute "WATTAGE" "1/16W"
					( Origin gFrontEnd )
				)
				( attribute "XY" "(-6700,1400)"
					( Origin gFrontEnd )
				)
				( attribute "CHIPS_PART_NAME" "RES"
					( Origin gPackager )
				)
				( attribute "CDS_PART_NAME" "RES_0402-0.0,5%,1/16W,EMPTY,G2A"
					( Origin gPackager )
				)
				( objectStatus "R3P63" )
				( pin "a"
					( attribute "PN" "1"
						( Origin gPackager )
					)
					( objectStatus "R3P63.1" )
				)
				( pin "b"
					( attribute "PN" "2"
						( Origin gPackager )
					)
					( objectStatus "R3P63.2" )
				)
			)
			( gate "@baseboard_fab2_lib.baseboard_fab2(sch_1):page152_i102"
				( attribute "CDS_LIB" "mstr_discrete"
					( Origin gPackager )
				)
				( attribute "CDS_LOCATION" "R2U45"
					( Origin gPackager )
				)
				( attribute "CDS_SEC" "1"
					( Origin gPackager )
				)
				( attribute "LOCATION" "R2U45"
					( Origin gFrontEnd )
				)
				( attribute "MATERIAL" "EMPTY"
					( Origin gFrontEnd )
				)
				( attribute "PACK_TYPE" "0402"
					( Origin gFrontEnd )
				)
				( attribute "PART_NUMBER" "G21497-005"
					( Origin gFrontEnd )
				)
				( attribute "PHYS_PAGE" "152"
					( Origin gFrontEnd )
				)
				( attribute "ROT" "0"
					( Origin gFrontEnd )
				)
				( attribute "SEC" "1"
					( Origin gPackager )
				)
				( attribute "TOLERANCE" "5%"
					( Origin gFrontEnd )
				)
				( attribute "VALUE" "0.0"
					( Origin gFrontEnd )
				)
				( attribute "VER" "1"
					( Origin gFrontEnd )
				)
				( attribute "WATTAGE" "1/16W"
					( Origin gFrontEnd )
				)
				( attribute "XY" "(-6700,975)"
					( Origin gFrontEnd )
				)
				( attribute "CHIPS_PART_NAME" "RES"
					( Origin gPackager )
				)
				( attribute "CDS_PART_NAME" "RES_0402-0.0,5%,1/16W,EMPTY,G2A"
					( Origin gPackager )
				)
				( objectStatus "R2U45" )
				( pin "a"
					( attribute "PN" "1"
						( Origin gPackager )
					)
					( objectStatus "R2U45.1" )
				)
				( pin "b"
					( attribute "PN" "2"
						( Origin gPackager )
					)
					( objectStatus "R2U45.2" )
				)
			)
			( gate "@baseboard_fab2_lib.baseboard_fab2(sch_1):page153_i90"
				( attribute "BOM_COST" "MIO_BIOS_MEM"
					( Origin gFrontEnd )
				)
				( attribute "CDS_LIB" "mstr_discrete"
					( Origin gPackager )
				)
				( attribute "CDS_LOCATION" "R7F6"
					( Origin gPackager )
				)
				( attribute "CDS_SEC" "1"
					( Origin gPackager )
				)
				( attribute "LOCATION" "R7F6"
					( Origin gFrontEnd )
				)
				( attribute "MATERIAL" "EMPTY"
					( Origin gFrontEnd )
				)
				( attribute "NO_XNET_CONNECTION" "1"
					( Origin gFrontEnd )
				)
				( attribute "PACK_TYPE" "0402"
					( Origin gFrontEnd )
				)
				( attribute "PART_NUMBER" "G21796-072"
					( Origin gFrontEnd )
				)
				( attribute "PHYS_PAGE" "153"
					( Origin gFrontEnd )
				)
				( attribute "ROOM" "SB_SPI"
					( Origin gFrontEnd )
				)
				( attribute "ROT" "2"
					( Origin gFrontEnd )
				)
				( attribute "SEC" "1"
					( Origin gFrontEnd )
				)
				( attribute "SEC_TYPE" "0402"
					( Origin gFrontEnd )
				)
				( attribute "TOLERANCE" "1%"
					( Origin gFrontEnd )
				)
				( attribute "VALUE" "4.75K"
					( Origin gFrontEnd )
				)
				( attribute "VER" "2"
					( Origin gFrontEnd )
				)
				( attribute "WATTAGE" "1/16W"
					( Origin gFrontEnd )
				)
				( attribute "XY" "(-5950,4425)"
					( Origin gFrontEnd )
				)
				( attribute "CHIPS_PART_NAME" "RES"
					( Origin gPackager )
				)
				( attribute "CDS_PART_NAME" "RES_0402-4.75K,1%,1/16W,EMPTY,A"
					( Origin gPackager )
				)
				( objectStatus "R7F6" )
				( pin "a"
					( attribute "PN" "1"
						( Origin gPackager )
					)
					( objectStatus "R7F6.1" )
				)
				( pin "b"
					( attribute "PN" "2"
						( Origin gPackager )
					)
					( objectStatus "R7F6.2" )
				)
			)
			( gate "@baseboard_fab2_lib.baseboard_fab2(sch_1):page153_i94"
				( attribute "BOM_COST" "MIO_BIOS_MEM"
					( Origin gFrontEnd )
				)
				( attribute "CDS_LIB" "mstr_discrete"
					( Origin gPackager )
				)
				( attribute "CDS_LOCATION" "R7F5"
					( Origin gPackager )
				)
				( attribute "CDS_SEC" "1"
					( Origin gPackager )
				)
				( attribute "LOCATION" "R7F5"
					( Origin gFrontEnd )
				)
				( attribute "MATERIAL" "CHIP"
					( Origin gFrontEnd )
				)
				( attribute "NO_XNET_CONNECTION" "1"
					( Origin gFrontEnd )
				)
				( attribute "PACK_TYPE" "0402"
					( Origin gFrontEnd )
				)
				( attribute "PART_NUMBER" "G21796-072"
					( Origin gFrontEnd )
				)
				( attribute "PHYS_PAGE" "153"
					( Origin gFrontEnd )
				)
				( attribute "ROOM" "SB_SPI"
					( Origin gFrontEnd )
				)
				( attribute "ROT" "2"
					( Origin gFrontEnd )
				)
				( attribute "SEC" "1"
					( Origin gFrontEnd )
				)
				( attribute "SEC_TYPE" "0402"
					( Origin gFrontEnd )
				)
				( attribute "TOLERANCE" "1%"
					( Origin gFrontEnd )
				)
				( attribute "VALUE" "4.75K"
					( Origin gFrontEnd )
				)
				( attribute "VER" "2"
					( Origin gFrontEnd )
				)
				( attribute "WATTAGE" "1/16W"
					( Origin gFrontEnd )
				)
				( attribute "XY" "(-6250,4425)"
					( Origin gFrontEnd )
				)
				( attribute "CHIPS_PART_NAME" "RES"
					( Origin gPackager )
				)
				( attribute "CDS_PART_NAME" "RES_0402-4.75K,1%,1/16W,CHIP,GA"
					( Origin gPackager )
				)
				( objectStatus "R7F5" )
				( pin "a"
					( attribute "PN" "1"
						( Origin gPackager )
					)
					( objectStatus "R7F5.1" )
				)
				( pin "b"
					( attribute "PN" "2"
						( Origin gPackager )
					)
					( objectStatus "R7F5.2" )
				)
			)
			( gate "@baseboard_fab2_lib.baseboard_fab2(sch_1):page153_i98"
				( attribute "BOM_COST" "MIO_BIOS_MEM"
					( Origin gFrontEnd )
				)
				( attribute "CDS_LIB" "mstr_discrete"
					( Origin gPackager )
				)
				( attribute "CDS_LOCATION" "R7F4"
					( Origin gPackager )
				)
				( attribute "CDS_SEC" "1"
					( Origin gPackager )
				)
				( attribute "LOCATION" "R7F4"
					( Origin gFrontEnd )
				)
				( attribute "MATERIAL" "CHIP"
					( Origin gFrontEnd )
				)
				( attribute "PACK_TYPE" "0402"
					( Origin gFrontEnd )
				)
				( attribute "PART_NUMBER" "G21796-074"
					( Origin gFrontEnd )
				)
				( attribute "PHYS_PAGE" "153"
					( Origin gFrontEnd )
				)
				( attribute "ROOM" "SB_SPI"
					( Origin gFrontEnd )
				)
				( attribute "ROT" "0"
					( Origin gFrontEnd )
				)
				( attribute "SEC" "1"
					( Origin gFrontEnd )
				)
				( attribute "SEC_TYPE" "0402"
					( Origin gFrontEnd )
				)
				( attribute "TOLERANCE" "1%"
					( Origin gFrontEnd )
				)
				( attribute "VALUE" "33.2"
					( Origin gFrontEnd )
				)
				( attribute "VER" "1"
					( Origin gFrontEnd )
				)
				( attribute "WATTAGE" "1/16W"
					( Origin gFrontEnd )
				)
				( attribute "XY" "(-6275,3975)"
					( Origin gFrontEnd )
				)
				( attribute "CHIPS_PART_NAME" "RES"
					( Origin gPackager )
				)
				( attribute "CDS_PART_NAME" "RES_0402-33.2,1%,1/16W,CHIP,G2A"
					( Origin gPackager )
				)
				( objectStatus "R7F4" )
				( pin "a"
					( attribute "PN" "1"
						( Origin gPackager )
					)
					( objectStatus "R7F4.1" )
				)
				( pin "b"
					( attribute "PN" "2"
						( Origin gPackager )
					)
					( objectStatus "R7F4.2" )
				)
			)
			( gate "@baseboard_fab2_lib.baseboard_fab2(sch_1):page153_i108"
				( attribute "BOM_COST" "MIO_BIOS_MEM"
					( Origin gFrontEnd )
				)
				( attribute "CDS_LIB" "mstr_discrete"
					( Origin gPackager )
				)
				( attribute "CDS_LOCATION" "R7F37"
					( Origin gPackager )
				)
				( attribute "CDS_SEC" "1"
					( Origin gPackager )
				)
				( attribute "LOCATION" "R7F37"
					( Origin gFrontEnd )
				)
				( attribute "MATERIAL" "CHIP"
					( Origin gFrontEnd )
				)
				( attribute "PACK_TYPE" "0402"
					( Origin gFrontEnd )
				)
				( attribute "PART_NUMBER" "G21796-074"
					( Origin gFrontEnd )
				)
				( attribute "PHYS_PAGE" "153"
					( Origin gFrontEnd )
				)
				( attribute "ROOM" "SB_SPI"
					( Origin gFrontEnd )
				)
				( attribute "ROT" "0"
					( Origin gFrontEnd )
				)
				( attribute "SEC" "1"
					( Origin gPackager )
				)
				( attribute "TOLERANCE" "1%"
					( Origin gFrontEnd )
				)
				( attribute "VALUE" "33.2"
					( Origin gFrontEnd )
				)
				( attribute "VER" "1"
					( Origin gFrontEnd )
				)
				( attribute "WATTAGE" "1/16W"
					( Origin gFrontEnd )
				)
				( attribute "XY" "(-6500,3600)"
					( Origin gFrontEnd )
				)
				( attribute "CHIPS_PART_NAME" "RES"
					( Origin gPackager )
				)
				( attribute "CDS_PART_NAME" "RES_0402-33.2,1%,1/16W,CHIP,G2A"
					( Origin gPackager )
				)
				( objectStatus "R7F37" )
				( pin "a"
					( attribute "PN" "1"
						( Origin gPackager )
					)
					( objectStatus "R7F37.1" )
				)
				( pin "b"
					( attribute "PN" "2"
						( Origin gPackager )
					)
					( objectStatus "R7F37.2" )
				)
			)
			( gate "@baseboard_fab2_lib.baseboard_fab2(sch_1):page153_i109"
				( attribute "BOM_COST" "MIO_BIOS_MEM"
					( Origin gFrontEnd )
				)
				( attribute "CDS_LIB" "mstr_discrete"
					( Origin gPackager )
				)
				( attribute "CDS_LOCATION" "R7F3"
					( Origin gPackager )
				)
				( attribute "CDS_SEC" "1"
					( Origin gPackager )
				)
				( attribute "LOCATION" "R7F3"
					( Origin gFrontEnd )
				)
				( attribute "MATERIAL" "CHIP"
					( Origin gFrontEnd )
				)
				( attribute "NO_XNET_CONNECTION" "1"
					( Origin gFrontEnd )
				)
				( attribute "PACK_TYPE" "0402"
					( Origin gFrontEnd )
				)
				( attribute "PART_NUMBER" "G21796-074"
					( Origin gFrontEnd )
				)
				( attribute "PHYS_PAGE" "153"
					( Origin gFrontEnd )
				)
				( attribute "ROOM" "SB_SPI"
					( Origin gFrontEnd )
				)
				( attribute "ROT" "0"
					( Origin gFrontEnd )
				)
				( attribute "SEC" "1"
					( Origin gPackager )
				)
				( attribute "TOLERANCE" "1%"
					( Origin gFrontEnd )
				)
				( attribute "VALUE" "33.2"
					( Origin gFrontEnd )
				)
				( attribute "VER" "1"
					( Origin gFrontEnd )
				)
				( attribute "WATTAGE" "1/16W"
					( Origin gFrontEnd )
				)
				( attribute "XY" "(-6475,3325)"
					( Origin gFrontEnd )
				)
				( attribute "CHIPS_PART_NAME" "RES"
					( Origin gPackager )
				)
				( attribute "CDS_PART_NAME" "RES_0402-33.2,1%,1/16W,CHIP,G2A"
					( Origin gPackager )
				)
				( objectStatus "R7F3" )
				( pin "a"
					( attribute "PN" "1"
						( Origin gPackager )
					)
					( objectStatus "R7F3.1" )
				)
				( pin "b"
					( attribute "PN" "2"
						( Origin gPackager )
					)
					( objectStatus "R7F3.2" )
				)
			)
			( gate "@baseboard_fab2_lib.baseboard_fab2(sch_1):page153_i130"
				( attribute "BOM_COST" "MIO_BIOS_MEM"
					( Origin gFrontEnd )
				)
				( attribute "CDS_LIB" "dev_discrete"
					( Origin gPackager )
				)
				( attribute "CDS_LOCATION" "C7F2"
					( Origin gPackager )
				)
				( attribute "CDS_SEC" "1"
					( Origin gPackager )
				)
				( attribute "LOCATION" "C7F2"
					( Origin gFrontEnd )
				)
				( attribute "MATERIAL" "X6S"
					( Origin gFrontEnd )
				)
				( attribute "NO_XNET_CONNECTION" "1"
					( Origin gFrontEnd )
				)
				( attribute "PACK_TYPE" "0402V"
					( Origin gFrontEnd )
				)
				( attribute "PART_NUMBER" "D97712-004"
					( Origin gFrontEnd )
				)
				( attribute "PHYS_PAGE" "153"
					( Origin gFrontEnd )
				)
				( attribute "ROOM" "SB_SPI"
					( Origin gFrontEnd )
				)
				( attribute "ROT" "0"
					( Origin gFrontEnd )
				)
				( attribute "SEC" "1"
					( Origin gFrontEnd )
				)
				( attribute "SEC_TYPE" "0402V"
					( Origin gFrontEnd )
				)
				( attribute "TOLERANCE" "10%"
					( Origin gFrontEnd )
				)
				( attribute "VALUE" "1.0UF"
					( Origin gFrontEnd )
				)
				( attribute "VER" "1"
					( Origin gFrontEnd )
				)
				( attribute "VOLTAGE" "6.3V"
					( Units "uVoltage" "V" 1.000000)
					( Origin gFrontEnd )
				)
				( attribute "XY" "(-4075,4500)"
					( Origin gFrontEnd )
				)
				( attribute "CHIPS_PART_NAME" "CAP_A"
					( Origin gPackager )
				)
				( attribute "CDS_PART_NAME" "CAP_A_0402V-1.0UF,6.3V,10%,X6SA"
					( Origin gPackager )
				)
				( objectStatus "C7F2" )
				( pin "a"
					( attribute "PN" "1"
						( Origin gPackager )
					)
					( objectStatus "C7F2.1" )
				)
				( pin "b"
					( attribute "PN" "2"
						( Origin gPackager )
					)
					( objectStatus "C7F2.2" )
				)
			)
			( gate "@baseboard_fab2_lib.baseboard_fab2(sch_1):page153_i131"
				( attribute "BOM_COST" "MIO_BIOS_MEM"
					( Origin gFrontEnd )
				)
				( attribute "CDS_LIB" "dev_discrete"
					( Origin gPackager )
				)
				( attribute "CDS_LOCATION" "C7F1"
					( Origin gPackager )
				)
				( attribute "CDS_SEC" "1"
					( Origin gPackager )
				)
				( attribute "LOCATION" "C7F1"
					( Origin gFrontEnd )
				)
				( attribute "MATERIAL" "X7R"
					( Origin gFrontEnd )
				)
				( attribute "NO_XNET_CONNECTION" "1"
					( Origin gFrontEnd )
				)
				( attribute "PACK_TYPE" "0402V"
					( Origin gFrontEnd )
				)
				( attribute "PART_NUMBER" "A36096-045"
					( Origin gFrontEnd )
				)
				( attribute "PHYS_PAGE" "153"
					( Origin gFrontEnd )
				)
				( attribute "ROOM" "SB_SPI"
					( Origin gFrontEnd )
				)
				( attribute "ROT" "0"
					( Origin gFrontEnd )
				)
				( attribute "SEC" "1"
					( Origin gFrontEnd )
				)
				( attribute "SEC_TYPE" "0402V"
					( Origin gFrontEnd )
				)
				( attribute "TOLERANCE" "10%"
					( Origin gFrontEnd )
				)
				( attribute "VALUE" "0.01UF"
					( Origin gFrontEnd )
				)
				( attribute "VER" "1"
					( Origin gFrontEnd )
				)
				( attribute "VOLTAGE" "25V"
					( Units "uVoltage" "V" 1.000000)
					( Origin gFrontEnd )
				)
				( attribute "XY" "(-3775,4500)"
					( Origin gFrontEnd )
				)
				( attribute "CHIPS_PART_NAME" "CAP_A"
					( Origin gPackager )
				)
				( attribute "CDS_PART_NAME" "CAP_A_0402V-0.01UF,25V,10%,X7RA"
					( Origin gPackager )
				)
				( objectStatus "C7F1" )
				( pin "a"
					( attribute "PN" "1"
						( Origin gPackager )
					)
					( objectStatus "C7F1.1" )
				)
				( pin "b"
					( attribute "PN" "2"
						( Origin gPackager )
					)
					( objectStatus "C7F1.2" )
				)
			)
			( gate "@baseboard_fab2_lib.baseboard_fab2(sch_1):page153_i136"
				( attribute "BOM_COST" "MIO_BIOS_MEM"
					( Origin gFrontEnd )
				)
				( attribute "CDS_LIB" "dev_discrete"
					( Origin gPackager )
				)
				( attribute "CDS_LOCATION" "C3T5"
					( Origin gPackager )
				)
				( attribute "CDS_SEC" "1"
					( Origin gPackager )
				)
				( attribute "LOCATION" "C3T5"
					( Origin gFrontEnd )
				)
				( attribute "MATERIAL" "X7R"
					( Origin gFrontEnd )
				)
				( attribute "NO_XNET_CONNECTION" "1"
					( Origin gFrontEnd )
				)
				( attribute "PACK_TYPE" "0402V"
					( Origin gFrontEnd )
				)
				( attribute "PART_NUMBER" "A36096-045"
					( Origin gFrontEnd )
				)
				( attribute "PHYS_PAGE" "153"
					( Origin gFrontEnd )
				)
				( attribute "ROOM" "SB_SPI"
					( Origin gFrontEnd )
				)
				( attribute "ROT" "0"
					( Origin gFrontEnd )
				)
				( attribute "SEC" "1"
					( Origin gFrontEnd )
				)
				( attribute "SEC_TYPE" "0402V"
					( Origin gFrontEnd )
				)
				( attribute "TOLERANCE" "10%"
					( Origin gFrontEnd )
				)
				( attribute "VALUE" "0.01UF"
					( Origin gFrontEnd )
				)
				( attribute "VER" "1"
					( Origin gFrontEnd )
				)
				( attribute "VOLTAGE" "25V"
					( Units "uVoltage" "V" 1.000000)
					( Origin gFrontEnd )
				)
				( attribute "XY" "(-3625,2400)"
					( Origin gFrontEnd )
				)
				( attribute "CHIPS_PART_NAME" "CAP_A"
					( Origin gPackager )
				)
				( attribute "CDS_PART_NAME" "CAP_A_0402V-0.01UF,25V,10%,X7RA"
					( Origin gPackager )
				)
				( objectStatus "C3T5" )
				( pin "a"
					( attribute "PN" "1"
						( Origin gPackager )
					)
					( objectStatus "C3T5.1" )
				)
				( pin "b"
					( attribute "PN" "2"
						( Origin gPackager )
					)
					( objectStatus "C3T5.2" )
				)
			)
			( gate "@baseboard_fab2_lib.baseboard_fab2(sch_1):page153_i138"
				( attribute "BOM_COST" "MIO_BIOS_MEM"
					( Origin gFrontEnd )
				)
				( attribute "CDS_LIB" "dev_discrete"
					( Origin gPackager )
				)
				( attribute "CDS_LOCATION" "C3T4"
					( Origin gPackager )
				)
				( attribute "CDS_SEC" "1"
					( Origin gPackager )
				)
				( attribute "LOCATION" "C3T4"
					( Origin gFrontEnd )
				)
				( attribute "MATERIAL" "X6S"
					( Origin gFrontEnd )
				)
				( attribute "NO_XNET_CONNECTION" "1"
					( Origin gFrontEnd )
				)
				( attribute "PACK_TYPE" "0402V"
					( Origin gFrontEnd )
				)
				( attribute "PART_NUMBER" "D97712-004"
					( Origin gFrontEnd )
				)
				( attribute "PHYS_PAGE" "153"
					( Origin gFrontEnd )
				)
				( attribute "ROOM" "SB_SPI"
					( Origin gFrontEnd )
				)
				( attribute "ROT" "0"
					( Origin gFrontEnd )
				)
				( attribute "SEC" "1"
					( Origin gPackager )
				)
				( attribute "TOLERANCE" "10%"
					( Origin gFrontEnd )
				)
				( attribute "VALUE" "1.0UF"
					( Origin gFrontEnd )
				)
				( attribute "VER" "1"
					( Origin gFrontEnd )
				)
				( attribute "VOLTAGE" "6.3V"
					( Units "uVoltage" "V" 1.000000)
					( Origin gFrontEnd )
				)
				( attribute "XY" "(-3925,2400)"
					( Origin gFrontEnd )
				)
				( attribute "CHIPS_PART_NAME" "CAP_A"
					( Origin gPackager )
				)
				( attribute "CDS_PART_NAME" "CAP_A_0402V-1.0UF,6.3V,10%,X6SA"
					( Origin gPackager )
				)
				( objectStatus "C3T4" )
				( pin "a"
					( attribute "PN" "1"
						( Origin gPackager )
					)
					( objectStatus "C3T4.1" )
				)
				( pin "b"
					( attribute "PN" "2"
						( Origin gPackager )
					)
					( objectStatus "C3T4.2" )
				)
			)
			( gate "@baseboard_fab2_lib.baseboard_fab2(sch_1):page153_i140"
				( attribute "BOM_COST" "MIO_BIOS_MEM"
					( Origin gFrontEnd )
				)
				( attribute "CDS_LIB" "mstr_discrete"
					( Origin gPackager )
				)
				( attribute "CDS_LOCATION" "R7F32"
					( Origin gPackager )
				)
				( attribute "CDS_SEC" "1"
					( Origin gPackager )
				)
				( attribute "LOCATION" "R7F32"
					( Origin gFrontEnd )
				)
				( attribute "MATERIAL" "CHIP"
					( Origin gFrontEnd )
				)
				( attribute "NO_XNET_CONNECTION" "1"
					( Origin gFrontEnd )
				)
				( attribute "PACK_TYPE" "0402"
					( Origin gFrontEnd )
				)
				( attribute "PART_NUMBER" "G21796-016"
					( Origin gFrontEnd )
				)
				( attribute "PHYS_PAGE" "153"
					( Origin gFrontEnd )
				)
				( attribute "ROOM" "SB_SPI"
					( Origin gFrontEnd )
				)
				( attribute "ROT" "0"
					( Origin gFrontEnd )
				)
				( attribute "SEC" "1"
					( Origin gFrontEnd )
				)
				( attribute "SEC_TYPE" "0402"
					( Origin gFrontEnd )
				)
				( attribute "TOLERANCE" "1%"
					( Origin gFrontEnd )
				)
				( attribute "VALUE" "10.0K"
					( Origin gFrontEnd )
				)
				( attribute "VER" "1"
					( Origin gFrontEnd )
				)
				( attribute "WATTAGE" "1/16W"
					( Origin gFrontEnd )
				)
				( attribute "XY" "(-1450,4425)"
					( Origin gFrontEnd )
				)
				( attribute "CHIPS_PART_NAME" "RES"
					( Origin gPackager )
				)
				( attribute "CDS_PART_NAME" "RES_0402-10.0K,1%,1/16W,CHIP,GA"
					( Origin gPackager )
				)
				( objectStatus "R7F32" )
				( pin "a"
					( attribute "PN" "1"
						( Origin gPackager )
					)
					( objectStatus "R7F32.1" )
				)
				( pin "b"
					( attribute "PN" "2"
						( Origin gPackager )
					)
					( objectStatus "R7F32.2" )
				)
			)
			( gate "@baseboard_fab2_lib.baseboard_fab2(sch_1):page153_i146"
				( attribute "BOM_COST" "MIO_BIOS_MEM"
					( Origin gFrontEnd )
				)
				( attribute "CDS_LIB" "mstr_memory"
					( Origin gPackager )
				)
				( attribute "CDS_LOCATION" "U7F1"
					( Origin gPackager )
				)
				( attribute "CDS_SEC" "1"
					( Origin gPackager )
				)
				( attribute "LOCATION" "U7F1"
					( Origin gFrontEnd )
				)
				( attribute "MATERIAL" "IC"
					( Origin gFrontEnd )
				)
				( attribute "PACK_TYPE" "XSOI"
					( Origin gFrontEnd )
				)
				( attribute "PART_NUMBER" "H25002-001"
					( Origin gFrontEnd )
				)
				( attribute "PHYS_PAGE" "153"
					( Origin gFrontEnd )
				)
				( attribute "ROOM" "SB_SPI"
					( Origin gFrontEnd )
				)
				( attribute "ROT" "0"
					( Origin gFrontEnd )
				)
				( attribute "SEC" "1"
					( Origin gFrontEnd )
				)
				( attribute "SEC_TYPE" "XSOI"
					( Origin gFrontEnd )
				)
				( attribute "VER" "1"
					( Origin gFrontEnd )
				)
				( attribute "XY" "(-4900,3975)"
					( Origin gFrontEnd )
				)
				( attribute "CHIPS_PART_NAME" "W25Q256"
					( Origin gPackager )
				)
				( attribute "CDS_PART_NAME" "W25Q256_XSOI-IC,H25002-001"
					( Origin gPackager )
				)
				( objectStatus "U7F1" )
				( pin "clk"
					( attribute "PN" "16"
						( Origin gPackager )
					)
					( objectStatus "U7F1.16" )
				)
				( pin "cs_n"
					( attribute "PN" "7"
						( Origin gPackager )
					)
					( objectStatus "U7F1.7" )
				)
				( pin "di_io(0)"
					( attribute "PN" "15"
						( Origin gPackager )
					)
					( objectStatus "U7F1.15" )
				)
				( pin "do_io(1)"
					( attribute "PN" "8"
						( Origin gPackager )
					)
					( objectStatus "U7F1.8" )
				)
				( pin "gnd"
					( attribute "PN" "10"
						( Origin gPackager )
					)
					( objectStatus "U7F1.10" )
				)
				( pin "hold_n_io(3)"
					( attribute "PN" "1"
						( Origin gPackager )
					)
					( objectStatus "U7F1.1" )
				)
				( pin "nc(0)"
					( attribute "PN" "14"
						( Origin gPackager )
					)
					( objectStatus "U7F1.14" )
				)
				( pin "nc(1)"
					( attribute "PN" "13"
						( Origin gPackager )
					)
					( objectStatus "U7F1.13" )
				)
				( pin "nc(2)"
					( attribute "PN" "12"
						( Origin gPackager )
					)
					( objectStatus "U7F1.12" )
				)
				( pin "nc(3)"
					( attribute "PN" "11"
						( Origin gPackager )
					)
					( objectStatus "U7F1.11" )
				)
				( pin "nc(4)"
					( attribute "PN" "6"
						( Origin gPackager )
					)
					( objectStatus "U7F1.6" )
				)
				( pin "nc(5)"
					( attribute "PN" "5"
						( Origin gPackager )
					)
					( objectStatus "U7F1.5" )
				)
				( pin "nc(6)"
					( attribute "PN" "4"
						( Origin gPackager )
					)
					( objectStatus "U7F1.4" )
				)
				( pin "reset_n"
					( attribute "PN" "3"
						( Origin gPackager )
					)
					( objectStatus "U7F1.3" )
				)
				( pin "vcc"
					( attribute "PN" "2"
						( Origin gPackager )
					)
					( objectStatus "U7F1.2" )
				)
				( pin "wp_n_io(2)"
					( attribute "PN" "9"
						( Origin gPackager )
					)
					( objectStatus "U7F1.9" )
				)
			)
			( gate "@baseboard_fab2_lib.baseboard_fab2(sch_1):page153_i150"
				( attribute "BOM_COST" "MIO_BIOS_MEM"
					( Origin gFrontEnd )
				)
				( attribute "CDS_LIB" "mstr_discrete"
					( Origin gPackager )
				)
				( attribute "CDS_LOCATION" "R3T3"
					( Origin gPackager )
				)
				( attribute "CDS_SEC" "1"
					( Origin gPackager )
				)
				( attribute "LOCATION" "R3T3"
					( Origin gFrontEnd )
				)
				( attribute "MATERIAL" "EMPTY"
					( Origin gFrontEnd )
				)
				( attribute "NO_XNET_CONNECTION" "1"
					( Origin gFrontEnd )
				)
				( attribute "PACK_TYPE" "0402"
					( Origin gFrontEnd )
				)
				( attribute "PART_NUMBER" "G21796-072"
					( Origin gFrontEnd )
				)
				( attribute "PHYS_PAGE" "153"
					( Origin gFrontEnd )
				)
				( attribute "ROOM" "SB_SPI"
					( Origin gFrontEnd )
				)
				( attribute "ROT" "2"
					( Origin gFrontEnd )
				)
				( attribute "SEC" "1"
					( Origin gFrontEnd )
				)
				( attribute "SEC_TYPE" "0402"
					( Origin gFrontEnd )
				)
				( attribute "TOLERANCE" "1%"
					( Origin gFrontEnd )
				)
				( attribute "VALUE" "4.75K"
					( Origin gFrontEnd )
				)
				( attribute "VER" "2"
					( Origin gFrontEnd )
				)
				( attribute "WATTAGE" "1/16W"
					( Origin gFrontEnd )
				)
				( attribute "XY" "(-5875,2325)"
					( Origin gFrontEnd )
				)
				( attribute "CHIPS_PART_NAME" "RES"
					( Origin gPackager )
				)
				( attribute "CDS_PART_NAME" "RES_0402-4.75K,1%,1/16W,EMPTY,A"
					( Origin gPackager )
				)
				( objectStatus "R3T3" )
				( pin "a"
					( attribute "PN" "1"
						( Origin gPackager )
					)
					( objectStatus "R3T3.1" )
				)
				( pin "b"
					( attribute "PN" "2"
						( Origin gPackager )
					)
					( objectStatus "R3T3.2" )
				)
			)
			( gate "@baseboard_fab2_lib.baseboard_fab2(sch_1):page153_i152"
				( attribute "BOM_COST" "MIO_BIOS_MEM"
					( Origin gFrontEnd )
				)
				( attribute "CDS_LIB" "mstr_discrete"
					( Origin gPackager )
				)
				( attribute "CDS_LOCATION" "R3T5"
					( Origin gPackager )
				)
				( attribute "CDS_SEC" "1"
					( Origin gPackager )
				)
				( attribute "LOCATION" "R3T5"
					( Origin gFrontEnd )
				)
				( attribute "MATERIAL" "CHIP"
					( Origin gFrontEnd )
				)
				( attribute "NO_XNET_CONNECTION" "1"
					( Origin gFrontEnd )
				)
				( attribute "PACK_TYPE" "0402"
					( Origin gFrontEnd )
				)
				( attribute "PART_NUMBER" "G21796-072"
					( Origin gFrontEnd )
				)
				( attribute "PHYS_PAGE" "153"
					( Origin gFrontEnd )
				)
				( attribute "ROOM" "SB_SPI"
					( Origin gFrontEnd )
				)
				( attribute "ROT" "2"
					( Origin gFrontEnd )
				)
				( attribute "SEC" "1"
					( Origin gFrontEnd )
				)
				( attribute "SEC_TYPE" "0402"
					( Origin gFrontEnd )
				)
				( attribute "TOLERANCE" "1%"
					( Origin gFrontEnd )
				)
				( attribute "VALUE" "4.75K"
					( Origin gFrontEnd )
				)
				( attribute "VER" "2"
					( Origin gFrontEnd )
				)
				( attribute "WATTAGE" "1/16W"
					( Origin gFrontEnd )
				)
				( attribute "XY" "(-6175,2325)"
					( Origin gFrontEnd )
				)
				( attribute "CHIPS_PART_NAME" "RES"
					( Origin gPackager )
				)
				( attribute "CDS_PART_NAME" "RES_0402-4.75K,1%,1/16W,CHIP,GA"
					( Origin gPackager )
				)
				( objectStatus "R3T5" )
				( pin "a"
					( attribute "PN" "1"
						( Origin gPackager )
					)
					( objectStatus "R3T5.1" )
				)
				( pin "b"
					( attribute "PN" "2"
						( Origin gPackager )
					)
					( objectStatus "R3T5.2" )
				)
			)
			( gate "@baseboard_fab2_lib.baseboard_fab2(sch_1):page153_i155"
				( attribute "BOM_COST" "MIO_BIOS_MEM"
					( Origin gFrontEnd )
				)
				( attribute "CDS_LIB" "mstr_discrete"
					( Origin gPackager )
				)
				( attribute "CDS_LOCATION" "R3T2"
					( Origin gPackager )
				)
				( attribute "CDS_SEC" "1"
					( Origin gPackager )
				)
				( attribute "LOCATION" "R3T2"
					( Origin gFrontEnd )
				)
				( attribute "MATERIAL" "CHIP"
					( Origin gFrontEnd )
				)
				( attribute "PACK_TYPE" "0402"
					( Origin gFrontEnd )
				)
				( attribute "PART_NUMBER" "G21796-074"
					( Origin gFrontEnd )
				)
				( attribute "PHYS_PAGE" "153"
					( Origin gFrontEnd )
				)
				( attribute "ROOM" "SB_SPI"
					( Origin gFrontEnd )
				)
				( attribute "ROT" "0"
					( Origin gFrontEnd )
				)
				( attribute "SEC" "1"
					( Origin gFrontEnd )
				)
				( attribute "SEC_TYPE" "0402"
					( Origin gFrontEnd )
				)
				( attribute "TOLERANCE" "1%"
					( Origin gFrontEnd )
				)
				( attribute "VALUE" "33.2"
					( Origin gFrontEnd )
				)
				( attribute "VER" "1"
					( Origin gFrontEnd )
				)
				( attribute "WATTAGE" "1/16W"
					( Origin gFrontEnd )
				)
				( attribute "XY" "(-6200,1875)"
					( Origin gFrontEnd )
				)
				( attribute "CHIPS_PART_NAME" "RES"
					( Origin gPackager )
				)
				( attribute "CDS_PART_NAME" "RES_0402-33.2,1%,1/16W,CHIP,G2A"
					( Origin gPackager )
				)
				( objectStatus "R3T2" )
				( pin "a"
					( attribute "PN" "1"
						( Origin gPackager )
					)
					( objectStatus "R3T2.1" )
				)
				( pin "b"
					( attribute "PN" "2"
						( Origin gPackager )
					)
					( objectStatus "R3T2.2" )
				)
			)
			( gate "@baseboard_fab2_lib.baseboard_fab2(sch_1):page153_i156"
				( attribute "BOM_COST" "MIO_BIOS_MEM"
					( Origin gFrontEnd )
				)
				( attribute "CDS_LIB" "mstr_discrete"
					( Origin gPackager )
				)
				( attribute "CDS_LOCATION" "R3U1"
					( Origin gPackager )
				)
				( attribute "CDS_SEC" "1"
					( Origin gPackager )
				)
				( attribute "LOCATION" "R3U1"
					( Origin gFrontEnd )
				)
				( attribute "MATERIAL" "CHIP"
					( Origin gFrontEnd )
				)
				( attribute "NO_XNET_CONNECTION" "1"
					( Origin gFrontEnd )
				)
				( attribute "PACK_TYPE" "0402"
					( Origin gFrontEnd )
				)
				( attribute "PART_NUMBER" "G21796-074"
					( Origin gFrontEnd )
				)
				( attribute "PHYS_PAGE" "153"
					( Origin gFrontEnd )
				)
				( attribute "ROOM" "SB_SPI"
					( Origin gFrontEnd )
				)
				( attribute "ROT" "0"
					( Origin gFrontEnd )
				)
				( attribute "SEC" "1"
					( Origin gPackager )
				)
				( attribute "TOLERANCE" "1%"
					( Origin gFrontEnd )
				)
				( attribute "VALUE" "33.2"
					( Origin gFrontEnd )
				)
				( attribute "VER" "1"
					( Origin gFrontEnd )
				)
				( attribute "WATTAGE" "1/16W"
					( Origin gFrontEnd )
				)
				( attribute "XY" "(-6425,1500)"
					( Origin gFrontEnd )
				)
				( attribute "CHIPS_PART_NAME" "RES"
					( Origin gPackager )
				)
				( attribute "CDS_PART_NAME" "RES_0402-33.2,1%,1/16W,CHIP,G2A"
					( Origin gPackager )
				)
				( objectStatus "R3U1" )
				( pin "a"
					( attribute "PN" "1"
						( Origin gPackager )
					)
					( objectStatus "R3U1.1" )
				)
				( pin "b"
					( attribute "PN" "2"
						( Origin gPackager )
					)
					( objectStatus "R3U1.2" )
				)
			)
			( gate "@baseboard_fab2_lib.baseboard_fab2(sch_1):page153_i157"
				( attribute "BOM_COST" "MIO_BIOS_MEM"
					( Origin gFrontEnd )
				)
				( attribute "CDS_LIB" "mstr_discrete"
					( Origin gPackager )
				)
				( attribute "CDS_LOCATION" "R3T1"
					( Origin gPackager )
				)
				( attribute "CDS_SEC" "1"
					( Origin gPackager )
				)
				( attribute "LOCATION" "R3T1"
					( Origin gFrontEnd )
				)
				( attribute "MATERIAL" "CHIP"
					( Origin gFrontEnd )
				)
				( attribute "NO_XNET_CONNECTION" "1"
					( Origin gFrontEnd )
				)
				( attribute "PACK_TYPE" "0402"
					( Origin gFrontEnd )
				)
				( attribute "PART_NUMBER" "G21796-074"
					( Origin gFrontEnd )
				)
				( attribute "PHYS_PAGE" "153"
					( Origin gFrontEnd )
				)
				( attribute "ROOM" "SB_SPI"
					( Origin gFrontEnd )
				)
				( attribute "ROT" "0"
					( Origin gFrontEnd )
				)
				( attribute "SEC" "1"
					( Origin gPackager )
				)
				( attribute "TOLERANCE" "1%"
					( Origin gFrontEnd )
				)
				( attribute "VALUE" "33.2"
					( Origin gFrontEnd )
				)
				( attribute "VER" "1"
					( Origin gFrontEnd )
				)
				( attribute "WATTAGE" "1/16W"
					( Origin gFrontEnd )
				)
				( attribute "XY" "(-6400,1225)"
					( Origin gFrontEnd )
				)
				( attribute "CHIPS_PART_NAME" "RES"
					( Origin gPackager )
				)
				( attribute "CDS_PART_NAME" "RES_0402-33.2,1%,1/16W,CHIP,G2A"
					( Origin gPackager )
				)
				( objectStatus "R3T1" )
				( pin "a"
					( attribute "PN" "1"
						( Origin gPackager )
					)
					( objectStatus "R3T1.1" )
				)
				( pin "b"
					( attribute "PN" "2"
						( Origin gPackager )
					)
					( objectStatus "R3T1.2" )
				)
			)
			( gate "@baseboard_fab2_lib.baseboard_fab2(sch_1):page153_i165"
				( attribute "BOM_COST" "MIO_BIOS_MEM"
					( Origin gFrontEnd )
				)
				( attribute "CDS_LIB" "mstr_memory"
					( Origin gPackager )
				)
				( attribute "CDS_LOCATION" "U3T1"
					( Origin gPackager )
				)
				( attribute "CDS_SEC" "1"
					( Origin gPackager )
				)
				( attribute "LOCATION" "U3T1"
					( Origin gFrontEnd )
				)
				( attribute "MATERIAL" "IC"
					( Origin gFrontEnd )
				)
				( attribute "PACK_TYPE" "XSOI"
					( Origin gFrontEnd )
				)
				( attribute "PART_NUMBER" "H25002-001"
					( Origin gFrontEnd )
				)
				( attribute "PHYS_PAGE" "153"
					( Origin gFrontEnd )
				)
				( attribute "ROOM" "SB_SPI"
					( Origin gFrontEnd )
				)
				( attribute "ROT" "0"
					( Origin gFrontEnd )
				)
				( attribute "SEC" "1"
					( Origin gFrontEnd )
				)
				( attribute "SEC_TYPE" "XSOI"
					( Origin gFrontEnd )
				)
				( attribute "VER" "1"
					( Origin gFrontEnd )
				)
				( attribute "XY" "(-4825,1875)"
					( Origin gFrontEnd )
				)
				( attribute "CHIPS_PART_NAME" "W25Q256"
					( Origin gPackager )
				)
				( attribute "CDS_PART_NAME" "W25Q256_XSOI-IC,H25002-001"
					( Origin gPackager )
				)
				( objectStatus "U3T1" )
				( pin "clk"
					( attribute "PN" "16"
						( Origin gPackager )
					)
					( objectStatus "U3T1.16" )
				)
				( pin "cs_n"
					( attribute "PN" "7"
						( Origin gPackager )
					)
					( objectStatus "U3T1.7" )
				)
				( pin "di_io(0)"
					( attribute "PN" "15"
						( Origin gPackager )
					)
					( objectStatus "U3T1.15" )
				)
				( pin "do_io(1)"
					( attribute "PN" "8"
						( Origin gPackager )
					)
					( objectStatus "U3T1.8" )
				)
				( pin "gnd"
					( attribute "PN" "10"
						( Origin gPackager )
					)
					( objectStatus "U3T1.10" )
				)
				( pin "hold_n_io(3)"
					( attribute "PN" "1"
						( Origin gPackager )
					)
					( objectStatus "U3T1.1" )
				)
				( pin "nc(0)"
					( attribute "PN" "14"
						( Origin gPackager )
					)
					( objectStatus "U3T1.14" )
				)
				( pin "nc(1)"
					( attribute "PN" "13"
						( Origin gPackager )
					)
					( objectStatus "U3T1.13" )
				)
				( pin "nc(2)"
					( attribute "PN" "12"
						( Origin gPackager )
					)
					( objectStatus "U3T1.12" )
				)
				( pin "nc(3)"
					( attribute "PN" "11"
						( Origin gPackager )
					)
					( objectStatus "U3T1.11" )
				)
				( pin "nc(4)"
					( attribute "PN" "6"
						( Origin gPackager )
					)
					( objectStatus "U3T1.6" )
				)
				( pin "nc(5)"
					( attribute "PN" "5"
						( Origin gPackager )
					)
					( objectStatus "U3T1.5" )
				)
				( pin "nc(6)"
					( attribute "PN" "4"
						( Origin gPackager )
					)
					( objectStatus "U3T1.4" )
				)
				( pin "reset_n"
					( attribute "PN" "3"
						( Origin gPackager )
					)
					( objectStatus "U3T1.3" )
				)
				( pin "vcc"
					( attribute "PN" "2"
						( Origin gPackager )
					)
					( objectStatus "U3T1.2" )
				)
				( pin "wp_n_io(2)"
					( attribute "PN" "9"
						( Origin gPackager )
					)
					( objectStatus "U3T1.9" )
				)
			)
			( gate "@baseboard_fab2_lib.baseboard_fab2(sch_1):page153_i166"
				( attribute "CDS_LIB" "mstr_discrete"
					( Origin gPackager )
				)
				( attribute "CDS_LOCATION" "R8F8"
					( Origin gPackager )
				)
				( attribute "CDS_SEC" "1"
					( Origin gPackager )
				)
				( attribute "LOCATION" "R8F8"
					( Origin gFrontEnd )
				)
				( attribute "MATERIAL" "CHIP"
					( Origin gFrontEnd )
				)
				( attribute "PACK_TYPE" "0402"
					( Origin gFrontEnd )
				)
				( attribute "PART_NUMBER" "G21796-074"
					( Origin gFrontEnd )
				)
				( attribute "PHYS_PAGE" "153"
					( Origin gFrontEnd )
				)
				( attribute "ROOM" "MIO_BIOS_MEM"
					( Origin gFrontEnd )
				)
				( attribute "ROT" "0"
					( Origin gFrontEnd )
				)
				( attribute "SEC" "1"
					( Origin gPackager )
				)
				( attribute "TOLERANCE" "1%"
					( Origin gFrontEnd )
				)
				( attribute "VALUE" "33.2"
					( Origin gFrontEnd )
				)
				( attribute "VER" "1"
					( Origin gFrontEnd )
				)
				( attribute "WATTAGE" "1/16W"
					( Origin gFrontEnd )
				)
				( attribute "XY" "(-6550,3825)"
					( Origin gFrontEnd )
				)
				( attribute "CHIPS_PART_NAME" "RES"
					( Origin gPackager )
				)
				( attribute "CDS_PART_NAME" "RES_0402-33.2,1%,1/16W,CHIP,G2A"
					( Origin gPackager )
				)
				( objectStatus "R8F8" )
				( pin "a"
					( attribute "PN" "1"
						( Origin gPackager )
					)
					( objectStatus "R8F8.1" )
				)
				( pin "b"
					( attribute "PN" "2"
						( Origin gPackager )
					)
					( objectStatus "R8F8.2" )
				)
			)
			( gate "@baseboard_fab2_lib.baseboard_fab2(sch_1):page153_i167"
				( attribute "CDS_LIB" "mstr_discrete"
					( Origin gPackager )
				)
				( attribute "CDS_LOCATION" "R8F7"
					( Origin gPackager )
				)
				( attribute "CDS_SEC" "1"
					( Origin gPackager )
				)
				( attribute "LOCATION" "R8F7"
					( Origin gFrontEnd )
				)
				( attribute "MATERIAL" "CHIP"
					( Origin gFrontEnd )
				)
				( attribute "PACK_TYPE" "0402"
					( Origin gFrontEnd )
				)
				( attribute "PART_NUMBER" "G21796-074"
					( Origin gFrontEnd )
				)
				( attribute "PHYS_PAGE" "153"
					( Origin gFrontEnd )
				)
				( attribute "ROOM" "MIO_BIOS_MEM"
					( Origin gFrontEnd )
				)
				( attribute "ROT" "0"
					( Origin gFrontEnd )
				)
				( attribute "SEC" "1"
					( Origin gPackager )
				)
				( attribute "TOLERANCE" "1%"
					( Origin gFrontEnd )
				)
				( attribute "VALUE" "33.2"
					( Origin gFrontEnd )
				)
				( attribute "VER" "1"
					( Origin gFrontEnd )
				)
				( attribute "WATTAGE" "1/16W"
					( Origin gFrontEnd )
				)
				( attribute "XY" "(-6525,1725)"
					( Origin gFrontEnd )
				)
				( attribute "CHIPS_PART_NAME" "RES"
					( Origin gPackager )
				)
				( attribute "CDS_PART_NAME" "RES_0402-33.2,1%,1/16W,CHIP,G2A"
					( Origin gPackager )
				)
				( objectStatus "R8F7" )
				( pin "a"
					( attribute "PN" "1"
						( Origin gPackager )
					)
					( objectStatus "R8F7.1" )
				)
				( pin "b"
					( attribute "PN" "2"
						( Origin gPackager )
					)
					( objectStatus "R8F7.2" )
				)
			)
			( gate "@baseboard_fab2_lib.baseboard_fab2(sch_1):page153_i168"
				( attribute "BOM_COST" "MIO_BIOS_MEM"
					( Origin gFrontEnd )
				)
				( attribute "CDS_LIB" "mstr_discrete"
					( Origin gPackager )
				)
				( attribute "CDS_LOCATION" "R7F28"
					( Origin gPackager )
				)
				( attribute "CDS_SEC" "1"
					( Origin gPackager )
				)
				( attribute "LOCATION" "R7F28"
					( Origin gFrontEnd )
				)
				( attribute "MATERIAL" "CHIP"
					( Origin gFrontEnd )
				)
				( attribute "NO_XNET_CONNECTION" "1"
					( Origin gFrontEnd )
				)
				( attribute "PACK_TYPE" "0402"
					( Origin gFrontEnd )
				)
				( attribute "PART_NUMBER" "G21796-016"
					( Origin gFrontEnd )
				)
				( attribute "PHYS_PAGE" "153"
					( Origin gFrontEnd )
				)
				( attribute "ROOM" "SB_SPI"
					( Origin gFrontEnd )
				)
				( attribute "ROT" "0"
					( Origin gFrontEnd )
				)
				( attribute "SEC" "1"
					( Origin gFrontEnd )
				)
				( attribute "SEC_TYPE" "0402"
					( Origin gFrontEnd )
				)
				( attribute "TOLERANCE" "1%"
					( Origin gFrontEnd )
				)
				( attribute "VALUE" "10.0K"
					( Origin gFrontEnd )
				)
				( attribute "VER" "2"
					( Origin gFrontEnd )
				)
				( attribute "WATTAGE" "1/16W"
					( Origin gFrontEnd )
				)
				( attribute "XY" "(-1750,3925)"
					( Origin gFrontEnd )
				)
				( attribute "CHIPS_PART_NAME" "RES"
					( Origin gPackager )
				)
				( attribute "CDS_PART_NAME" "RES_0402-10.0K,1%,1/16W,CHIP,GA"
					( Origin gPackager )
				)
				( objectStatus "R7F28" )
				( pin "a"
					( attribute "PN" "1"
						( Origin gPackager )
					)
					( objectStatus "R7F28.1" )
				)
				( pin "b"
					( attribute "PN" "2"
						( Origin gPackager )
					)
					( objectStatus "R7F28.2" )
				)
			)
			( gate "@baseboard_fab2_lib.baseboard_fab2(sch_1):page153_i170"
				( attribute "BOM_COST" "MIO_BIOS_MEM"
					( Origin gFrontEnd )
				)
				( attribute "CDS_LIB" "mstr_discrete"
					( Origin gPackager )
				)
				( attribute "CDS_LOCATION" "R7F30"
					( Origin gPackager )
				)
				( attribute "CDS_SEC" "1"
					( Origin gPackager )
				)
				( attribute "LOCATION" "R7F30"
					( Origin gFrontEnd )
				)
				( attribute "MATERIAL" "EMPTY"
					( Origin gFrontEnd )
				)
				( attribute "PACK_TYPE" "0402"
					( Origin gFrontEnd )
				)
				( attribute "PART_NUMBER" "G21796-016"
					( Origin gFrontEnd )
				)
				( attribute "PHYS_PAGE" "153"
					( Origin gFrontEnd )
				)
				( attribute "ROOM" "SB_SPI"
					( Origin gFrontEnd )
				)
				( attribute "ROT" "0"
					( Origin gFrontEnd )
				)
				( attribute "SEC" "1"
					( Origin gFrontEnd )
				)
				( attribute "SEC_TYPE" "0402"
					( Origin gFrontEnd )
				)
				( attribute "TOLERANCE" "1%"
					( Origin gFrontEnd )
				)
				( attribute "VALUE" "10.0K"
					( Origin gFrontEnd )
				)
				( attribute "VER" "2"
					( Origin gFrontEnd )
				)
				( attribute "WATTAGE" "1/16W"
					( Origin gFrontEnd )
				)
				( attribute "XY" "(-1750,3550)"
					( Origin gFrontEnd )
				)
				( attribute "CHIPS_PART_NAME" "RES"
					( Origin gPackager )
				)
				( attribute "CDS_PART_NAME" "RES_0402-10.0K,1%,1/16W,EMPTY,A"
					( Origin gPackager )
				)
				( objectStatus "R7F30" )
				( pin "a"
					( attribute "PN" "1"
						( Origin gPackager )
					)
					( objectStatus "R7F30.1" )
				)
				( pin "b"
					( attribute "PN" "2"
						( Origin gPackager )
					)
					( objectStatus "R7F30.2" )
				)
			)
			( gate "@baseboard_fab2_lib.baseboard_fab2(sch_1):page153_i174"
				( attribute "BOM_COST" "MIO_BIOS_MEM"
					( Origin gFrontEnd )
				)
				( attribute "CDS_LIB" "mstr_discrete"
					( Origin gPackager )
				)
				( attribute "CDS_LOCATION" "R3T4"
					( Origin gPackager )
				)
				( attribute "CDS_SEC" "1"
					( Origin gPackager )
				)
				( attribute "LOCATION" "R3T4"
					( Origin gFrontEnd )
				)
				( attribute "MATERIAL" "CHIP"
					( Origin gFrontEnd )
				)
				( attribute "PACK_TYPE" "0402"
					( Origin gFrontEnd )
				)
				( attribute "PART_NUMBER" "G21796-016"
					( Origin gFrontEnd )
				)
				( attribute "PHYS_PAGE" "153"
					( Origin gFrontEnd )
				)
				( attribute "ROOM" "SB_SPI"
					( Origin gFrontEnd )
				)
				( attribute "ROT" "0"
					( Origin gFrontEnd )
				)
				( attribute "SEC" "1"
					( Origin gFrontEnd )
				)
				( attribute "SEC_TYPE" "0402"
					( Origin gFrontEnd )
				)
				( attribute "TOLERANCE" "1%"
					( Origin gFrontEnd )
				)
				( attribute "VALUE" "10.0K"
					( Origin gFrontEnd )
				)
				( attribute "VER" "1"
					( Origin gFrontEnd )
				)
				( attribute "WATTAGE" "1/16W"
					( Origin gFrontEnd )
				)
				( attribute "XY" "(-1450,2325)"
					( Origin gFrontEnd )
				)
				( attribute "CHIPS_PART_NAME" "RES"
					( Origin gPackager )
				)
				( attribute "CDS_PART_NAME" "RES_0402-10.0K,1%,1/16W,CHIP,GA"
					( Origin gPackager )
				)
				( objectStatus "R3T4" )
				( pin "a"
					( attribute "PN" "1"
						( Origin gPackager )
					)
					( objectStatus "R3T4.1" )
				)
				( pin "b"
					( attribute "PN" "2"
						( Origin gPackager )
					)
					( objectStatus "R3T4.2" )
				)
			)
			( gate "@baseboard_fab2_lib.baseboard_fab2(sch_1):page153_i178"
				( attribute "BOM_COST" "MIO_BIOS_MEM"
					( Origin gFrontEnd )
				)
				( attribute "CDS_LIB" "mstr_discrete"
					( Origin gPackager )
				)
				( attribute "CDS_LOCATION" "R3T12"
					( Origin gPackager )
				)
				( attribute "CDS_SEC" "1"
					( Origin gPackager )
				)
				( attribute "LOCATION" "R3T12"
					( Origin gFrontEnd )
				)
				( attribute "MATERIAL" "CHIP"
					( Origin gFrontEnd )
				)
				( attribute "PACK_TYPE" "0402"
					( Origin gFrontEnd )
				)
				( attribute "PART_NUMBER" "G21796-016"
					( Origin gFrontEnd )
				)
				( attribute "PHYS_PAGE" "153"
					( Origin gFrontEnd )
				)
				( attribute "ROOM" "SB_SPI"
					( Origin gFrontEnd )
				)
				( attribute "ROT" "0"
					( Origin gFrontEnd )
				)
				( attribute "SEC" "1"
					( Origin gFrontEnd )
				)
				( attribute "SEC_TYPE" "0402"
					( Origin gFrontEnd )
				)
				( attribute "TOLERANCE" "1%"
					( Origin gFrontEnd )
				)
				( attribute "VALUE" "10.0K"
					( Origin gFrontEnd )
				)
				( attribute "VER" "2"
					( Origin gFrontEnd )
				)
				( attribute "WATTAGE" "1/16W"
					( Origin gFrontEnd )
				)
				( attribute "XY" "(-1750,1825)"
					( Origin gFrontEnd )
				)
				( attribute "CHIPS_PART_NAME" "RES"
					( Origin gPackager )
				)
				( attribute "CDS_PART_NAME" "RES_0402-10.0K,1%,1/16W,CHIP,GA"
					( Origin gPackager )
				)
				( objectStatus "R3T12" )
				( pin "a"
					( attribute "PN" "1"
						( Origin gPackager )
					)
					( objectStatus "R3T12.1" )
				)
				( pin "b"
					( attribute "PN" "2"
						( Origin gPackager )
					)
					( objectStatus "R3T12.2" )
				)
			)
			( gate "@baseboard_fab2_lib.baseboard_fab2(sch_1):page153_i179"
				( attribute "BOM_COST" "MIO_BIOS_MEM"
					( Origin gFrontEnd )
				)
				( attribute "CDS_LIB" "mstr_discrete"
					( Origin gPackager )
				)
				( attribute "CDS_LOCATION" "R3T9"
					( Origin gPackager )
				)
				( attribute "CDS_SEC" "1"
					( Origin gPackager )
				)
				( attribute "LOCATION" "R3T9"
					( Origin gFrontEnd )
				)
				( attribute "MATERIAL" "EMPTY"
					( Origin gFrontEnd )
				)
				( attribute "PACK_TYPE" "0402"
					( Origin gFrontEnd )
				)
				( attribute "PART_NUMBER" "G21796-016"
					( Origin gFrontEnd )
				)
				( attribute "PHYS_PAGE" "153"
					( Origin gFrontEnd )
				)
				( attribute "ROOM" "SB_SPI"
					( Origin gFrontEnd )
				)
				( attribute "ROT" "0"
					( Origin gFrontEnd )
				)
				( attribute "SEC" "1"
					( Origin gFrontEnd )
				)
				( attribute "SEC_TYPE" "0402"
					( Origin gFrontEnd )
				)
				( attribute "TOLERANCE" "1%"
					( Origin gFrontEnd )
				)
				( attribute "VALUE" "10.0K"
					( Origin gFrontEnd )
				)
				( attribute "VER" "2"
					( Origin gFrontEnd )
				)
				( attribute "WATTAGE" "1/16W"
					( Origin gFrontEnd )
				)
				( attribute "XY" "(-1750,1450)"
					( Origin gFrontEnd )
				)
				( attribute "CHIPS_PART_NAME" "RES"
					( Origin gPackager )
				)
				( attribute "CDS_PART_NAME" "RES_0402-10.0K,1%,1/16W,EMPTY,A"
					( Origin gPackager )
				)
				( objectStatus "R3T9" )
				( pin "a"
					( attribute "PN" "1"
						( Origin gPackager )
					)
					( objectStatus "R3T9.1" )
				)
				( pin "b"
					( attribute "PN" "2"
						( Origin gPackager )
					)
					( objectStatus "R3T9.2" )
				)
			)
			( gate "@baseboard_fab2_lib.baseboard_fab2(sch_1):page153_i181"
				( attribute "BOM_COST" "MIO_BIOS_MEM"
					( Origin gFrontEnd )
				)
				( attribute "CDS_LIB" "mstr_discrete"
					( Origin gPackager )
				)
				( attribute "CDS_LOCATION" "R7F29"
					( Origin gPackager )
				)
				( attribute "CDS_SEC" "1"
					( Origin gPackager )
				)
				( attribute "LOCATION" "R7F29"
					( Origin gFrontEnd )
				)
				( attribute "MATERIAL" "CHIP"
					( Origin gFrontEnd )
				)
				( attribute "PACK_TYPE" "0402"
					( Origin gFrontEnd )
				)
				( attribute "PART_NUMBER" "G21796-074"
					( Origin gFrontEnd )
				)
				( attribute "PHYS_PAGE" "153"
					( Origin gFrontEnd )
				)
				( attribute "ROOM" "SB_SPI"
					( Origin gFrontEnd )
				)
				( attribute "ROT" "0"
					( Origin gFrontEnd )
				)
				( attribute "SEC" "1"
					( Origin gFrontEnd )
				)
				( attribute "SEC_TYPE" "0402"
					( Origin gFrontEnd )
				)
				( attribute "TOLERANCE" "1%"
					( Origin gFrontEnd )
				)
				( attribute "VALUE" "33.2"
					( Origin gFrontEnd )
				)
				( attribute "VER" "1"
					( Origin gFrontEnd )
				)
				( attribute "WATTAGE" "1/16W"
					( Origin gFrontEnd )
				)
				( attribute "XY" "(-6525,3925)"
					( Origin gFrontEnd )
				)
				( attribute "CHIPS_PART_NAME" "RES"
					( Origin gPackager )
				)
				( attribute "CDS_PART_NAME" "RES_0402-33.2,1%,1/16W,CHIP,G2A"
					( Origin gPackager )
				)
				( objectStatus "R7F29" )
				( pin "a"
					( attribute "PN" "1"
						( Origin gPackager )
					)
					( objectStatus "R7F29.1" )
				)
				( pin "b"
					( attribute "PN" "2"
						( Origin gPackager )
					)
					( objectStatus "R7F29.2" )
				)
			)
			( gate "@baseboard_fab2_lib.baseboard_fab2(sch_1):page153_i184"
				( attribute "BOM_COST" "MIO_BIOS_MEM"
					( Origin gFrontEnd )
				)
				( attribute "CDS_LIB" "mstr_discrete"
					( Origin gPackager )
				)
				( attribute "CDS_LOCATION" "R3T10"
					( Origin gPackager )
				)
				( attribute "CDS_SEC" "1"
					( Origin gPackager )
				)
				( attribute "LOCATION" "R3T10"
					( Origin gFrontEnd )
				)
				( attribute "MATERIAL" "CHIP"
					( Origin gFrontEnd )
				)
				( attribute "PACK_TYPE" "0402"
					( Origin gFrontEnd )
				)
				( attribute "PART_NUMBER" "G21796-074"
					( Origin gFrontEnd )
				)
				( attribute "PHYS_PAGE" "153"
					( Origin gFrontEnd )
				)
				( attribute "ROOM" "SB_SPI"
					( Origin gFrontEnd )
				)
				( attribute "ROT" "0"
					( Origin gFrontEnd )
				)
				( attribute "SEC" "1"
					( Origin gFrontEnd )
				)
				( attribute "SEC_TYPE" "0402"
					( Origin gFrontEnd )
				)
				( attribute "TOLERANCE" "1%"
					( Origin gFrontEnd )
				)
				( attribute "VALUE" "33.2"
					( Origin gFrontEnd )
				)
				( attribute "VER" "1"
					( Origin gFrontEnd )
				)
				( attribute "WATTAGE" "1/16W"
					( Origin gFrontEnd )
				)
				( attribute "XY" "(-6450,1825)"
					( Origin gFrontEnd )
				)
				( attribute "CHIPS_PART_NAME" "RES"
					( Origin gPackager )
				)
				( attribute "CDS_PART_NAME" "RES_0402-33.2,1%,1/16W,CHIP,G2A"
					( Origin gPackager )
				)
				( objectStatus "R3T10" )
				( pin "a"
					( attribute "PN" "1"
						( Origin gPackager )
					)
					( objectStatus "R3T10.1" )
				)
				( pin "b"
					( attribute "PN" "2"
						( Origin gPackager )
					)
					( objectStatus "R3T10.2" )
				)
			)
			( gate "@baseboard_fab2_lib.baseboard_fab2(sch_1):page154_i14"
				( attribute "BOM_COST" "MIO_BIOS_MEM"
					( Origin gFrontEnd )
				)
				( attribute "CDS_LIB" "dev_discrete"
					( Origin gPackager )
				)
				( attribute "CDS_LOCATION" "C8E18"
					( Origin gPackager )
				)
				( attribute "CDS_SEC" "1"
					( Origin gPackager )
				)
				( attribute "LOCATION" "C8E18"
					( Origin gFrontEnd )
				)
				( attribute "MATERIAL" "X7R"
					( Origin gFrontEnd )
				)
				( attribute "PACK_TYPE" "0402V"
					( Origin gFrontEnd )
				)
				( attribute "PART_NUMBER" "A36096-030"
					( Origin gFrontEnd )
				)
				( attribute "PHYS_PAGE" "154"
					( Origin gFrontEnd )
				)
				( attribute "ROOM" "SB_BMC_SPI_MUX"
					( Origin gFrontEnd )
				)
				( attribute "ROT" "0"
					( Origin gFrontEnd )
				)
				( attribute "SEC" "1"
					( Origin gFrontEnd )
				)
				( attribute "SEC_TYPE" "0402V"
					( Origin gFrontEnd )
				)
				( attribute "TOLERANCE" "10%"
					( Origin gFrontEnd )
				)
				( attribute "VALUE" "0.1UF"
					( Origin gFrontEnd )
				)
				( attribute "VER" "1"
					( Origin gFrontEnd )
				)
				( attribute "VOLTAGE" "16V"
					( Units "uVoltage" "V" 1.000000)
					( Origin gFrontEnd )
				)
				( attribute "XY" "(-5400,4350)"
					( Origin gFrontEnd )
				)
				( attribute "CHIPS_PART_NAME" "CAP_A"
					( Origin gPackager )
				)
				( attribute "CDS_PART_NAME" "CAP_A_0402V-0.1UF,16V,10%,X7R,A"
					( Origin gPackager )
				)
				( objectStatus "C8E18" )
				( pin "a"
					( attribute "PN" "1"
						( Origin gPackager )
					)
					( objectStatus "C8E18.1" )
				)
				( pin "b"
					( attribute "PN" "2"
						( Origin gPackager )
					)
					( objectStatus "C8E18.2" )
				)
			)
			( gate "@baseboard_fab2_lib.baseboard_fab2(sch_1):page154_i62"
				( attribute "BOM_COST" "MIO_BIOS_MEM"
					( Origin gFrontEnd )
				)
				( attribute "CDS_LIB" "mstr_discrete"
					( Origin gPackager )
				)
				( attribute "CDS_LOCATION" "R2T9"
					( Origin gPackager )
				)
				( attribute "CDS_SEC" "1"
					( Origin gPackager )
				)
				( attribute "LOCATION" "R2T9"
					( Origin gFrontEnd )
				)
				( attribute "MATERIAL" "CHIP"
					( Origin gFrontEnd )
				)
				( attribute "PACK_TYPE" "0402"
					( Origin gFrontEnd )
				)
				( attribute "PART_NUMBER" "G21796-267"
					( Origin gFrontEnd )
				)
				( attribute "PHYS_PAGE" "154"
					( Origin gFrontEnd )
				)
				( attribute "ROOM" "SB_BMC_SPI_MUX"
					( Origin gFrontEnd )
				)
				( attribute "ROT" "0"
					( Origin gFrontEnd )
				)
				( attribute "SEC" "1"
					( Origin gFrontEnd )
				)
				( attribute "SEC_TYPE" "0402"
					( Origin gFrontEnd )
				)
				( attribute "TOLERANCE" "1.0%"
					( Origin gFrontEnd )
				)
				( attribute "VALUE" "75"
					( Origin gFrontEnd )
				)
				( attribute "VER" "1"
					( Origin gFrontEnd )
				)
				( attribute "WATTAGE" "1/16W"
					( Origin gFrontEnd )
				)
				( attribute "XY" "(-1450,1150)"
					( Origin gFrontEnd )
				)
				( attribute "CHIPS_PART_NAME" "RES"
					( Origin gPackager )
				)
				( attribute "CDS_PART_NAME" "RES_0402-75,1.0%,1/16W,CHIP,G2A"
					( Origin gPackager )
				)
				( objectStatus "R2T9" )
				( pin "a"
					( attribute "PN" "1"
						( Origin gPackager )
					)
					( objectStatus "R2T9.1" )
				)
				( pin "b"
					( attribute "PN" "2"
						( Origin gPackager )
					)
					( objectStatus "R2T9.2" )
				)
			)
			( gate "@baseboard_fab2_lib.baseboard_fab2(sch_1):page154_i74"
				( attribute "BOM_COST" "MIO_BIOS_MEM"
					( Origin gFrontEnd )
				)
				( attribute "CDS_LIB" "mstr_digital"
					( Origin gPackager )
				)
				( attribute "CDS_LOCATION" "U8F1"
					( Origin gPackager )
				)
				( attribute "CDS_SEC" "1"
					( Origin gPackager )
				)
				( attribute "LOCATION" "U8F1"
					( Origin gFrontEnd )
				)
				( attribute "MATERIAL" "IC"
					( Origin gFrontEnd )
				)
				( attribute "PACK_TYPE" "TSSOPLF"
					( Origin gFrontEnd )
				)
				( attribute "PART_NUMBER" "E16801-001"
					( Origin gFrontEnd )
				)
				( attribute "PHYS_PAGE" "154"
					( Origin gFrontEnd )
				)
				( attribute "ROOM" "SB_BMC_SPI_MUX"
					( Origin gFrontEnd )
				)
				( attribute "ROT" "2"
					( Origin gFrontEnd )
				)
				( attribute "SEC" "1"
					( Origin gFrontEnd )
				)
				( attribute "SEC_TYPE" "TSSOPLF"
					( Origin gFrontEnd )
				)
				( attribute "VER" "1"
					( Origin gFrontEnd )
				)
				( attribute "XY" "(-5900,3700)"
					( Origin gFrontEnd )
				)
				( attribute "CHIPS_PART_NAME" "PI3B3257A"
					( Origin gPackager )
				)
				( attribute "CDS_PART_NAME" "PI3B3257A_TSSOPLF-IC,E16801-001"
					( Origin gPackager )
				)
				( objectStatus "U8F1" )
				( pin "en"
					( attribute "PN" "15"
						( Origin gPackager )
					)
					( objectStatus "U8F1.15" )
				)
				( pin "gnd"
					( attribute "PN" "8"
						( Origin gPackager )
					)
					( objectStatus "U8F1.8" )
				)
				( pin "ia0"
					( attribute "PN" "2"
						( Origin gPackager )
					)
					( objectStatus "U8F1.2" )
				)
				( pin "ia1"
					( attribute "PN" "3"
						( Origin gPackager )
					)
					( objectStatus "U8F1.3" )
				)
				( pin "ib0"
					( attribute "PN" "5"
						( Origin gPackager )
					)
					( objectStatus "U8F1.5" )
				)
				( pin "ib1"
					( attribute "PN" "6"
						( Origin gPackager )
					)
					( objectStatus "U8F1.6" )
				)
				( pin "ic0"
					( attribute "PN" "11"
						( Origin gPackager )
					)
					( objectStatus "U8F1.11" )
				)
				( pin "ic1"
					( attribute "PN" "10"
						( Origin gPackager )
					)
					( objectStatus "U8F1.10" )
				)
				( pin "id0"
					( attribute "PN" "14"
						( Origin gPackager )
					)
					( objectStatus "U8F1.14" )
				)
				( pin "id1"
					( attribute "PN" "13"
						( Origin gPackager )
					)
					( objectStatus "U8F1.13" )
				)
				( pin "s"
					( attribute "PN" "1"
						( Origin gPackager )
					)
					( objectStatus "U8F1.1" )
				)
				( pin "vcc"
					( attribute "PN" "16"
						( Origin gPackager )
					)
					( objectStatus "U8F1.16" )
				)
				( pin "ya"
					( attribute "PN" "4"
						( Origin gPackager )
					)
					( objectStatus "U8F1.4" )
				)
				( pin "yb"
					( attribute "PN" "7"
						( Origin gPackager )
					)
					( objectStatus "U8F1.7" )
				)
				( pin "yc"
					( attribute "PN" "9"
						( Origin gPackager )
					)
					( objectStatus "U8F1.9" )
				)
				( pin "yd"
					( attribute "PN" "12"
						( Origin gPackager )
					)
					( objectStatus "U8F1.12" )
				)
			)
			( gate "@baseboard_fab2_lib.baseboard_fab2(sch_1):page154_i75"
				( attribute "BOM_COST" "MIO_BIOS_MEM"
					( Origin gFrontEnd )
				)
				( attribute "CDS_LIB" "mstr_digital"
					( Origin gPackager )
				)
				( attribute "CDS_LOCATION" "U2T1"
					( Origin gPackager )
				)
				( attribute "CDS_SEC" "1"
					( Origin gPackager )
				)
				( attribute "LOCATION" "U2T1"
					( Origin gFrontEnd )
				)
				( attribute "MATERIAL" "IC"
					( Origin gFrontEnd )
				)
				( attribute "PACK_TYPE" "TSSOPLF"
					( Origin gFrontEnd )
				)
				( attribute "PART_NUMBER" "E16801-001"
					( Origin gFrontEnd )
				)
				( attribute "PHYS_PAGE" "154"
					( Origin gFrontEnd )
				)
				( attribute "ROOM" "SB_BMC_SPI_MUX"
					( Origin gFrontEnd )
				)
				( attribute "ROT" "2"
					( Origin gFrontEnd )
				)
				( attribute "SEC" "1"
					( Origin gFrontEnd )
				)
				( attribute "SEC_TYPE" "TSSOPLF"
					( Origin gFrontEnd )
				)
				( attribute "VER" "1"
					( Origin gFrontEnd )
				)
				( attribute "XY" "(-2000,3875)"
					( Origin gFrontEnd )
				)
				( attribute "CHIPS_PART_NAME" "PI3B3257A"
					( Origin gPackager )
				)
				( attribute "CDS_PART_NAME" "PI3B3257A_TSSOPLF-IC,E16801-001"
					( Origin gPackager )
				)
				( objectStatus "U2T1" )
				( pin "en"
					( attribute "PN" "15"
						( Origin gPackager )
					)
					( objectStatus "U2T1.15" )
				)
				( pin "gnd"
					( attribute "PN" "8"
						( Origin gPackager )
					)
					( objectStatus "U2T1.8" )
				)
				( pin "ia0"
					( attribute "PN" "2"
						( Origin gPackager )
					)
					( objectStatus "U2T1.2" )
				)
				( pin "ia1"
					( attribute "PN" "3"
						( Origin gPackager )
					)
					( objectStatus "U2T1.3" )
				)
				( pin "ib0"
					( attribute "PN" "5"
						( Origin gPackager )
					)
					( objectStatus "U2T1.5" )
				)
				( pin "ib1"
					( attribute "PN" "6"
						( Origin gPackager )
					)
					( objectStatus "U2T1.6" )
				)
				( pin "ic0"
					( attribute "PN" "11"
						( Origin gPackager )
					)
					( objectStatus "U2T1.11" )
				)
				( pin "ic1"
					( attribute "PN" "10"
						( Origin gPackager )
					)
					( objectStatus "U2T1.10" )
				)
				( pin "id0"
					( attribute "PN" "14"
						( Origin gPackager )
					)
					( objectStatus "U2T1.14" )
				)
				( pin "id1"
					( attribute "PN" "13"
						( Origin gPackager )
					)
					( objectStatus "U2T1.13" )
				)
				( pin "s"
					( attribute "PN" "1"
						( Origin gPackager )
					)
					( objectStatus "U2T1.1" )
				)
				( pin "vcc"
					( attribute "PN" "16"
						( Origin gPackager )
					)
					( objectStatus "U2T1.16" )
				)
				( pin "ya"
					( attribute "PN" "4"
						( Origin gPackager )
					)
					( objectStatus "U2T1.4" )
				)
				( pin "yb"
					( attribute "PN" "7"
						( Origin gPackager )
					)
					( objectStatus "U2T1.7" )
				)
				( pin "yc"
					( attribute "PN" "9"
						( Origin gPackager )
					)
					( objectStatus "U2T1.9" )
				)
				( pin "yd"
					( attribute "PN" "12"
						( Origin gPackager )
					)
					( objectStatus "U2T1.12" )
				)
			)
			( gate "@baseboard_fab2_lib.baseboard_fab2(sch_1):page154_i92"
				( attribute "BOM_COST" "MIO_BIOS_MEM"
					( Origin gFrontEnd )
				)
				( attribute "CDS_LIB" "mstr_discrete"
					( Origin gPackager )
				)
				( attribute "CDS_LOCATION" "R2T2"
					( Origin gPackager )
				)
				( attribute "CDS_SEC" "1"
					( Origin gPackager )
				)
				( attribute "LOCATION" "R2T2"
					( Origin gFrontEnd )
				)
				( attribute "MATERIAL" "CHIP"
					( Origin gFrontEnd )
				)
				( attribute "PACK_TYPE" "0402"
					( Origin gFrontEnd )
				)
				( attribute "PART_NUMBER" "G21497-005"
					( Origin gFrontEnd )
				)
				( attribute "PHYS_PAGE" "154"
					( Origin gFrontEnd )
				)
				( attribute "ROOM" "SB_BMC_SPI_MUX"
					( Origin gFrontEnd )
				)
				( attribute "ROT" "0"
					( Origin gFrontEnd )
				)
				( attribute "SEC" "1"
					( Origin gFrontEnd )
				)
				( attribute "SEC_TYPE" "0402"
					( Origin gFrontEnd )
				)
				( attribute "TOLERANCE" "5%"
					( Origin gFrontEnd )
				)
				( attribute "VALUE" "0.0"
					( Origin gFrontEnd )
				)
				( attribute "VER" "1"
					( Origin gFrontEnd )
				)
				( attribute "WATTAGE" "1/16W"
					( Origin gFrontEnd )
				)
				( attribute "XY" "(-2925,3975)"
					( Origin gFrontEnd )
				)
				( attribute "CHIPS_PART_NAME" "RES"
					( Origin gPackager )
				)
				( attribute "CDS_PART_NAME" "RES_0402-0.0,5%,1/16W,CHIP,G21A"
					( Origin gPackager )
				)
				( objectStatus "R2T2" )
				( pin "a"
					( attribute "PN" "1"
						( Origin gPackager )
					)
					( objectStatus "R2T2.1" )
				)
				( pin "b"
					( attribute "PN" "2"
						( Origin gPackager )
					)
					( objectStatus "R2T2.2" )
				)
			)
			( gate "@baseboard_fab2_lib.baseboard_fab2(sch_1):page154_i93"
				( attribute "BOM_COST" "MIO_BIOS_MEM"
					( Origin gFrontEnd )
				)
				( attribute "CDS_LIB" "mstr_discrete"
					( Origin gPackager )
				)
				( attribute "CDS_LOCATION" "R2R12"
					( Origin gPackager )
				)
				( attribute "CDS_SEC" "1"
					( Origin gPackager )
				)
				( attribute "LOCATION" "R2R12"
					( Origin gFrontEnd )
				)
				( attribute "MATERIAL" "CHIP"
					( Origin gFrontEnd )
				)
				( attribute "PACK_TYPE" "0402"
					( Origin gFrontEnd )
				)
				( attribute "PART_NUMBER" "G21497-005"
					( Origin gFrontEnd )
				)
				( attribute "PHYS_PAGE" "154"
					( Origin gFrontEnd )
				)
				( attribute "ROOM" "SB_BMC_SPI_MUX"
					( Origin gFrontEnd )
				)
				( attribute "ROT" "0"
					( Origin gFrontEnd )
				)
				( attribute "SEC" "1"
					( Origin gFrontEnd )
				)
				( attribute "SEC_TYPE" "0402"
					( Origin gFrontEnd )
				)
				( attribute "TOLERANCE" "5%"
					( Origin gFrontEnd )
				)
				( attribute "VALUE" "0.0"
					( Origin gFrontEnd )
				)
				( attribute "VER" "1"
					( Origin gFrontEnd )
				)
				( attribute "WATTAGE" "1/16W"
					( Origin gFrontEnd )
				)
				( attribute "XY" "(-2925,4075)"
					( Origin gFrontEnd )
				)
				( attribute "CHIPS_PART_NAME" "RES"
					( Origin gPackager )
				)
				( attribute "CDS_PART_NAME" "RES_0402-0.0,5%,1/16W,CHIP,G21A"
					( Origin gPackager )
				)
				( objectStatus "R2R12" )
				( pin "a"
					( attribute "PN" "1"
						( Origin gPackager )
					)
					( objectStatus "R2R12.1" )
				)
				( pin "b"
					( attribute "PN" "2"
						( Origin gPackager )
					)
					( objectStatus "R2R12.2" )
				)
			)
			( gate "@baseboard_fab2_lib.baseboard_fab2(sch_1):page154_i94"
				( attribute "BOM_COST" "MIO_BIOS_MEM"
					( Origin gFrontEnd )
				)
				( attribute "CDS_LIB" "dev_discrete"
					( Origin gPackager )
				)
				( attribute "CDS_LOCATION" "C2T1"
					( Origin gPackager )
				)
				( attribute "CDS_SEC" "1"
					( Origin gPackager )
				)
				( attribute "LOCATION" "C2T1"
					( Origin gFrontEnd )
				)
				( attribute "MATERIAL" "X7R"
					( Origin gFrontEnd )
				)
				( attribute "PACK_TYPE" "0402V"
					( Origin gFrontEnd )
				)
				( attribute "PART_NUMBER" "A36096-030"
					( Origin gFrontEnd )
				)
				( attribute "PHYS_PAGE" "154"
					( Origin gFrontEnd )
				)
				( attribute "ROOM" "SB_BMC_SPI_MUX"
					( Origin gFrontEnd )
				)
				( attribute "ROT" "0"
					( Origin gFrontEnd )
				)
				( attribute "SEC" "1"
					( Origin gFrontEnd )
				)
				( attribute "SEC_TYPE" "0402V"
					( Origin gFrontEnd )
				)
				( attribute "TOLERANCE" "10%"
					( Origin gFrontEnd )
				)
				( attribute "VALUE" "0.1UF"
					( Origin gFrontEnd )
				)
				( attribute "VER" "1"
					( Origin gFrontEnd )
				)
				( attribute "VOLTAGE" "16V"
					( Units "uVoltage" "V" 1.000000)
					( Origin gFrontEnd )
				)
				( attribute "XY" "(-1500,4525)"
					( Origin gFrontEnd )
				)
				( attribute "CHIPS_PART_NAME" "CAP_A"
					( Origin gPackager )
				)
				( attribute "CDS_PART_NAME" "CAP_A_0402V-0.1UF,16V,10%,X7R,A"
					( Origin gPackager )
				)
				( objectStatus "C2T1" )
				( pin "a"
					( attribute "PN" "1"
						( Origin gPackager )
					)
					( objectStatus "C2T1.1" )
				)
				( pin "b"
					( attribute "PN" "2"
						( Origin gPackager )
					)
					( objectStatus "C2T1.2" )
				)
			)
			( gate "@baseboard_fab2_lib.baseboard_fab2(sch_1):page154_i99"
				( attribute "BOM_COST" "MIO_BIOS_MEM"
					( Origin gFrontEnd )
				)
				( attribute "CDS_LIB" "mstr_ttl"
					( Origin gPackager )
				)
				( attribute "CDS_LOCATION" "U2T3"
					( Origin gPackager )
				)
				( attribute "CDS_SEC" "1"
					( Origin gPackager )
				)
				( attribute "LOCATION" "U2T3"
					( Origin gFrontEnd )
				)
				( attribute "MATERIAL" "IC"
					( Origin gFrontEnd )
				)
				( attribute "PACK_TYPE" "SOT"
					( Origin gFrontEnd )
				)
				( attribute "PART_NUMBER" "E60229-001"
					( Origin gFrontEnd )
				)
				( attribute "PHYS_PAGE" "154"
					( Origin gFrontEnd )
				)
				( attribute "ROOM" "SB_BMC_SPI_MUX"
					( Origin gFrontEnd )
				)
				( attribute "ROT" "0"
					( Origin gFrontEnd )
				)
				( attribute "SEC" "1"
					( Origin gFrontEnd )
				)
				( attribute "SEC_TYPE" "SOT"
					( Origin gFrontEnd )
				)
				( attribute "VALUE" "74LVC1G32"
					( Origin gFrontEnd )
				)
				( attribute "VER" "1"
					( Origin gFrontEnd )
				)
				( attribute "XY" "(-2275,1875)"
					( Origin gFrontEnd )
				)
				( attribute "CHIPS_PART_NAME" "TTL1G32_A"
					( Origin gPackager )
				)
				( attribute "CDS_PART_NAME" "TTL1G32_A_SOT-74LVC1G32,IC,E60B"
					( Origin gPackager )
				)
				( objectStatus "U2T3" )
				( pin "a"
					( attribute "PN" "1"
						( Origin gPackager )
					)
					( objectStatus "U2T3.1" )
				)
				( pin "b"
					( attribute "PN" "2"
						( Origin gPackager )
					)
					( objectStatus "U2T3.2" )
				)
				( pin "y"
					( attribute "PN" "4"
						( Origin gPackager )
					)
					( objectStatus "U2T3.4" )
				)
			)
			( gate "@baseboard_fab2_lib.baseboard_fab2(sch_1):page154_i100"
				( attribute "BOM_COST" "MIO_BIOS_MEM"
					( Origin gFrontEnd )
				)
				( attribute "CDS_LIB" "mstr_ttl"
					( Origin gPackager )
				)
				( attribute "CDS_LOCATION" "U2T2"
					( Origin gPackager )
				)
				( attribute "CDS_SEC" "1"
					( Origin gPackager )
				)
				( attribute "LOCATION" "U2T2"
					( Origin gFrontEnd )
				)
				( attribute "MATERIAL" "IC"
					( Origin gFrontEnd )
				)
				( attribute "PACK_TYPE" "SOT"
					( Origin gFrontEnd )
				)
				( attribute "PART_NUMBER" "E60229-001"
					( Origin gFrontEnd )
				)
				( attribute "PHYS_PAGE" "154"
					( Origin gFrontEnd )
				)
				( attribute "ROOM" "SB_BMC_SPI_MUX"
					( Origin gFrontEnd )
				)
				( attribute "ROT" "0"
					( Origin gFrontEnd )
				)
				( attribute "SEC" "1"
					( Origin gFrontEnd )
				)
				( attribute "SEC_TYPE" "SOT"
					( Origin gFrontEnd )
				)
				( attribute "VALUE" "74LVC1G32"
					( Origin gFrontEnd )
				)
				( attribute "VER" "1"
					( Origin gFrontEnd )
				)
				( attribute "XY" "(-2275,1150)"
					( Origin gFrontEnd )
				)
				( attribute "CHIPS_PART_NAME" "TTL1G32_A"
					( Origin gPackager )
				)
				( attribute "CDS_PART_NAME" "TTL1G32_A_SOT-74LVC1G32,IC,E60B"
					( Origin gPackager )
				)
				( objectStatus "U2T2" )
				( pin "a"
					( attribute "PN" "1"
						( Origin gPackager )
					)
					( objectStatus "U2T2.1" )
				)
				( pin "b"
					( attribute "PN" "2"
						( Origin gPackager )
					)
					( objectStatus "U2T2.2" )
				)
				( pin "y"
					( attribute "PN" "4"
						( Origin gPackager )
					)
					( objectStatus "U2T2.4" )
				)
			)
			( gate "@baseboard_fab2_lib.baseboard_fab2(sch_1):page154_i101"
				( attribute "BOM_COST" "MIO_BIOS_MEM"
					( Origin gFrontEnd )
				)
				( attribute "CDS_LIB" "mstr_discrete"
					( Origin gPackager )
				)
				( attribute "CDS_LOCATION" "R2T13"
					( Origin gPackager )
				)
				( attribute "CDS_SEC" "1"
					( Origin gPackager )
				)
				( attribute "LOCATION" "R2T13"
					( Origin gFrontEnd )
				)
				( attribute "MATERIAL" "CHIP"
					( Origin gFrontEnd )
				)
				( attribute "PACK_TYPE" "0402"
					( Origin gFrontEnd )
				)
				( attribute "PART_NUMBER" "G21796-004"
					( Origin gFrontEnd )
				)
				( attribute "PHYS_PAGE" "154"
					( Origin gFrontEnd )
				)
				( attribute "ROOM" "SB_BMC_SPI_MUX"
					( Origin gFrontEnd )
				)
				( attribute "ROT" "0"
					( Origin gFrontEnd )
				)
				( attribute "SEC" "1"
					( Origin gFrontEnd )
				)
				( attribute "SEC_TYPE" "0402"
					( Origin gFrontEnd )
				)
				( attribute "TOLERANCE" "1%"
					( Origin gFrontEnd )
				)
				( attribute "VALUE" "200.0"
					( Origin gFrontEnd )
				)
				( attribute "VER" "1"
					( Origin gFrontEnd )
				)
				( attribute "WATTAGE" "1/16W"
					( Origin gFrontEnd )
				)
				( attribute "XY" "(-1450,1875)"
					( Origin gFrontEnd )
				)
				( attribute "CHIPS_PART_NAME" "RES"
					( Origin gPackager )
				)
				( attribute "CDS_PART_NAME" "RES_0402-200.0,1%,1/16W,CHIP,GA"
					( Origin gPackager )
				)
				( objectStatus "R2T13" )
				( pin "a"
					( attribute "PN" "1"
						( Origin gPackager )
					)
					( objectStatus "R2T13.1" )
				)
				( pin "b"
					( attribute "PN" "2"
						( Origin gPackager )
					)
					( objectStatus "R2T13.2" )
				)
			)
			( gate "@baseboard_fab2_lib.baseboard_fab2(sch_1):page154_i105"
				( attribute "BOM_COST" "MIO_BIOS_MEM"
					( Origin gFrontEnd )
				)
				( attribute "CDS_LIB" "mstr_discrete"
					( Origin gPackager )
				)
				( attribute "CDS_LOCATION" "R2T11"
					( Origin gPackager )
				)
				( attribute "CDS_SEC" "1"
					( Origin gPackager )
				)
				( attribute "LOCATION" "R2T11"
					( Origin gFrontEnd )
				)
				( attribute "MATERIAL" "CHIP"
					( Origin gFrontEnd )
				)
				( attribute "PACK_TYPE" "0402"
					( Origin gFrontEnd )
				)
				( attribute "PART_NUMBER" "G21796-072"
					( Origin gFrontEnd )
				)
				( attribute "PHYS_PAGE" "154"
					( Origin gFrontEnd )
				)
				( attribute "ROOM" "SB_BMC_SPI_MUX"
					( Origin gFrontEnd )
				)
				( attribute "ROT" "0"
					( Origin gFrontEnd )
				)
				( attribute "SEC" "1"
					( Origin gFrontEnd )
				)
				( attribute "SEC_TYPE" "0402"
					( Origin gFrontEnd )
				)
				( attribute "TOLERANCE" "1%"
					( Origin gFrontEnd )
				)
				( attribute "VALUE" "4.75K"
					( Origin gFrontEnd )
				)
				( attribute "VER" "2"
					( Origin gFrontEnd )
				)
				( attribute "WATTAGE" "1/16W"
					( Origin gFrontEnd )
				)
				( attribute "XY" "(-3100,2200)"
					( Origin gFrontEnd )
				)
				( attribute "CHIPS_PART_NAME" "RES"
					( Origin gPackager )
				)
				( attribute "CDS_PART_NAME" "RES_0402-4.75K,1%,1/16W,CHIP,GA"
					( Origin gPackager )
				)
				( objectStatus "R2T11" )
				( pin "a"
					( attribute "PN" "1"
						( Origin gPackager )
					)
					( objectStatus "R2T11.1" )
				)
				( pin "b"
					( attribute "PN" "2"
						( Origin gPackager )
					)
					( objectStatus "R2T11.2" )
				)
			)
			( gate "@baseboard_fab2_lib.baseboard_fab2(sch_1):page154_i106"
				( attribute "BOM_COST" "MIO_BIOS_MEM"
					( Origin gFrontEnd )
				)
				( attribute "CDS_LIB" "mstr_discrete"
					( Origin gPackager )
				)
				( attribute "CDS_LOCATION" "R2T8"
					( Origin gPackager )
				)
				( attribute "CDS_SEC" "1"
					( Origin gPackager )
				)
				( attribute "LOCATION" "R2T8"
					( Origin gFrontEnd )
				)
				( attribute "MATERIAL" "CHIP"
					( Origin gFrontEnd )
				)
				( attribute "PACK_TYPE" "0402"
					( Origin gFrontEnd )
				)
				( attribute "PART_NUMBER" "G21796-016"
					( Origin gFrontEnd )
				)
				( attribute "PHYS_PAGE" "154"
					( Origin gFrontEnd )
				)
				( attribute "ROOM" "SB_BMC_SPI_MUX"
					( Origin gFrontEnd )
				)
				( attribute "ROT" "2"
					( Origin gFrontEnd )
				)
				( attribute "SEC" "1"
					( Origin gFrontEnd )
				)
				( attribute "SEC_TYPE" "0402"
					( Origin gFrontEnd )
				)
				( attribute "TOLERANCE" "1%"
					( Origin gFrontEnd )
				)
				( attribute "VALUE" "10.0K"
					( Origin gFrontEnd )
				)
				( attribute "VER" "2"
					( Origin gFrontEnd )
				)
				( attribute "WATTAGE" "1/16W"
					( Origin gFrontEnd )
				)
				( attribute "XY" "(-3775,1750)"
					( Origin gFrontEnd )
				)
				( attribute "CHIPS_PART_NAME" "RES"
					( Origin gPackager )
				)
				( attribute "CDS_PART_NAME" "RES_0402-10.0K,1%,1/16W,CHIP,GA"
					( Origin gPackager )
				)
				( objectStatus "R2T8" )
				( pin "a"
					( attribute "PN" "1"
						( Origin gPackager )
					)
					( objectStatus "R2T8.1" )
				)
				( pin "b"
					( attribute "PN" "2"
						( Origin gPackager )
					)
					( objectStatus "R2T8.2" )
				)
			)
			( gate "@baseboard_fab2_lib.baseboard_fab2(sch_1):page154_i119"
				( attribute "CDS_LIB" "mstr_discrete"
					( Origin gPackager )
				)
				( attribute "CDS_LOCATION" "R8F6"
					( Origin gPackager )
				)
				( attribute "CDS_SEC" "1"
					( Origin gPackager )
				)
				( attribute "LOCATION" "R8F6"
					( Origin gFrontEnd )
				)
				( attribute "MATERIAL" "CHIP"
					( Origin gFrontEnd )
				)
				( attribute "PACK_TYPE" "0402"
					( Origin gFrontEnd )
				)
				( attribute "PART_NUMBER" "G21497-005"
					( Origin gFrontEnd )
				)
				( attribute "PHYS_PAGE" "154"
					( Origin gFrontEnd )
				)
				( attribute "ROOM" "MIO_BIOS_MEM"
					( Origin gFrontEnd )
				)
				( attribute "ROT" "0"
					( Origin gFrontEnd )
				)
				( attribute "SEC" "1"
					( Origin gPackager )
				)
				( attribute "TOLERANCE" "5%"
					( Origin gFrontEnd )
				)
				( attribute "VALUE" "0.0"
					( Origin gFrontEnd )
				)
				( attribute "VER" "1"
					( Origin gFrontEnd )
				)
				( attribute "WATTAGE" "1/16W"
					( Origin gFrontEnd )
				)
				( attribute "XY" "(-6725,3600)"
					( Origin gFrontEnd )
				)
				( attribute "CHIPS_PART_NAME" "RES"
					( Origin gPackager )
				)
				( attribute "CDS_PART_NAME" "RES_0402-0.0,5%,1/16W,CHIP,G21A"
					( Origin gPackager )
				)
				( objectStatus "R8F6" )
				( pin "a"
					( attribute "PN" "1"
						( Origin gPackager )
					)
					( objectStatus "R8F6.1" )
				)
				( pin "b"
					( attribute "PN" "2"
						( Origin gPackager )
					)
					( objectStatus "R8F6.2" )
				)
			)
			( gate "@baseboard_fab2_lib.baseboard_fab2(sch_1):page154_i126"
				( attribute "BOM_COST" "MIO_BIOS_MEM"
					( Origin gFrontEnd )
				)
				( attribute "CDS_LIB" "mstr_discrete"
					( Origin gPackager )
				)
				( attribute "CDS_LOCATION" "Q8F1"
					( Origin gPackager )
				)
				( attribute "CDS_SEC" "1"
					( Origin gPackager )
				)
				( attribute "LOCATION" "Q8F1"
					( Origin gFrontEnd )
				)
				( attribute "MATERIAL" "FET"
					( Origin gFrontEnd )
				)
				( attribute "PACK_TYPE" "SOT23LF"
					( Origin gFrontEnd )
				)
				( attribute "PART_NUMBER" "C79254-001"
					( Origin gFrontEnd )
				)
				( attribute "PHYS_PAGE" "154"
					( Origin gFrontEnd )
				)
				( attribute "ROOM" "SB_BMC_SPI_MUX"
					( Origin gFrontEnd )
				)
				( attribute "ROT" "0"
					( Origin gFrontEnd )
				)
				( attribute "SEC" "1"
					( Origin gFrontEnd )
				)
				( attribute "SEC_TYPE" "SOT23LF"
					( Origin gFrontEnd )
				)
				( attribute "VALUE" "2N7002"
					( Origin gFrontEnd )
				)
				( attribute "VER" "8"
					( Origin gFrontEnd )
				)
				( attribute "XY" "(-3100,1575)"
					( Origin gFrontEnd )
				)
				( attribute "CHIPS_PART_NAME" "FET_N"
					( Origin gPackager )
				)
				( attribute "CDS_PART_NAME" "FET_N_SOT23LF-2N7002,FET,C7925A"
					( Origin gPackager )
				)
				( objectStatus "Q8F1" )
				( pin "drn"
					( attribute "PN" "3"
						( Origin gPackager )
					)
					( objectStatus "Q8F1.3" )
				)
				( pin "gate"
					( attribute "PN" "1"
						( Origin gPackager )
					)
					( objectStatus "Q8F1.1" )
				)
				( pin "src"
					( attribute "PN" "2"
						( Origin gPackager )
					)
					( objectStatus "Q8F1.2" )
				)
			)
			( gate "@baseboard_fab2_lib.baseboard_fab2(sch_1):page154_i127"
				( attribute "BOM_COST" "MIO_BIOS_MEM"
					( Origin gFrontEnd )
				)
				( attribute "CDS_LIB" "mstr_discrete"
					( Origin gPackager )
				)
				( attribute "CDS_LOCATION" "R2T6"
					( Origin gPackager )
				)
				( attribute "CDS_SEC" "1"
					( Origin gPackager )
				)
				( attribute "LOCATION" "R2T6"
					( Origin gFrontEnd )
				)
				( attribute "MATERIAL" "CHIP"
					( Origin gFrontEnd )
				)
				( attribute "PACK_TYPE" "0402"
					( Origin gFrontEnd )
				)
				( attribute "PART_NUMBER" "G21796-072"
					( Origin gFrontEnd )
				)
				( attribute "PHYS_PAGE" "154"
					( Origin gFrontEnd )
				)
				( attribute "ROOM" "SB_BMC_SPI_MUX"
					( Origin gFrontEnd )
				)
				( attribute "ROT" "2"
					( Origin gFrontEnd )
				)
				( attribute "SEC" "1"
					( Origin gPackager )
				)
				( attribute "TOLERANCE" "1%"
					( Origin gFrontEnd )
				)
				( attribute "VALUE" "4.75K"
					( Origin gFrontEnd )
				)
				( attribute "VER" "2"
					( Origin gFrontEnd )
				)
				( attribute "WATTAGE" "1/16W"
					( Origin gFrontEnd )
				)
				( attribute "XY" "(-3400,1750)"
					( Origin gFrontEnd )
				)
				( attribute "CHIPS_PART_NAME" "RES"
					( Origin gPackager )
				)
				( attribute "CDS_PART_NAME" "RES_0402-4.75K,1%,1/16W,CHIP,GA"
					( Origin gPackager )
				)
				( objectStatus "R2T6" )
				( pin "a"
					( attribute "PN" "1"
						( Origin gPackager )
					)
					( objectStatus "R2T6.1" )
				)
				( pin "b"
					( attribute "PN" "2"
						( Origin gPackager )
					)
					( objectStatus "R2T6.2" )
				)
			)
			( gate "@baseboard_fab2_lib.baseboard_fab2(sch_1):page154_i128"
				( attribute "BOM_COST" "MIO_BIOS_MEM"
					( Origin gFrontEnd )
				)
				( attribute "CDS_LIB" "mstr_discrete"
					( Origin gPackager )
				)
				( attribute "CDS_LOCATION" "R1U6"
					( Origin gPackager )
				)
				( attribute "CDS_SEC" "1"
					( Origin gPackager )
				)
				( attribute "LOCATION" "R1U6"
					( Origin gFrontEnd )
				)
				( attribute "MATERIAL" "CHIP"
					( Origin gFrontEnd )
				)
				( attribute "PACK_TYPE" "0402"
					( Origin gFrontEnd )
				)
				( attribute "PART_NUMBER" "G21796-016"
					( Origin gFrontEnd )
				)
				( attribute "PHYS_PAGE" "154"
					( Origin gFrontEnd )
				)
				( attribute "ROOM" "SB_BMC_BPI_MUX"
					( Origin gFrontEnd )
				)
				( attribute "ROT" "0"
					( Origin gFrontEnd )
				)
				( attribute "SEC" "1"
					( Origin gFrontEnd )
				)
				( attribute "SEC_TYPE" "0402"
					( Origin gFrontEnd )
				)
				( attribute "TOLERANCE" "1%"
					( Origin gFrontEnd )
				)
				( attribute "VALUE" "10.0K"
					( Origin gFrontEnd )
				)
				( attribute "VER" "2"
					( Origin gFrontEnd )
				)
				( attribute "WATTAGE" "1/16W"
					( Origin gFrontEnd )
				)
				( attribute "XY" "(-6250,2750)"
					( Origin gFrontEnd )
				)
				( attribute "CHIPS_PART_NAME" "RES"
					( Origin gPackager )
				)
				( attribute "CDS_PART_NAME" "RES_0402-10.0K,1%,1/16W,CHIP,GA"
					( Origin gPackager )
				)
				( objectStatus "R1U6" )
				( pin "a"
					( attribute "PN" "1"
						( Origin gPackager )
					)
					( objectStatus "R1U6.1" )
				)
				( pin "b"
					( attribute "PN" "2"
						( Origin gPackager )
					)
					( objectStatus "R1U6.2" )
				)
			)
			( gate "@baseboard_fab2_lib.baseboard_fab2(sch_1):page154_i132"
				( attribute "BOM_COST" "MIO_BIOS_MEM"
					( Origin gFrontEnd )
				)
				( attribute "CDS_LIB" "dev_discrete"
					( Origin gPackager )
				)
				( attribute "CDS_LOCATION" "C2T12"
					( Origin gPackager )
				)
				( attribute "CDS_SEC" "1"
					( Origin gPackager )
				)
				( attribute "LOCATION" "C2T12"
					( Origin gFrontEnd )
				)
				( attribute "MATERIAL" "X7R"
					( Origin gFrontEnd )
				)
				( attribute "PACK_TYPE" "0402V"
					( Origin gFrontEnd )
				)
				( attribute "PART_NUMBER" "A36096-030"
					( Origin gFrontEnd )
				)
				( attribute "PHYS_PAGE" "154"
					( Origin gFrontEnd )
				)
				( attribute "ROOM" "SB_BMC_SPI_MUX"
					( Origin gFrontEnd )
				)
				( attribute "ROT" "0"
					( Origin gFrontEnd )
				)
				( attribute "SEC" "1"
					( Origin gFrontEnd )
				)
				( attribute "SEC_TYPE" "0402V"
					( Origin gFrontEnd )
				)
				( attribute "TOLERANCE" "10%"
					( Origin gFrontEnd )
				)
				( attribute "VALUE" "0.1UF"
					( Origin gFrontEnd )
				)
				( attribute "VER" "1"
					( Origin gFrontEnd )
				)
				( attribute "VOLTAGE" "16V"
					( Units "uVoltage" "V" 1.000000)
					( Origin gFrontEnd )
				)
				( attribute "XY" "(-375,2225)"
					( Origin gFrontEnd )
				)
				( attribute "CHIPS_PART_NAME" "CAP_A"
					( Origin gPackager )
				)
				( attribute "CDS_PART_NAME" "CAP_A_0402V-0.1UF,16V,10%,X7R,A"
					( Origin gPackager )
				)
				( objectStatus "C2T12" )
				( pin "a"
					( attribute "PN" "1"
						( Origin gPackager )
					)
					( objectStatus "C2T12.1" )
				)
				( pin "b"
					( attribute "PN" "2"
						( Origin gPackager )
					)
					( objectStatus "C2T12.2" )
				)
			)
			( gate "@baseboard_fab2_lib.baseboard_fab2(sch_1):page154_i135"
				( attribute "BOM_COST" "MIO_BIOS_MEM"
					( Origin gFrontEnd )
				)
				( attribute "CDS_LIB" "dev_discrete"
					( Origin gPackager )
				)
				( attribute "CDS_LOCATION" "C2T8"
					( Origin gPackager )
				)
				( attribute "CDS_SEC" "1"
					( Origin gPackager )
				)
				( attribute "LOCATION" "C2T8"
					( Origin gFrontEnd )
				)
				( attribute "MATERIAL" "X7R"
					( Origin gFrontEnd )
				)
				( attribute "PACK_TYPE" "0402V"
					( Origin gFrontEnd )
				)
				( attribute "PART_NUMBER" "A36096-030"
					( Origin gFrontEnd )
				)
				( attribute "PHYS_PAGE" "154"
					( Origin gFrontEnd )
				)
				( attribute "ROOM" "SB_BMC_SPI_MUX"
					( Origin gFrontEnd )
				)
				( attribute "ROT" "0"
					( Origin gFrontEnd )
				)
				( attribute "SEC" "1"
					( Origin gFrontEnd )
				)
				( attribute "SEC_TYPE" "0402V"
					( Origin gFrontEnd )
				)
				( attribute "TOLERANCE" "10%"
					( Origin gFrontEnd )
				)
				( attribute "VALUE" "0.1UF"
					( Origin gFrontEnd )
				)
				( attribute "VER" "1"
					( Origin gFrontEnd )
				)
				( attribute "VOLTAGE" "16V"
					( Units "uVoltage" "V" 1.000000)
					( Origin gFrontEnd )
				)
				( attribute "XY" "(-375,1400)"
					( Origin gFrontEnd )
				)
				( attribute "CHIPS_PART_NAME" "CAP_A"
					( Origin gPackager )
				)
				( attribute "CDS_PART_NAME" "CAP_A_0402V-0.1UF,16V,10%,X7R,A"
					( Origin gPackager )
				)
				( objectStatus "C2T8" )
				( pin "a"
					( attribute "PN" "1"
						( Origin gPackager )
					)
					( objectStatus "C2T8.1" )
				)
				( pin "b"
					( attribute "PN" "2"
						( Origin gPackager )
					)
					( objectStatus "C2T8.2" )
				)
			)
			( gate "@baseboard_fab2_lib.baseboard_fab2(sch_1):page155_i53"
				( attribute "BOM_COST" "DEBUG"
					( Origin gFrontEnd )
				)
				( attribute "CDS_LIB" "mstr_discrete"
					( Origin gPackager )
				)
				( attribute "CDS_LOCATION" "R9A8"
					( Origin gPackager )
				)
				( attribute "CDS_SEC" "1"
					( Origin gPackager )
				)
				( attribute "LOCATION" "R9A8"
					( Origin gFrontEnd )
				)
				( attribute "MATERIAL" "CHIP"
					( Origin gFrontEnd )
				)
				( attribute "PACK_TYPE" "0402"
					( Origin gFrontEnd )
				)
				( attribute "PART_NUMBER" "G21497-005"
					( Origin gFrontEnd )
				)
				( attribute "PHYS_PAGE" "155"
					( Origin gFrontEnd )
				)
				( attribute "ROOM" "BMC_DEBUG_HEADER"
					( Origin gFrontEnd )
				)
				( attribute "ROT" "0"
					( Origin gFrontEnd )
				)
				( attribute "SEC" "1"
					( Origin gFrontEnd )
				)
				( attribute "SEC_TYPE" "0402"
					( Origin gFrontEnd )
				)
				( attribute "TOLERANCE" "5%"
					( Origin gFrontEnd )
				)
				( attribute "VALUE" "0.0"
					( Origin gFrontEnd )
				)
				( attribute "VER" "1"
					( Origin gFrontEnd )
				)
				( attribute "WATTAGE" "1/16W"
					( Origin gFrontEnd )
				)
				( attribute "XY" "(-1575,1400)"
					( Origin gFrontEnd )
				)
				( attribute "CHIPS_PART_NAME" "RES"
					( Origin gPackager )
				)
				( attribute "CDS_PART_NAME" "RES_0402-0.0,5%,1/16W,CHIP,G21A"
					( Origin gPackager )
				)
				( objectStatus "R9A8" )
				( pin "a"
					( attribute "PN" "1"
						( Origin gPackager )
					)
					( objectStatus "R9A8.1" )
				)
				( pin "b"
					( attribute "PN" "2"
						( Origin gPackager )
					)
					( objectStatus "R9A8.2" )
				)
			)
			( gate "@baseboard_fab2_lib.baseboard_fab2(sch_1):page155_i65"
				( attribute "BOM_COST" "DEBUG"
					( Origin gFrontEnd )
				)
				( attribute "CDS_LIB" "mstr_discrete"
					( Origin gPackager )
				)
				( attribute "CDS_LOCATION" "R1L32"
					( Origin gPackager )
				)
				( attribute "CDS_SEC" "1"
					( Origin gPackager )
				)
				( attribute "LOCATION" "R1L32"
					( Origin gFrontEnd )
				)
				( attribute "MATERIAL" "CHIP"
					( Origin gFrontEnd )
				)
				( attribute "PACK_TYPE" "0402"
					( Origin gFrontEnd )
				)
				( attribute "PART_NUMBER" "G21796-066"
					( Origin gFrontEnd )
				)
				( attribute "PHYS_PAGE" "155"
					( Origin gFrontEnd )
				)
				( attribute "ROOM" "BMC_DEBUG_HEADER"
					( Origin gFrontEnd )
				)
				( attribute "ROT" "0"
					( Origin gFrontEnd )
				)
				( attribute "SEC" "1"
					( Origin gPackager )
				)
				( attribute "TOLERANCE" "1%"
					( Origin gFrontEnd )
				)
				( attribute "VALUE" "10.0"
					( Origin gFrontEnd )
				)
				( attribute "VER" "1"
					( Origin gFrontEnd )
				)
				( attribute "WATTAGE" "1/16W"
					( Origin gFrontEnd )
				)
				( attribute "XY" "(-6900,4650)"
					( Origin gFrontEnd )
				)
				( attribute "CHIPS_PART_NAME" "RES"
					( Origin gPackager )
				)
				( attribute "CDS_PART_NAME" "RES_0402-10.0,1%,1/16W,CHIP,G2A"
					( Origin gPackager )
				)
				( objectStatus "R1L32" )
				( pin "a"
					( attribute "PN" "1"
						( Origin gPackager )
					)
					( objectStatus "R1L32.1" )
				)
				( pin "b"
					( attribute "PN" "2"
						( Origin gPackager )
					)
					( objectStatus "R1L32.2" )
				)
			)
			( gate "@baseboard_fab2_lib.baseboard_fab2(sch_1):page155_i66"
				( attribute "BOM_COST" "DEBUG"
					( Origin gFrontEnd )
				)
				( attribute "CDS_LIB" "mstr_discrete"
					( Origin gPackager )
				)
				( attribute "CDS_LOCATION" "R1L30"
					( Origin gPackager )
				)
				( attribute "CDS_SEC" "1"
					( Origin gPackager )
				)
				( attribute "LOCATION" "R1L30"
					( Origin gFrontEnd )
				)
				( attribute "MATERIAL" "CHIP"
					( Origin gFrontEnd )
				)
				( attribute "PACK_TYPE" "0402"
					( Origin gFrontEnd )
				)
				( attribute "PART_NUMBER" "G21796-066"
					( Origin gFrontEnd )
				)
				( attribute "PHYS_PAGE" "155"
					( Origin gFrontEnd )
				)
				( attribute "ROOM" "BMC_DEBUG_HEADER"
					( Origin gFrontEnd )
				)
				( attribute "ROT" "0"
					( Origin gFrontEnd )
				)
				( attribute "SEC" "1"
					( Origin gPackager )
				)
				( attribute "TOLERANCE" "1%"
					( Origin gFrontEnd )
				)
				( attribute "VALUE" "10.0"
					( Origin gFrontEnd )
				)
				( attribute "VER" "1"
					( Origin gFrontEnd )
				)
				( attribute "WATTAGE" "1/16W"
					( Origin gFrontEnd )
				)
				( attribute "XY" "(-6900,4500)"
					( Origin gFrontEnd )
				)
				( attribute "CHIPS_PART_NAME" "RES"
					( Origin gPackager )
				)
				( attribute "CDS_PART_NAME" "RES_0402-10.0,1%,1/16W,CHIP,G2A"
					( Origin gPackager )
				)
				( objectStatus "R1L30" )
				( pin "a"
					( attribute "PN" "1"
						( Origin gPackager )
					)
					( objectStatus "R1L30.1" )
				)
				( pin "b"
					( attribute "PN" "2"
						( Origin gPackager )
					)
					( objectStatus "R1L30.2" )
				)
			)
			( gate "@baseboard_fab2_lib.baseboard_fab2(sch_1):page155_i67"
				( attribute "BOM_COST" "DEBUG"
					( Origin gFrontEnd )
				)
				( attribute "CDS_LIB" "mstr_discrete"
					( Origin gPackager )
				)
				( attribute "CDS_LOCATION" "R1L25"
					( Origin gPackager )
				)
				( attribute "CDS_SEC" "1"
					( Origin gPackager )
				)
				( attribute "LOCATION" "R1L25"
					( Origin gFrontEnd )
				)
				( attribute "MATERIAL" "CHIP"
					( Origin gFrontEnd )
				)
				( attribute "PACK_TYPE" "0402"
					( Origin gFrontEnd )
				)
				( attribute "PART_NUMBER" "G21796-066"
					( Origin gFrontEnd )
				)
				( attribute "PHYS_PAGE" "155"
					( Origin gFrontEnd )
				)
				( attribute "ROOM" "BMC_DEBUG_HEADER"
					( Origin gFrontEnd )
				)
				( attribute "ROT" "0"
					( Origin gFrontEnd )
				)
				( attribute "SEC" "1"
					( Origin gPackager )
				)
				( attribute "TOLERANCE" "1%"
					( Origin gFrontEnd )
				)
				( attribute "VALUE" "10.0"
					( Origin gFrontEnd )
				)
				( attribute "VER" "1"
					( Origin gFrontEnd )
				)
				( attribute "WATTAGE" "1/16W"
					( Origin gFrontEnd )
				)
				( attribute "XY" "(-6900,4350)"
					( Origin gFrontEnd )
				)
				( attribute "CHIPS_PART_NAME" "RES"
					( Origin gPackager )
				)
				( attribute "CDS_PART_NAME" "RES_0402-10.0,1%,1/16W,CHIP,G2A"
					( Origin gPackager )
				)
				( objectStatus "R1L25" )
				( pin "a"
					( attribute "PN" "1"
						( Origin gPackager )
					)
					( objectStatus "R1L25.1" )
				)
				( pin "b"
					( attribute "PN" "2"
						( Origin gPackager )
					)
					( objectStatus "R1L25.2" )
				)
			)
			( gate "@baseboard_fab2_lib.baseboard_fab2(sch_1):page155_i68"
				( attribute "BOM_COST" "DEBUG"
					( Origin gFrontEnd )
				)
				( attribute "CDS_LIB" "mstr_discrete"
					( Origin gPackager )
				)
				( attribute "CDS_LOCATION" "R1L24"
					( Origin gPackager )
				)
				( attribute "CDS_SEC" "1"
					( Origin gPackager )
				)
				( attribute "LOCATION" "R1L24"
					( Origin gFrontEnd )
				)
				( attribute "MATERIAL" "CHIP"
					( Origin gFrontEnd )
				)
				( attribute "PACK_TYPE" "0402"
					( Origin gFrontEnd )
				)
				( attribute "PART_NUMBER" "G21796-066"
					( Origin gFrontEnd )
				)
				( attribute "PHYS_PAGE" "155"
					( Origin gFrontEnd )
				)
				( attribute "ROOM" "BMC_DEBUG_HEADER"
					( Origin gFrontEnd )
				)
				( attribute "ROT" "0"
					( Origin gFrontEnd )
				)
				( attribute "SEC" "1"
					( Origin gPackager )
				)
				( attribute "TOLERANCE" "1%"
					( Origin gFrontEnd )
				)
				( attribute "VALUE" "10.0"
					( Origin gFrontEnd )
				)
				( attribute "VER" "1"
					( Origin gFrontEnd )
				)
				( attribute "WATTAGE" "1/16W"
					( Origin gFrontEnd )
				)
				( attribute "XY" "(-6900,4200)"
					( Origin gFrontEnd )
				)
				( attribute "CHIPS_PART_NAME" "RES"
					( Origin gPackager )
				)
				( attribute "CDS_PART_NAME" "RES_0402-10.0,1%,1/16W,CHIP,G2A"
					( Origin gPackager )
				)
				( objectStatus "R1L24" )
				( pin "a"
					( attribute "PN" "1"
						( Origin gPackager )
					)
					( objectStatus "R1L24.1" )
				)
				( pin "b"
					( attribute "PN" "2"
						( Origin gPackager )
					)
					( objectStatus "R1L24.2" )
				)
			)
			( gate "@baseboard_fab2_lib.baseboard_fab2(sch_1):page155_i73"
				( attribute "BOM_COST" "DEBUG"
					( Origin gFrontEnd )
				)
				( attribute "CDS_LIB" "mstr_discrete"
					( Origin gPackager )
				)
				( attribute "CDS_LOCATION" "R1L20"
					( Origin gPackager )
				)
				( attribute "CDS_SEC" "1"
					( Origin gPackager )
				)
				( attribute "LOCATION" "R1L20"
					( Origin gFrontEnd )
				)
				( attribute "MATERIAL" "CHIP"
					( Origin gFrontEnd )
				)
				( attribute "PACK_TYPE" "0402"
					( Origin gFrontEnd )
				)
				( attribute "PART_NUMBER" "G21796-066"
					( Origin gFrontEnd )
				)
				( attribute "PHYS_PAGE" "155"
					( Origin gFrontEnd )
				)
				( attribute "ROOM" "BMC_DEBUG_HEADER"
					( Origin gFrontEnd )
				)
				( attribute "ROT" "0"
					( Origin gFrontEnd )
				)
				( attribute "SEC" "1"
					( Origin gPackager )
				)
				( attribute "TOLERANCE" "1%"
					( Origin gFrontEnd )
				)
				( attribute "VALUE" "10.0"
					( Origin gFrontEnd )
				)
				( attribute "VER" "1"
					( Origin gFrontEnd )
				)
				( attribute "WATTAGE" "1/16W"
					( Origin gFrontEnd )
				)
				( attribute "XY" "(-6900,4050)"
					( Origin gFrontEnd )
				)
				( attribute "CHIPS_PART_NAME" "RES"
					( Origin gPackager )
				)
				( attribute "CDS_PART_NAME" "RES_0402-10.0,1%,1/16W,CHIP,G2A"
					( Origin gPackager )
				)
				( objectStatus "R1L20" )
				( pin "a"
					( attribute "PN" "1"
						( Origin gPackager )
					)
					( objectStatus "R1L20.1" )
				)
				( pin "b"
					( attribute "PN" "2"
						( Origin gPackager )
					)
					( objectStatus "R1L20.2" )
				)
			)
			( gate "@baseboard_fab2_lib.baseboard_fab2(sch_1):page155_i74"
				( attribute "BOM_COST" "DEBUG"
					( Origin gFrontEnd )
				)
				( attribute "CDS_LIB" "mstr_discrete"
					( Origin gPackager )
				)
				( attribute "CDS_LOCATION" "R1L18"
					( Origin gPackager )
				)
				( attribute "CDS_SEC" "1"
					( Origin gPackager )
				)
				( attribute "LOCATION" "R1L18"
					( Origin gFrontEnd )
				)
				( attribute "MATERIAL" "CHIP"
					( Origin gFrontEnd )
				)
				( attribute "PACK_TYPE" "0402"
					( Origin gFrontEnd )
				)
				( attribute "PART_NUMBER" "G21796-066"
					( Origin gFrontEnd )
				)
				( attribute "PHYS_PAGE" "155"
					( Origin gFrontEnd )
				)
				( attribute "ROOM" "BMC_DEBUG_HEADER"
					( Origin gFrontEnd )
				)
				( attribute "ROT" "0"
					( Origin gFrontEnd )
				)
				( attribute "SEC" "1"
					( Origin gPackager )
				)
				( attribute "TOLERANCE" "1%"
					( Origin gFrontEnd )
				)
				( attribute "VALUE" "10.0"
					( Origin gFrontEnd )
				)
				( attribute "VER" "1"
					( Origin gFrontEnd )
				)
				( attribute "WATTAGE" "1/16W"
					( Origin gFrontEnd )
				)
				( attribute "XY" "(-6900,3900)"
					( Origin gFrontEnd )
				)
				( attribute "CHIPS_PART_NAME" "RES"
					( Origin gPackager )
				)
				( attribute "CDS_PART_NAME" "RES_0402-10.0,1%,1/16W,CHIP,G2A"
					( Origin gPackager )
				)
				( objectStatus "R1L18" )
				( pin "a"
					( attribute "PN" "1"
						( Origin gPackager )
					)
					( objectStatus "R1L18.1" )
				)
				( pin "b"
					( attribute "PN" "2"
						( Origin gPackager )
					)
					( objectStatus "R1L18.2" )
				)
			)
			( gate "@baseboard_fab2_lib.baseboard_fab2(sch_1):page155_i75"
				( attribute "BOM_COST" "DEBUG"
					( Origin gFrontEnd )
				)
				( attribute "CDS_LIB" "mstr_discrete"
					( Origin gPackager )
				)
				( attribute "CDS_LOCATION" "R1L14"
					( Origin gPackager )
				)
				( attribute "CDS_SEC" "1"
					( Origin gPackager )
				)
				( attribute "LOCATION" "R1L14"
					( Origin gFrontEnd )
				)
				( attribute "MATERIAL" "CHIP"
					( Origin gFrontEnd )
				)
				( attribute "PACK_TYPE" "0402"
					( Origin gFrontEnd )
				)
				( attribute "PART_NUMBER" "G21796-066"
					( Origin gFrontEnd )
				)
				( attribute "PHYS_PAGE" "155"
					( Origin gFrontEnd )
				)
				( attribute "ROOM" "BMC_DEBUG_HEADER"
					( Origin gFrontEnd )
				)
				( attribute "ROT" "0"
					( Origin gFrontEnd )
				)
				( attribute "SEC" "1"
					( Origin gPackager )
				)
				( attribute "TOLERANCE" "1%"
					( Origin gFrontEnd )
				)
				( attribute "VALUE" "10.0"
					( Origin gFrontEnd )
				)
				( attribute "VER" "1"
					( Origin gFrontEnd )
				)
				( attribute "WATTAGE" "1/16W"
					( Origin gFrontEnd )
				)
				( attribute "XY" "(-6900,3750)"
					( Origin gFrontEnd )
				)
				( attribute "CHIPS_PART_NAME" "RES"
					( Origin gPackager )
				)
				( attribute "CDS_PART_NAME" "RES_0402-10.0,1%,1/16W,CHIP,G2A"
					( Origin gPackager )
				)
				( objectStatus "R1L14" )
				( pin "a"
					( attribute "PN" "1"
						( Origin gPackager )
					)
					( objectStatus "R1L14.1" )
				)
				( pin "b"
					( attribute "PN" "2"
						( Origin gPackager )
					)
					( objectStatus "R1L14.2" )
				)
			)
			( gate "@baseboard_fab2_lib.baseboard_fab2(sch_1):page155_i76"
				( attribute "BOM_COST" "DEBUG"
					( Origin gFrontEnd )
				)
				( attribute "CDS_LIB" "mstr_discrete"
					( Origin gPackager )
				)
				( attribute "CDS_LOCATION" "R1L11"
					( Origin gPackager )
				)
				( attribute "CDS_SEC" "1"
					( Origin gPackager )
				)
				( attribute "LOCATION" "R1L11"
					( Origin gFrontEnd )
				)
				( attribute "MATERIAL" "CHIP"
					( Origin gFrontEnd )
				)
				( attribute "PACK_TYPE" "0402"
					( Origin gFrontEnd )
				)
				( attribute "PART_NUMBER" "G21796-066"
					( Origin gFrontEnd )
				)
				( attribute "PHYS_PAGE" "155"
					( Origin gFrontEnd )
				)
				( attribute "ROOM" "BMC_DEBUG_HEADER"
					( Origin gFrontEnd )
				)
				( attribute "ROT" "0"
					( Origin gFrontEnd )
				)
				( attribute "SEC" "1"
					( Origin gPackager )
				)
				( attribute "TOLERANCE" "1%"
					( Origin gFrontEnd )
				)
				( attribute "VALUE" "10.0"
					( Origin gFrontEnd )
				)
				( attribute "VER" "1"
					( Origin gFrontEnd )
				)
				( attribute "WATTAGE" "1/16W"
					( Origin gFrontEnd )
				)
				( attribute "XY" "(-6900,3600)"
					( Origin gFrontEnd )
				)
				( attribute "CHIPS_PART_NAME" "RES"
					( Origin gPackager )
				)
				( attribute "CDS_PART_NAME" "RES_0402-10.0,1%,1/16W,CHIP,G2A"
					( Origin gPackager )
				)
				( objectStatus "R1L11" )
				( pin "a"
					( attribute "PN" "1"
						( Origin gPackager )
					)
					( objectStatus "R1L11.1" )
				)
				( pin "b"
					( attribute "PN" "2"
						( Origin gPackager )
					)
					( objectStatus "R1L11.2" )
				)
			)
			( gate "@baseboard_fab2_lib.baseboard_fab2(sch_1):page155_i80"
				( attribute "BOM_COST" "DEBUG"
					( Origin gFrontEnd )
				)
				( attribute "CDS_LIB" "mstr_discrete"
					( Origin gPackager )
				)
				( attribute "CDS_LOCATION" "R9A7"
					( Origin gPackager )
				)
				( attribute "CDS_SEC" "1"
					( Origin gPackager )
				)
				( attribute "LOCATION" "R9A7"
					( Origin gFrontEnd )
				)
				( attribute "MATERIAL" "CHIP"
					( Origin gFrontEnd )
				)
				( attribute "PACK_TYPE" "0402"
					( Origin gFrontEnd )
				)
				( attribute "PART_NUMBER" "G21796-112"
					( Origin gFrontEnd )
				)
				( attribute "PHYS_PAGE" "155"
					( Origin gFrontEnd )
				)
				( attribute "ROOM" "BMC_DEBUG_HEADER"
					( Origin gFrontEnd )
				)
				( attribute "ROT" "0"
					( Origin gFrontEnd )
				)
				( attribute "SEC" "1"
					( Origin gFrontEnd )
				)
				( attribute "SEC_TYPE" "0402"
					( Origin gFrontEnd )
				)
				( attribute "TOLERANCE" "1%"
					( Origin gFrontEnd )
				)
				( attribute "VALUE" "2.21K"
					( Origin gFrontEnd )
				)
				( attribute "VER" "2"
					( Origin gFrontEnd )
				)
				( attribute "WATTAGE" "1/16W"
					( Origin gFrontEnd )
				)
				( attribute "XY" "(-1900,1725)"
					( Origin gFrontEnd )
				)
				( attribute "CHIPS_PART_NAME" "RES"
					( Origin gPackager )
				)
				( attribute "CDS_PART_NAME" "RES_0402-2.21K,1%,1/16W,CHIP,GA"
					( Origin gPackager )
				)
				( objectStatus "R9A7" )
				( pin "a"
					( attribute "PN" "1"
						( Origin gPackager )
					)
					( objectStatus "R9A7.1" )
				)
				( pin "b"
					( attribute "PN" "2"
						( Origin gPackager )
					)
					( objectStatus "R9A7.2" )
				)
			)
			( gate "@baseboard_fab2_lib.baseboard_fab2(sch_1):page155_i127"
				( attribute "BOM_COST" "DEBUG"
					( Origin gFrontEnd )
				)
				( attribute "CDS_LIB" "dev_discrete"
					( Origin gPackager )
				)
				( attribute "CDS_LOCATION" "C9A1"
					( Origin gPackager )
				)
				( attribute "CDS_SEC" "1"
					( Origin gPackager )
				)
				( attribute "LOCATION" "C9A1"
					( Origin gFrontEnd )
				)
				( attribute "MATERIAL" "X7R"
					( Origin gFrontEnd )
				)
				( attribute "PACK_TYPE" "0402V"
					( Origin gFrontEnd )
				)
				( attribute "PART_NUMBER" "A36096-030"
					( Origin gFrontEnd )
				)
				( attribute "PHYS_PAGE" "155"
					( Origin gFrontEnd )
				)
				( attribute "ROOM" "BMC_DEBUG_HEADER"
					( Origin gFrontEnd )
				)
				( attribute "ROT" "0"
					( Origin gFrontEnd )
				)
				( attribute "SEC" "1"
					( Origin gPackager )
				)
				( attribute "TOLERANCE" "10%"
					( Origin gFrontEnd )
				)
				( attribute "VALUE" "0.1UF"
					( Origin gFrontEnd )
				)
				( attribute "VER" "1"
					( Origin gFrontEnd )
				)
				( attribute "VOLTAGE" "16V"
					( Units "uVoltage" "V" 1.000000)
					( Origin gFrontEnd )
				)
				( attribute "XY" "(-4100,1050)"
					( Origin gFrontEnd )
				)
				( attribute "CHIPS_PART_NAME" "CAP_A"
					( Origin gPackager )
				)
				( attribute "CDS_PART_NAME" "CAP_A_0402V-0.1UF,16V,10%,X7R,A"
					( Origin gPackager )
				)
				( objectStatus "C9A1" )
				( pin "a"
					( attribute "PN" "1"
						( Origin gPackager )
					)
					( objectStatus "C9A1.1" )
				)
				( pin "b"
					( attribute "PN" "2"
						( Origin gPackager )
					)
					( objectStatus "C9A1.2" )
				)
			)
			( gate "@baseboard_fab2_lib.baseboard_fab2(sch_1):page155_i129"
				( attribute "BOM_COST" "DEBUG"
					( Origin gFrontEnd )
				)
				( attribute "CDS_LIB" "mstr_discrete"
					( Origin gPackager )
				)
				( attribute "CDS_LOCATION" "F1L1"
					( Origin gPackager )
				)
				( attribute "CDS_SEC" "1"
					( Origin gPackager )
				)
				( attribute "LOCATION" "F1L1"
					( Origin gFrontEnd )
				)
				( attribute "MATERIAL" "IC"
					( Origin gFrontEnd )
				)
				( attribute "PACK_TYPE" "SMT"
					( Origin gFrontEnd )
				)
				( attribute "PART_NUMBER" "H45581-001"
					( Origin gFrontEnd )
				)
				( attribute "PHYS_PAGE" "155"
					( Origin gFrontEnd )
				)
				( attribute "ROOM" "BMC_DEBUG_HEADER"
					( Origin gFrontEnd )
				)
				( attribute "ROT" "0"
					( Origin gFrontEnd )
				)
				( attribute "SEC" "1"
					( Origin gFrontEnd )
				)
				( attribute "SEC_TYPE" "SMT"
					( Origin gFrontEnd )
				)
				( attribute "VER" "1"
					( Origin gFrontEnd )
				)
				( attribute "XY" "(-4275,2625)"
					( Origin gFrontEnd )
				)
				( attribute "CHIPS_PART_NAME" "FUSE"
					( Origin gPackager )
				)
				( attribute "CDS_PART_NAME" "FUSE_SMT-IC,H45581-001"
					( Origin gPackager )
				)
				( objectStatus "F1L1" )
				( pin "a(0)"
					( attribute "PN" "1"
						( Origin gPackager )
					)
					( objectStatus "F1L1.1" )
				)
				( pin "b(0)"
					( attribute "PN" "2"
						( Origin gPackager )
					)
					( objectStatus "F1L1.2" )
				)
			)
			( gate "@baseboard_fab2_lib.baseboard_fab2(sch_1):page155_i130"
				( attribute "BOM_COST" "DEBUG"
					( Origin gFrontEnd )
				)
				( attribute "CDS_LIB" "mstr_discrete"
					( Origin gPackager )
				)
				( attribute "CDS_LOCATION" "R1L9"
					( Origin gPackager )
				)
				( attribute "CDS_SEC" "1"
					( Origin gPackager )
				)
				( attribute "LOCATION" "R1L9"
					( Origin gFrontEnd )
				)
				( attribute "MATERIAL" "CHIP"
					( Origin gFrontEnd )
				)
				( attribute "PACK_TYPE" "0402"
					( Origin gFrontEnd )
				)
				( attribute "PART_NUMBER" "G21796-010"
					( Origin gFrontEnd )
				)
				( attribute "PHYS_PAGE" "155"
					( Origin gFrontEnd )
				)
				( attribute "ROOM" "BMC_DEBUG_HEADER"
					( Origin gFrontEnd )
				)
				( attribute "ROT" "0"
					( Origin gFrontEnd )
				)
				( attribute "SEC" "1"
					( Origin gFrontEnd )
				)
				( attribute "SEC_TYPE" "0402"
					( Origin gFrontEnd )
				)
				( attribute "TOLERANCE" "1%"
					( Origin gFrontEnd )
				)
				( attribute "VALUE" "100.0K"
					( Origin gFrontEnd )
				)
				( attribute "VER" "2"
					( Origin gFrontEnd )
				)
				( attribute "WATTAGE" "1/16W"
					( Origin gFrontEnd )
				)
				( attribute "XY" "(-6050,2575)"
					( Origin gFrontEnd )
				)
				( attribute "CHIPS_PART_NAME" "RES"
					( Origin gPackager )
				)
				( attribute "CDS_PART_NAME" "RES_0402-100.0K,1%,1/16W,CHIP,A"
					( Origin gPackager )
				)
				( objectStatus "R1L9" )
				( pin "a"
					( attribute "PN" "1"
						( Origin gPackager )
					)
					( objectStatus "R1L9.1" )
				)
				( pin "b"
					( attribute "PN" "2"
						( Origin gPackager )
					)
					( objectStatus "R1L9.2" )
				)
			)
			( gate "@baseboard_fab2_lib.baseboard_fab2(sch_1):page176_i122"
				( attribute "BOM_COST" "SM_THERM"
					( Origin gFrontEnd )
				)
				( attribute "CDS_LIB" "mstr_ttl"
					( Origin gPackager )
				)
				( attribute "LOCATION" "U6W10"
					( Origin gFrontEnd )
				)
				( attribute "MATERIAL" "IC"
					( Origin gFrontEnd )
				)
				( attribute "PACK_TYPE" "SOTLF"
					( Origin gFrontEnd )
				)
				( attribute "PART_NUMBER" "D10321-001"
					( Origin gFrontEnd )
				)
				( attribute "PHYS_PAGE" "176"
					( Origin gFrontEnd )
				)
				( attribute "ROOM" "CPU_FANS"
					( Origin gFrontEnd )
				)
				( attribute "ROT" "0"
					( Origin gFrontEnd )
				)
				( attribute "VALUE" "NC7SZ08"
					( Origin gFrontEnd )
				)
				( attribute "VER" "1"
					( Origin gFrontEnd )
				)
				( attribute "XY" "(-1725,3275)"
					( Origin gFrontEnd )
				)
				( attribute "CHIPS_PART_NAME" "TTL1G08"
					( Origin gPackager )
				)
				( attribute "CDS_PART_NAME" "TTL1G08_SOTLF-NC7SZ08,IC,D1032B"
					( Origin gPackager )
				)
				( attribute "CDS_LOCATION" "U6W10"
					( Origin gPackager )
				)
				( attribute "CDS_SEC" "1"
					( Origin gPackager )
				)
				( attribute "SEC" "1"
					( Origin gPackager )
				)
				( objectStatus "U6W10" )
				( pin "a(0)"
					( attribute "PN" "1"
						( Origin gPackager )
					)
					( objectStatus "U6W10.1" )
				)
				( pin "b(0)"
					( attribute "PN" "2"
						( Origin gPackager )
					)
					( objectStatus "U6W10.2" )
				)
				( pin "y(0)"
					( attribute "PN" "4"
						( Origin gPackager )
					)
					( objectStatus "U6W10.4" )
				)
			)
			( gate "@baseboard_fab2_lib.baseboard_fab2(sch_1):page155_i171"
				( attribute "BOM_COST" "DEBUG"
					( Origin gFrontEnd )
				)
				( attribute "CDS_LIB" "mstr_conn"
					( Origin gPackager )
				)
				( attribute "CDS_LMAN_SYM_OUTLINE" "-250,250,250,-250"
					( Origin gPackager )
				)
				( attribute "CDS_LOCATION" "J9A2"
					( Origin gPackager )
				)
				( attribute "CDS_SEC" "1"
					( Origin gPackager )
				)
				( attribute "LOCATION" "J9A2"
					( Origin gFrontEnd )
				)
				( attribute "MATERIAL" "CONN"
					( Origin gFrontEnd )
				)
				( attribute "PACK_TYPE" "PIP"
					( Origin gFrontEnd )
				)
				( attribute "PART_NUMBER" "H54902-001"
					( Origin gFrontEnd )
				)
				( attribute "PHYS_PAGE" "155"
					( Origin gFrontEnd )
				)
				( attribute "ROOM" "BMC_DEBUG_HEADER"
					( Origin gFrontEnd )
				)
				( attribute "ROT" "0"
					( Origin gFrontEnd )
				)
				( attribute "SEC" "1"
					( Origin gPackager )
				)
				( attribute "VER" "1"
					( Origin gFrontEnd )
				)
				( attribute "XY" "(-4450,1500)"
					( Origin gFrontEnd )
				)
				( attribute "CHIPS_PART_NAME" "CONN14_H54902001"
					( Origin gPackager )
				)
				( attribute "CDS_PART_NAME" "CONN14_H54902001_PIP-CONN,H549A"
					( Origin gPackager )
				)
				( objectStatus "J9A2" )
				( pin "io1"
					( attribute "PN" "1"
						( Origin gPackager )
					)
					( objectStatus "J9A2.1" )
				)
				( pin "io2"
					( attribute "PN" "2"
						( Origin gPackager )
					)
					( objectStatus "J9A2.2" )
				)
				( pin "io3"
					( attribute "PN" "3"
						( Origin gPackager )
					)
					( objectStatus "J9A2.3" )
				)
				( pin "io4"
					( attribute "PN" "4"
						( Origin gPackager )
					)
					( objectStatus "J9A2.4" )
				)
				( pin "io5"
					( attribute "PN" "5"
						( Origin gPackager )
					)
					( objectStatus "J9A2.5" )
				)
				( pin "io6"
					( attribute "PN" "6"
						( Origin gPackager )
					)
					( objectStatus "J9A2.6" )
				)
				( pin "io7"
					( attribute "PN" "7"
						( Origin gPackager )
					)
					( objectStatus "J9A2.7" )
				)
				( pin "io8"
					( attribute "PN" "8"
						( Origin gPackager )
					)
					( objectStatus "J9A2.8" )
				)
				( pin "io9"
					( attribute "PN" "9"
						( Origin gPackager )
					)
					( objectStatus "J9A2.9" )
				)
				( pin "io10"
					( attribute "PN" "10"
						( Origin gPackager )
					)
					( objectStatus "J9A2.10" )
				)
				( pin "io11"
					( attribute "PN" "11"
						( Origin gPackager )
					)
					( objectStatus "J9A2.11" )
				)
				( pin "io12"
					( attribute "PN" "12"
						( Origin gPackager )
					)
					( objectStatus "J9A2.12" )
				)
				( pin "io13"
					( attribute "PN" "13"
						( Origin gPackager )
					)
					( objectStatus "J9A2.13" )
				)
				( pin "io14"
					( attribute "PN" "14"
						( Origin gPackager )
					)
					( objectStatus "J9A2.14" )
				)
			)
			( gate "@baseboard_fab2_lib.baseboard_fab2(sch_1):page155_i178"
				( attribute "BOM_COST" "DEBUG"
					( Origin gFrontEnd )
				)
				( attribute "CDS_LIB" "mstr_ttl"
					( Origin gPackager )
				)
				( attribute "CDS_LOCATION" "U9A1"
					( Origin gPackager )
				)
				( attribute "CDS_SEC" "1"
					( Origin gPackager )
				)
				( attribute "LOCATION" "U9A1"
					( Origin gFrontEnd )
				)
				( attribute "MATERIAL" "IC"
					( Origin gFrontEnd )
				)
				( attribute "PACK_TYPE" "SOP"
					( Origin gFrontEnd )
				)
				( attribute "PART_NUMBER" "C88419-001"
					( Origin gFrontEnd )
				)
				( attribute "PHYS_PAGE" "155"
					( Origin gFrontEnd )
				)
				( attribute "ROOM" "BMC_DEBUG_HEADER"
					( Origin gFrontEnd )
				)
				( attribute "ROT" "0"
					( Origin gFrontEnd )
				)
				( attribute "SEC" "1"
					( Origin gFrontEnd )
				)
				( attribute "SEC_TYPE" "SOP"
					( Origin gFrontEnd )
				)
				( attribute "VALUE" "74LVC1G07"
					( Origin gFrontEnd )
				)
				( attribute "VER" "1"
					( Origin gFrontEnd )
				)
				( attribute "XY" "(-2550,1400)"
					( Origin gFrontEnd )
				)
				( attribute "CHIPS_PART_NAME" "TTL1G07_A"
					( Origin gPackager )
				)
				( attribute "CDS_PART_NAME" "TTL1G07_A_SOP-74LVC1G07,IC,C88B"
					( Origin gPackager )
				)
				( objectStatus "U9A1" )
				( pin "a"
					( attribute "PN" "2"
						( Origin gPackager )
					)
					( objectStatus "U9A1.2" )
				)
				( pin "y"
					( attribute "PN" "4"
						( Origin gPackager )
					)
					( objectStatus "U9A1.4" )
				)
			)
			( gate "@baseboard_fab2_lib.baseboard_fab2(sch_1):page155_i184"
				( attribute "BOM_COST" "DEBUG"
					( Origin gFrontEnd )
				)
				( attribute "CDS_LIB" "dev_discrete"
					( Origin gPackager )
				)
				( attribute "CDS_LOCATION" "C1T56"
					( Origin gPackager )
				)
				( attribute "CDS_SEC" "1"
					( Origin gPackager )
				)
				( attribute "LOCATION" "C1T56"
					( Origin gFrontEnd )
				)
				( attribute "MATERIAL" "X7R"
					( Origin gFrontEnd )
				)
				( attribute "PACK_TYPE" "0402V"
					( Origin gFrontEnd )
				)
				( attribute "PART_NUMBER" "A36096-030"
					( Origin gFrontEnd )
				)
				( attribute "PHYS_PAGE" "155"
					( Origin gFrontEnd )
				)
				( attribute "ROOM" "BMC_DEBUG_HEADER"
					( Origin gFrontEnd )
				)
				( attribute "ROT" "0"
					( Origin gFrontEnd )
				)
				( attribute "SEC" "1"
					( Origin gFrontEnd )
				)
				( attribute "SEC_TYPE" "0402V"
					( Origin gFrontEnd )
				)
				( attribute "TOLERANCE" "10%"
					( Origin gFrontEnd )
				)
				( attribute "VALUE" "0.1UF"
					( Origin gFrontEnd )
				)
				( attribute "VER" "1"
					( Origin gFrontEnd )
				)
				( attribute "VOLTAGE" "16V"
					( Units "uVoltage" "V" 1.000000)
					( Origin gFrontEnd )
				)
				( attribute "XY" "(-1550,3025)"
					( Origin gFrontEnd )
				)
				( attribute "CHIPS_PART_NAME" "CAP_A"
					( Origin gPackager )
				)
				( attribute "CDS_PART_NAME" "CAP_A_0402V-0.1UF,16V,10%,X7R,A"
					( Origin gPackager )
				)
				( objectStatus "C1T56" )
				( pin "a"
					( attribute "PN" "1"
						( Origin gPackager )
					)
					( objectStatus "C1T56.1" )
				)
				( pin "b"
					( attribute "PN" "2"
						( Origin gPackager )
					)
					( objectStatus "C1T56.2" )
				)
			)
			( gate "@baseboard_fab2_lib.baseboard_fab2(sch_1):page155_i186"
				( attribute "BOM_COST" "DEBUG"
					( Origin gFrontEnd )
				)
				( attribute "CDS_LIB" "mstr_discrete"
					( Origin gPackager )
				)
				( attribute "CDS_LOCATION" "R1L2"
					( Origin gPackager )
				)
				( attribute "CDS_SEC" "1"
					( Origin gPackager )
				)
				( attribute "LOCATION" "R1L2"
					( Origin gFrontEnd )
				)
				( attribute "MATERIAL" "CHIP"
					( Origin gFrontEnd )
				)
				( attribute "PACK_TYPE" "0402"
					( Origin gFrontEnd )
				)
				( attribute "PART_NUMBER" "G21796-066"
					( Origin gFrontEnd )
				)
				( attribute "PHYS_PAGE" "155"
					( Origin gFrontEnd )
				)
				( attribute "ROOM" "BMC_DEBUG_HEADER"
					( Origin gFrontEnd )
				)
				( attribute "ROT" "0"
					( Origin gFrontEnd )
				)
				( attribute "SEC" "1"
					( Origin gPackager )
				)
				( attribute "TOLERANCE" "1%"
					( Origin gFrontEnd )
				)
				( attribute "VALUE" "10.0"
					( Origin gFrontEnd )
				)
				( attribute "VER" "1"
					( Origin gFrontEnd )
				)
				( attribute "WATTAGE" "1/16W"
					( Origin gFrontEnd )
				)
				( attribute "XY" "(-7050,2000)"
					( Origin gFrontEnd )
				)
				( attribute "CHIPS_PART_NAME" "RES"
					( Origin gPackager )
				)
				( attribute "CDS_PART_NAME" "RES_0402-10.0,1%,1/16W,CHIP,G2A"
					( Origin gPackager )
				)
				( objectStatus "R1L2" )
				( pin "a"
					( attribute "PN" "1"
						( Origin gPackager )
					)
					( objectStatus "R1L2.1" )
				)
				( pin "b"
					( attribute "PN" "2"
						( Origin gPackager )
					)
					( objectStatus "R1L2.2" )
				)
			)
			( gate "@baseboard_fab2_lib.baseboard_fab2(sch_1):page155_i187"
				( attribute "BOM_COST" "BMC_DEBUG_HEADER"
					( Origin gFrontEnd )
				)
				( attribute "CDS_LIB" "mstr_discrete"
					( Origin gPackager )
				)
				( attribute "CDS_LOCATION" "Q1L2"
					( Origin gPackager )
				)
				( attribute "LOCATION" "Q1L2"
					( Origin gFrontEnd )
				)
				( attribute "MATERIAL" "FET"
					( Origin gFrontEnd )
				)
				( attribute "PACK_TYPE" "SMLF"
					( Origin gFrontEnd )
				)
				( attribute "PART_NUMBER" "E40049-001"
					( Origin gFrontEnd )
				)
				( attribute "PHYS_PAGE" "155"
					( Origin gFrontEnd )
				)
				( attribute "ROOM" "BMC"
					( Origin gFrontEnd )
				)
				( attribute "ROT" "0"
					( Origin gFrontEnd )
				)
				( attribute "SEC" "2"
					( Origin gFrontEnd )
				)
				( attribute "SEC_TYPE" "SMLF"
					( Origin gFrontEnd )
				)
				( attribute "VALUE" "NTJD4001N"
					( Origin gFrontEnd )
				)
				( attribute "VER" "5"
					( Origin gFrontEnd )
				)
				( attribute "XY" "(-6050,2100)"
					( Origin gFrontEnd )
				)
				( attribute "CHIPS_PART_NAME" "FET_N_DUAL"
					( Origin gPackager )
				)
				( attribute "CDS_PART_NAME" "FET_N_DUAL_SMLF-NTJD4001N,FET,A"
					( Origin gPackager )
				)
				( attribute "CDS_SEC" "2"
					( Origin gPackager )
				)
				( objectStatus "Q1L2" )
				( pin "drain(0)"
					( attribute "PN" "3"
						( Origin gPackager )
					)
					( objectStatus "Q1L2.3" )
				)
				( pin "gate(0)"
					( attribute "PN" "5"
						( Origin gPackager )
					)
					( objectStatus "Q1L2.5" )
				)
				( pin "source(0)"
					( attribute "PN" "4"
						( Origin gPackager )
					)
					( objectStatus "Q1L2.4" )
				)
			)
			( gate "@baseboard_fab2_lib.baseboard_fab2(sch_1):page155_i188"
				( attribute "BOM_COST" "BMC_DEBUG_HEADER"
					( Origin gFrontEnd )
				)
				( attribute "CDS_LIB" "mstr_discrete"
					( Origin gPackager )
				)
				( attribute "CDS_LOCATION" "Q1L2"
					( Origin gPackager )
				)
				( attribute "CDS_SEC" "1"
					( Origin gPackager )
				)
				( attribute "LOCATION" "Q1L2"
					( Origin gFrontEnd )
				)
				( attribute "MATERIAL" "FET"
					( Origin gFrontEnd )
				)
				( attribute "PACK_TYPE" "SMLF"
					( Origin gFrontEnd )
				)
				( attribute "PART_NUMBER" "E40049-001"
					( Origin gFrontEnd )
				)
				( attribute "PHYS_PAGE" "155"
					( Origin gFrontEnd )
				)
				( attribute "ROOM" "BMC"
					( Origin gFrontEnd )
				)
				( attribute "ROT" "1"
					( Origin gFrontEnd )
				)
				( attribute "SEC" "1"
					( Origin gFrontEnd )
				)
				( attribute "SEC_TYPE" "SMLF"
					( Origin gFrontEnd )
				)
				( attribute "VALUE" "NTJD4001N"
					( Origin gFrontEnd )
				)
				( attribute "VER" "5"
					( Origin gFrontEnd )
				)
				( attribute "XY" "(-4950,2625)"
					( Origin gFrontEnd )
				)
				( attribute "CHIPS_PART_NAME" "FET_N_DUAL"
					( Origin gPackager )
				)
				( attribute "CDS_PART_NAME" "FET_N_DUAL_SMLF-NTJD4001N,FET,A"
					( Origin gPackager )
				)
				( objectStatus "Q1L2" )
				( pin "drain(0)"
					( attribute "PN" "6"
						( Origin gPackager )
					)
					( objectStatus "Q1L2.6" )
				)
				( pin "gate(0)"
					( attribute "PN" "2"
						( Origin gPackager )
					)
					( objectStatus "Q1L2.2" )
				)
				( pin "source(0)"
					( attribute "PN" "1"
						( Origin gPackager )
					)
					( objectStatus "Q1L2.1" )
				)
			)
			( gate "@baseboard_fab2_lib.baseboard_fab2(sch_1):page155_i191"
				( attribute "BOM_COST" "BMC_DEBUG_HEADER"
					( Origin gFrontEnd )
				)
				( attribute "CDS_LIB" "mstr_discrete"
					( Origin gPackager )
				)
				( attribute "CDS_LOCATION" "R9A6"
					( Origin gPackager )
				)
				( attribute "CDS_SEC" "1"
					( Origin gPackager )
				)
				( attribute "LOCATION" "R9A6"
					( Origin gFrontEnd )
				)
				( attribute "MATERIAL" "EMPTY"
					( Origin gFrontEnd )
				)
				( attribute "PACK_TYPE" "0402"
					( Origin gFrontEnd )
				)
				( attribute "PART_NUMBER" "G21796-040"
					( Origin gFrontEnd )
				)
				( attribute "PHYS_PAGE" "155"
					( Origin gFrontEnd )
				)
				( attribute "ROOM" "BMC"
					( Origin gFrontEnd )
				)
				( attribute "ROT" "0"
					( Origin gFrontEnd )
				)
				( attribute "SEC" "1"
					( Origin gPackager )
				)
				( attribute "TOLERANCE" "1%"
					( Origin gFrontEnd )
				)
				( attribute "VALUE" "20.0K"
					( Origin gFrontEnd )
				)
				( attribute "VER" "2"
					( Origin gFrontEnd )
				)
				( attribute "WATTAGE" "1/16W"
					( Origin gFrontEnd )
				)
				( attribute "XY" "(-2950,1725)"
					( Origin gFrontEnd )
				)
				( attribute "CHIPS_PART_NAME" "RES"
					( Origin gPackager )
				)
				( attribute "CDS_PART_NAME" "RES_0402-20.0K,1%,1/16W,EMPTY,A"
					( Origin gPackager )
				)
				( objectStatus "R9A6" )
				( pin "a"
					( attribute "PN" "1"
						( Origin gPackager )
					)
					( objectStatus "R9A6.1" )
				)
				( pin "b"
					( attribute "PN" "2"
						( Origin gPackager )
					)
					( objectStatus "R9A6.2" )
				)
			)
			( gate "@baseboard_fab2_lib.baseboard_fab2(sch_1):page156_i201"
				( attribute "BOM_COST" "SM_CONTROLLER"
					( Origin gFrontEnd )
				)
				( attribute "CDS_LIB" "mstr_ttl"
					( Origin gPackager )
				)
				( attribute "CDS_LOCATION" "U8F3"
					( Origin gPackager )
				)
				( attribute "CDS_SEC" "1"
					( Origin gPackager )
				)
				( attribute "LOCATION" "U8F3"
					( Origin gFrontEnd )
				)
				( attribute "MATERIAL" "IC"
					( Origin gFrontEnd )
				)
				( attribute "PACK_TYPE" "SOT23LF"
					( Origin gFrontEnd )
				)
				( attribute "PART_NUMBER" "D22707-001"
					( Origin gFrontEnd )
				)
				( attribute "PHYS_PAGE" "156"
					( Origin gFrontEnd )
				)
				( attribute "ROOM" "BMC_MISC"
					( Origin gFrontEnd )
				)
				( attribute "ROT" "0"
					( Origin gFrontEnd )
				)
				( attribute "SEC" "1"
					( Origin gFrontEnd )
				)
				( attribute "SEC_TYPE" "SOT23LF"
					( Origin gFrontEnd )
				)
				( attribute "VALUE" "74LVC2G07"
					( Origin gFrontEnd )
				)
				( attribute "VER" "1"
					( Origin gFrontEnd )
				)
				( attribute "XY" "(-3000,4150)"
					( Origin gFrontEnd )
				)
				( attribute "CHIPS_PART_NAME" "TTL2G07"
					( Origin gPackager )
				)
				( attribute "CDS_PART_NAME" "TTL2G07_SOT23LF-74LVC2G07,IC,DB"
					( Origin gPackager )
				)
				( objectStatus "U8F3" )
				( pin "\1a\"
					( attribute "PN" "1"
						( Origin gPackager )
					)
					( objectStatus "U8F3.1" )
				)
				( pin "\1y\"
					( attribute "PN" "6"
						( Origin gPackager )
					)
					( objectStatus "U8F3.6" )
				)
				( pin "\2a\"
					( attribute "PN" "3"
						( Origin gPackager )
					)
					( objectStatus "U8F3.3" )
				)
				( pin "\2y\"
					( attribute "PN" "4"
						( Origin gPackager )
					)
					( objectStatus "U8F3.4" )
				)
			)
			( gate "@baseboard_fab2_lib.baseboard_fab2(sch_1):page156_i206"
				( attribute "BOM_COST" "SM_CONTROLLER"
					( Origin gFrontEnd )
				)
				( attribute "CDS_LIB" "mstr_discrete"
					( Origin gPackager )
				)
				( attribute "CDS_LOCATION" "R2T34"
					( Origin gPackager )
				)
				( attribute "CDS_SEC" "1"
					( Origin gPackager )
				)
				( attribute "LOCATION" "R2T34"
					( Origin gFrontEnd )
				)
				( attribute "MATERIAL" "CHIP"
					( Origin gFrontEnd )
				)
				( attribute "PACK_TYPE" "0402"
					( Origin gFrontEnd )
				)
				( attribute "PART_NUMBER" "G21796-072"
					( Origin gFrontEnd )
				)
				( attribute "PHYS_PAGE" "156"
					( Origin gFrontEnd )
				)
				( attribute "ROOM" "BMC_MISC"
					( Origin gFrontEnd )
				)
				( attribute "ROT" "0"
					( Origin gFrontEnd )
				)
				( attribute "SEC" "1"
					( Origin gFrontEnd )
				)
				( attribute "SEC_TYPE" "0402"
					( Origin gFrontEnd )
				)
				( attribute "TOLERANCE" "1%"
					( Origin gFrontEnd )
				)
				( attribute "VALUE" "4.75K"
					( Origin gFrontEnd )
				)
				( attribute "VER" "2"
					( Origin gFrontEnd )
				)
				( attribute "WATTAGE" "1/16W"
					( Origin gFrontEnd )
				)
				( attribute "XY" "(-4150,4450)"
					( Origin gFrontEnd )
				)
				( attribute "CHIPS_PART_NAME" "RES"
					( Origin gPackager )
				)
				( attribute "CDS_PART_NAME" "RES_0402-4.75K,1%,1/16W,CHIP,GA"
					( Origin gPackager )
				)
				( objectStatus "R2T34" )
				( pin "a"
					( attribute "PN" "1"
						( Origin gPackager )
					)
					( objectStatus "R2T34.1" )
				)
				( pin "b"
					( attribute "PN" "2"
						( Origin gPackager )
					)
					( objectStatus "R2T34.2" )
				)
			)
			( gate "@baseboard_fab2_lib.baseboard_fab2(sch_1):page156_i207"
				( attribute "BOM_COST" "SM_CONTROLLER"
					( Origin gFrontEnd )
				)
				( attribute "CDS_LIB" "mstr_discrete"
					( Origin gPackager )
				)
				( attribute "CDS_LOCATION" "R2T35"
					( Origin gPackager )
				)
				( attribute "CDS_SEC" "1"
					( Origin gPackager )
				)
				( attribute "LOCATION" "R2T35"
					( Origin gFrontEnd )
				)
				( attribute "MATERIAL" "CHIP"
					( Origin gFrontEnd )
				)
				( attribute "PACK_TYPE" "0402"
					( Origin gFrontEnd )
				)
				( attribute "PART_NUMBER" "G21796-072"
					( Origin gFrontEnd )
				)
				( attribute "PHYS_PAGE" "156"
					( Origin gFrontEnd )
				)
				( attribute "ROOM" "BMC_MISC"
					( Origin gFrontEnd )
				)
				( attribute "ROT" "0"
					( Origin gFrontEnd )
				)
				( attribute "SEC" "1"
					( Origin gFrontEnd )
				)
				( attribute "SEC_TYPE" "0402"
					( Origin gFrontEnd )
				)
				( attribute "TOLERANCE" "1%"
					( Origin gFrontEnd )
				)
				( attribute "VALUE" "4.75K"
					( Origin gFrontEnd )
				)
				( attribute "VER" "2"
					( Origin gFrontEnd )
				)
				( attribute "WATTAGE" "1/16W"
					( Origin gFrontEnd )
				)
				( attribute "XY" "(-3825,4450)"
					( Origin gFrontEnd )
				)
				( attribute "CHIPS_PART_NAME" "RES"
					( Origin gPackager )
				)
				( attribute "CDS_PART_NAME" "RES_0402-4.75K,1%,1/16W,CHIP,GA"
					( Origin gPackager )
				)
				( objectStatus "R2T35" )
				( pin "a"
					( attribute "PN" "1"
						( Origin gPackager )
					)
					( objectStatus "R2T35.1" )
				)
				( pin "b"
					( attribute "PN" "2"
						( Origin gPackager )
					)
					( objectStatus "R2T35.2" )
				)
			)
			( gate "@baseboard_fab2_lib.baseboard_fab2(sch_1):page156_i210"
				( attribute "BOM_COST" "SM_CONTROLLER"
					( Origin gFrontEnd )
				)
				( attribute "CDS_LIB" "mstr_discrete"
					( Origin gPackager )
				)
				( attribute "CDS_LOCATION" "R2T22"
					( Origin gPackager )
				)
				( attribute "CDS_SEC" "1"
					( Origin gPackager )
				)
				( attribute "LOCATION" "R2T22"
					( Origin gFrontEnd )
				)
				( attribute "MATERIAL" "CHIP"
					( Origin gFrontEnd )
				)
				( attribute "PACK_TYPE" "0402"
					( Origin gFrontEnd )
				)
				( attribute "PART_NUMBER" "G21796-016"
					( Origin gFrontEnd )
				)
				( attribute "PHYS_PAGE" "156"
					( Origin gFrontEnd )
				)
				( attribute "ROOM" "BMC_MISC"
					( Origin gFrontEnd )
				)
				( attribute "ROT" "0"
					( Origin gFrontEnd )
				)
				( attribute "SEC" "1"
					( Origin gFrontEnd )
				)
				( attribute "SEC_TYPE" "0402"
					( Origin gFrontEnd )
				)
				( attribute "TOLERANCE" "1%"
					( Origin gFrontEnd )
				)
				( attribute "VALUE" "10.0K"
					( Origin gFrontEnd )
				)
				( attribute "VER" "2"
					( Origin gFrontEnd )
				)
				( attribute "WATTAGE" "1/16W"
					( Origin gFrontEnd )
				)
				( attribute "XY" "(-2275,4425)"
					( Origin gFrontEnd )
				)
				( attribute "CHIPS_PART_NAME" "RES"
					( Origin gPackager )
				)
				( attribute "CDS_PART_NAME" "RES_0402-10.0K,1%,1/16W,CHIP,GA"
					( Origin gPackager )
				)
				( objectStatus "R2T22" )
				( pin "a"
					( attribute "PN" "1"
						( Origin gPackager )
					)
					( objectStatus "R2T22.1" )
				)
				( pin "b"
					( attribute "PN" "2"
						( Origin gPackager )
					)
					( objectStatus "R2T22.2" )
				)
			)
			( gate "@baseboard_fab2_lib.baseboard_fab2(sch_1):page156_i211"
				( attribute "BOM_COST" "SM_CONTROLLER"
					( Origin gFrontEnd )
				)
				( attribute "CDS_LIB" "mstr_discrete"
					( Origin gPackager )
				)
				( attribute "CDS_LOCATION" "R8F26"
					( Origin gPackager )
				)
				( attribute "CDS_SEC" "1"
					( Origin gPackager )
				)
				( attribute "LOCATION" "R8F26"
					( Origin gFrontEnd )
				)
				( attribute "MATERIAL" "CHIP"
					( Origin gFrontEnd )
				)
				( attribute "PACK_TYPE" "0402"
					( Origin gFrontEnd )
				)
				( attribute "PART_NUMBER" "G21796-016"
					( Origin gFrontEnd )
				)
				( attribute "PHYS_PAGE" "156"
					( Origin gFrontEnd )
				)
				( attribute "ROOM" "BMC_MISC"
					( Origin gFrontEnd )
				)
				( attribute "ROT" "0"
					( Origin gFrontEnd )
				)
				( attribute "SEC" "1"
					( Origin gFrontEnd )
				)
				( attribute "SEC_TYPE" "0402"
					( Origin gFrontEnd )
				)
				( attribute "TOLERANCE" "1%"
					( Origin gFrontEnd )
				)
				( attribute "VALUE" "10.0K"
					( Origin gFrontEnd )
				)
				( attribute "VER" "2"
					( Origin gFrontEnd )
				)
				( attribute "WATTAGE" "1/16W"
					( Origin gFrontEnd )
				)
				( attribute "XY" "(-2550,4450)"
					( Origin gFrontEnd )
				)
				( attribute "CHIPS_PART_NAME" "RES"
					( Origin gPackager )
				)
				( attribute "CDS_PART_NAME" "RES_0402-10.0K,1%,1/16W,CHIP,GA"
					( Origin gPackager )
				)
				( objectStatus "R8F26" )
				( pin "a"
					( attribute "PN" "1"
						( Origin gPackager )
					)
					( objectStatus "R8F26.1" )
				)
				( pin "b"
					( attribute "PN" "2"
						( Origin gPackager )
					)
					( objectStatus "R8F26.2" )
				)
			)
			( gate "@baseboard_fab2_lib.baseboard_fab2(sch_1):page156_i214"
				( attribute "BOM_COST" "SM_CONTROLLER"
					( Origin gFrontEnd )
				)
				( attribute "CDS_LIB" "mstr_discrete"
					( Origin gPackager )
				)
				( attribute "CDS_LOCATION" "R8E24"
					( Origin gPackager )
				)
				( attribute "CDS_SEC" "1"
					( Origin gPackager )
				)
				( attribute "LOCATION" "R8E24"
					( Origin gFrontEnd )
				)
				( attribute "MATERIAL" "CHIP"
					( Origin gFrontEnd )
				)
				( attribute "PACK_TYPE" "0402"
					( Origin gFrontEnd )
				)
				( attribute "PART_NUMBER" "G21796-074"
					( Origin gFrontEnd )
				)
				( attribute "PHYS_PAGE" "156"
					( Origin gFrontEnd )
				)
				( attribute "ROOM" "BMC_MISC"
					( Origin gFrontEnd )
				)
				( attribute "ROT" "0"
					( Origin gFrontEnd )
				)
				( attribute "SEC" "1"
					( Origin gFrontEnd )
				)
				( attribute "SEC_TYPE" "0402"
					( Origin gFrontEnd )
				)
				( attribute "TOLERANCE" "1%"
					( Origin gFrontEnd )
				)
				( attribute "VALUE" "33.2"
					( Origin gFrontEnd )
				)
				( attribute "VER" "1"
					( Origin gFrontEnd )
				)
				( attribute "WATTAGE" "1/16W"
					( Origin gFrontEnd )
				)
				( attribute "XY" "(-6575,2775)"
					( Origin gFrontEnd )
				)
				( attribute "CHIPS_PART_NAME" "RES"
					( Origin gPackager )
				)
				( attribute "CDS_PART_NAME" "RES_0402-33.2,1%,1/16W,CHIP,G2A"
					( Origin gPackager )
				)
				( objectStatus "R8E24" )
				( pin "a"
					( attribute "PN" "1"
						( Origin gPackager )
					)
					( objectStatus "R8E24.1" )
				)
				( pin "b"
					( attribute "PN" "2"
						( Origin gPackager )
					)
					( objectStatus "R8E24.2" )
				)
			)
			( gate "@baseboard_fab2_lib.baseboard_fab2(sch_1):page156_i215"
				( attribute "BOM_COST" "SM_CONTROLLER"
					( Origin gFrontEnd )
				)
				( attribute "CDS_LIB" "mstr_discrete"
					( Origin gPackager )
				)
				( attribute "CDS_LOCATION" "R8E22"
					( Origin gPackager )
				)
				( attribute "CDS_SEC" "1"
					( Origin gPackager )
				)
				( attribute "LOCATION" "R8E22"
					( Origin gFrontEnd )
				)
				( attribute "MATERIAL" "CHIP"
					( Origin gFrontEnd )
				)
				( attribute "PACK_TYPE" "0402"
					( Origin gFrontEnd )
				)
				( attribute "PART_NUMBER" "G21796-072"
					( Origin gFrontEnd )
				)
				( attribute "PHYS_PAGE" "156"
					( Origin gFrontEnd )
				)
				( attribute "ROOM" "BMC_MISC"
					( Origin gFrontEnd )
				)
				( attribute "ROT" "0"
					( Origin gFrontEnd )
				)
				( attribute "SEC" "1"
					( Origin gFrontEnd )
				)
				( attribute "SEC_TYPE" "0402"
					( Origin gFrontEnd )
				)
				( attribute "TOLERANCE" "1%"
					( Origin gFrontEnd )
				)
				( attribute "VALUE" "4.75K"
					( Origin gFrontEnd )
				)
				( attribute "VER" "2"
					( Origin gFrontEnd )
				)
				( attribute "WATTAGE" "1/16W"
					( Origin gFrontEnd )
				)
				( attribute "XY" "(-6825,3025)"
					( Origin gFrontEnd )
				)
				( attribute "CHIPS_PART_NAME" "RES"
					( Origin gPackager )
				)
				( attribute "CDS_PART_NAME" "RES_0402-4.75K,1%,1/16W,CHIP,GA"
					( Origin gPackager )
				)
				( objectStatus "R8E22" )
				( pin "a"
					( attribute "PN" "1"
						( Origin gPackager )
					)
					( objectStatus "R8E22.1" )
				)
				( pin "b"
					( attribute "PN" "2"
						( Origin gPackager )
					)
					( objectStatus "R8E22.2" )
				)
			)
			( gate "@baseboard_fab2_lib.baseboard_fab2(sch_1):page156_i265"
				( attribute "BOM_COST" "SM_CONTROLLER"
					( Origin gFrontEnd )
				)
				( attribute "CDS_LIB" "mstr_discrete"
					( Origin gPackager )
				)
				( attribute "CDS_LOCATION" "R2U2"
					( Origin gPackager )
				)
				( attribute "CDS_SEC" "1"
					( Origin gPackager )
				)
				( attribute "LOCATION" "R2U2"
					( Origin gFrontEnd )
				)
				( attribute "MATERIAL" "CHIP"
					( Origin gFrontEnd )
				)
				( attribute "PACK_TYPE" "0402"
					( Origin gFrontEnd )
				)
				( attribute "PART_NUMBER" "G21796-072"
					( Origin gFrontEnd )
				)
				( attribute "PHYS_PAGE" "156"
					( Origin gFrontEnd )
				)
				( attribute "ROOM" "BMC_MISC"
					( Origin gFrontEnd )
				)
				( attribute "ROT" "0"
					( Origin gFrontEnd )
				)
				( attribute "SEC" "1"
					( Origin gFrontEnd )
				)
				( attribute "SEC_TYPE" "0402"
					( Origin gFrontEnd )
				)
				( attribute "TOLERANCE" "1%"
					( Origin gFrontEnd )
				)
				( attribute "VALUE" "4.75K"
					( Origin gFrontEnd )
				)
				( attribute "VER" "2"
					( Origin gFrontEnd )
				)
				( attribute "WATTAGE" "1/16W"
					( Origin gFrontEnd )
				)
				( attribute "XY" "(-3750,3550)"
					( Origin gFrontEnd )
				)
				( attribute "CHIPS_PART_NAME" "RES"
					( Origin gPackager )
				)
				( attribute "CDS_PART_NAME" "RES_0402-4.75K,1%,1/16W,CHIP,GA"
					( Origin gPackager )
				)
				( objectStatus "R2U2" )
				( pin "a"
					( attribute "PN" "1"
						( Origin gPackager )
					)
					( objectStatus "R2U2.1" )
				)
				( pin "b"
					( attribute "PN" "2"
						( Origin gPackager )
					)
					( objectStatus "R2U2.2" )
				)
			)
			( gate "@baseboard_fab2_lib.baseboard_fab2(sch_1):page156_i267"
				( attribute "BOM_COST" "SM_CONTROLLER"
					( Origin gFrontEnd )
				)
				( attribute "CDS_LIB" "mstr_discrete"
					( Origin gPackager )
				)
				( attribute "CDS_LOCATION" "R8G2"
					( Origin gPackager )
				)
				( attribute "CDS_SEC" "1"
					( Origin gPackager )
				)
				( attribute "LOCATION" "R8G2"
					( Origin gFrontEnd )
				)
				( attribute "MATERIAL" "CHIP"
					( Origin gFrontEnd )
				)
				( attribute "PACK_TYPE" "0402"
					( Origin gFrontEnd )
				)
				( attribute "PART_NUMBER" "G21796-072"
					( Origin gFrontEnd )
				)
				( attribute "PHYS_PAGE" "156"
					( Origin gFrontEnd )
				)
				( attribute "ROOM" "BMC_MISC"
					( Origin gFrontEnd )
				)
				( attribute "ROT" "0"
					( Origin gFrontEnd )
				)
				( attribute "SEC" "1"
					( Origin gFrontEnd )
				)
				( attribute "SEC_TYPE" "0402"
					( Origin gFrontEnd )
				)
				( attribute "TOLERANCE" "1%"
					( Origin gFrontEnd )
				)
				( attribute "VALUE" "4.75K"
					( Origin gFrontEnd )
				)
				( attribute "VER" "2"
					( Origin gFrontEnd )
				)
				( attribute "WATTAGE" "1/16W"
					( Origin gFrontEnd )
				)
				( attribute "XY" "(-4075,3550)"
					( Origin gFrontEnd )
				)
				( attribute "CHIPS_PART_NAME" "RES"
					( Origin gPackager )
				)
				( attribute "CDS_PART_NAME" "RES_0402-4.75K,1%,1/16W,CHIP,GA"
					( Origin gPackager )
				)
				( objectStatus "R8G2" )
				( pin "a"
					( attribute "PN" "1"
						( Origin gPackager )
					)
					( objectStatus "R8G2.1" )
				)
				( pin "b"
					( attribute "PN" "2"
						( Origin gPackager )
					)
					( objectStatus "R8G2.2" )
				)
			)
			( gate "@baseboard_fab2_lib.baseboard_fab2(sch_1):page156_i269"
				( attribute "BOM_COST" "SM_CONTROLLER"
					( Origin gFrontEnd )
				)
				( attribute "CDS_LIB" "mstr_ttl"
					( Origin gPackager )
				)
				( attribute "CDS_LOCATION" "U8G1"
					( Origin gPackager )
				)
				( attribute "CDS_SEC" "1"
					( Origin gPackager )
				)
				( attribute "LOCATION" "U8G1"
					( Origin gFrontEnd )
				)
				( attribute "MATERIAL" "IC"
					( Origin gFrontEnd )
				)
				( attribute "PACK_TYPE" "SOT23LF"
					( Origin gFrontEnd )
				)
				( attribute "PART_NUMBER" "D22707-001"
					( Origin gFrontEnd )
				)
				( attribute "PHYS_PAGE" "156"
					( Origin gFrontEnd )
				)
				( attribute "ROOM" "BMC_MISC"
					( Origin gFrontEnd )
				)
				( attribute "ROT" "0"
					( Origin gFrontEnd )
				)
				( attribute "SEC" "1"
					( Origin gFrontEnd )
				)
				( attribute "SEC_TYPE" "SOT23LF"
					( Origin gFrontEnd )
				)
				( attribute "VALUE" "74LVC2G07"
					( Origin gFrontEnd )
				)
				( attribute "VER" "1"
					( Origin gFrontEnd )
				)
				( attribute "XY" "(-2925,3250)"
					( Origin gFrontEnd )
				)
				( attribute "CHIPS_PART_NAME" "TTL2G07"
					( Origin gPackager )
				)
				( attribute "CDS_PART_NAME" "TTL2G07_SOT23LF-74LVC2G07,IC,DB"
					( Origin gPackager )
				)
				( objectStatus "U8G1" )
				( pin "\1a\"
					( attribute "PN" "1"
						( Origin gPackager )
					)
					( objectStatus "U8G1.1" )
				)
				( pin "\1y\"
					( attribute "PN" "6"
						( Origin gPackager )
					)
					( objectStatus "U8G1.6" )
				)
				( pin "\2a\"
					( attribute "PN" "3"
						( Origin gPackager )
					)
					( objectStatus "U8G1.3" )
				)
				( pin "\2y\"
					( attribute "PN" "4"
						( Origin gPackager )
					)
					( objectStatus "U8G1.4" )
				)
			)
			( gate "@baseboard_fab2_lib.baseboard_fab2(sch_1):page156_i273"
				( attribute "BOM_COST" "SM_CONTROLLER"
					( Origin gFrontEnd )
				)
				( attribute "CDS_LIB" "dev_discrete"
					( Origin gPackager )
				)
				( attribute "CDS_LOCATION" "C2T35"
					( Origin gPackager )
				)
				( attribute "CDS_SEC" "1"
					( Origin gPackager )
				)
				( attribute "LOCATION" "C2T35"
					( Origin gFrontEnd )
				)
				( attribute "MATERIAL" "X7R"
					( Origin gFrontEnd )
				)
				( attribute "PACK_TYPE" "0402V"
					( Origin gFrontEnd )
				)
				( attribute "PART_NUMBER" "A36096-030"
					( Origin gFrontEnd )
				)
				( attribute "PHYS_PAGE" "156"
					( Origin gFrontEnd )
				)
				( attribute "ROOM" "BMC_MISC"
					( Origin gFrontEnd )
				)
				( attribute "ROT" "0"
					( Origin gFrontEnd )
				)
				( attribute "SEC" "1"
					( Origin gFrontEnd )
				)
				( attribute "SEC_TYPE" "0402V"
					( Origin gFrontEnd )
				)
				( attribute "TOLERANCE" "10%"
					( Origin gFrontEnd )
				)
				( attribute "VALUE" "0.1UF"
					( Origin gFrontEnd )
				)
				( attribute "VER" "1"
					( Origin gFrontEnd )
				)
				( attribute "VOLTAGE" "16V"
					( Units "uVoltage" "V" 1.000000)
					( Origin gFrontEnd )
				)
				( attribute "XY" "(-450,3550)"
					( Origin gFrontEnd )
				)
				( attribute "CHIPS_PART_NAME" "CAP_A"
					( Origin gPackager )
				)
				( attribute "CDS_PART_NAME" "CAP_A_0402V-0.1UF,16V,10%,X7R,A"
					( Origin gPackager )
				)
				( objectStatus "C2T35" )
				( pin "a"
					( attribute "PN" "1"
						( Origin gPackager )
					)
					( objectStatus "C2T35.1" )
				)
				( pin "b"
					( attribute "PN" "2"
						( Origin gPackager )
					)
					( objectStatus "C2T35.2" )
				)
			)
			( gate "@baseboard_fab2_lib.baseboard_fab2(sch_1):page156_i275"
				( attribute "BOM_COST" "SM_CONTROLLER"
					( Origin gFrontEnd )
				)
				( attribute "CDS_LIB" "dev_discrete"
					( Origin gPackager )
				)
				( attribute "CDS_LOCATION" "C8F16"
					( Origin gPackager )
				)
				( attribute "CDS_SEC" "1"
					( Origin gPackager )
				)
				( attribute "LOCATION" "C8F16"
					( Origin gFrontEnd )
				)
				( attribute "MATERIAL" "X7R"
					( Origin gFrontEnd )
				)
				( attribute "PACK_TYPE" "0402V"
					( Origin gFrontEnd )
				)
				( attribute "PART_NUMBER" "A36096-030"
					( Origin gFrontEnd )
				)
				( attribute "PHYS_PAGE" "156"
					( Origin gFrontEnd )
				)
				( attribute "ROOM" "BMC_MISC"
					( Origin gFrontEnd )
				)
				( attribute "ROT" "0"
					( Origin gFrontEnd )
				)
				( attribute "SEC" "1"
					( Origin gFrontEnd )
				)
				( attribute "SEC_TYPE" "0402V"
					( Origin gFrontEnd )
				)
				( attribute "TOLERANCE" "10%"
					( Origin gFrontEnd )
				)
				( attribute "VALUE" "0.1UF"
					( Origin gFrontEnd )
				)
				( attribute "VER" "1"
					( Origin gFrontEnd )
				)
				( attribute "VOLTAGE" "16V"
					( Units "uVoltage" "V" 1.000000)
					( Origin gFrontEnd )
				)
				( attribute "XY" "(-450,4450)"
					( Origin gFrontEnd )
				)
				( attribute "CHIPS_PART_NAME" "CAP_A"
					( Origin gPackager )
				)
				( attribute "CDS_PART_NAME" "CAP_A_0402V-0.1UF,16V,10%,X7R,A"
					( Origin gPackager )
				)
				( objectStatus "C8F16" )
				( pin "a"
					( attribute "PN" "1"
						( Origin gPackager )
					)
					( objectStatus "C8F16.1" )
				)
				( pin "b"
					( attribute "PN" "2"
						( Origin gPackager )
					)
					( objectStatus "C8F16.2" )
				)
			)
			( gate "@baseboard_fab2_lib.baseboard_fab2(sch_1):page156_i279"
				( attribute "BOM_COST" "SM_CONTROLLER"
					( Origin gFrontEnd )
				)
				( attribute "CDS_LIB" "mstr_discrete"
					( Origin gPackager )
				)
				( attribute "CDS_LOCATION" "R8E11"
					( Origin gPackager )
				)
				( attribute "CDS_SEC" "1"
					( Origin gPackager )
				)
				( attribute "LOCATION" "R8E11"
					( Origin gFrontEnd )
				)
				( attribute "MATERIAL" "EMPTY"
					( Origin gFrontEnd )
				)
				( attribute "PACK_TYPE" "0402"
					( Origin gFrontEnd )
				)
				( attribute "PART_NUMBER" "G21497-005"
					( Origin gFrontEnd )
				)
				( attribute "PHYS_PAGE" "156"
					( Origin gFrontEnd )
				)
				( attribute "ROOM" "BMC_MISC"
					( Origin gFrontEnd )
				)
				( attribute "ROT" "0"
					( Origin gFrontEnd )
				)
				( attribute "SEC" "1"
					( Origin gFrontEnd )
				)
				( attribute "SEC_TYPE" "0402"
					( Origin gFrontEnd )
				)
				( attribute "TOLERANCE" "5%"
					( Origin gFrontEnd )
				)
				( attribute "VALUE" "0.0"
					( Origin gFrontEnd )
				)
				( attribute "VER" "1"
					( Origin gFrontEnd )
				)
				( attribute "WATTAGE" "1/16W"
					( Origin gFrontEnd )
				)
				( attribute "XY" "(-6600,2350)"
					( Origin gFrontEnd )
				)
				( attribute "CHIPS_PART_NAME" "RES"
					( Origin gPackager )
				)
				( attribute "CDS_PART_NAME" "RES_0402-0.0,5%,1/16W,EMPTY,G2A"
					( Origin gPackager )
				)
				( objectStatus "R8E11" )
				( pin "a"
					( attribute "PN" "1"
						( Origin gPackager )
					)
					( objectStatus "R8E11.1" )
				)
				( pin "b"
					( attribute "PN" "2"
						( Origin gPackager )
					)
					( objectStatus "R8E11.2" )
				)
			)
			( gate "@baseboard_fab2_lib.baseboard_fab2(sch_1):page156_i281"
				( attribute "BOM_COST" "DEBUG"
					( Origin gFrontEnd )
				)
				( attribute "CDS_LIB" "mstr_conn"
					( Origin gPackager )
				)
				( attribute "CDS_LOCATION" "J9B2"
					( Origin gPackager )
				)
				( attribute "CDS_SEC" "1"
					( Origin gPackager )
				)
				( attribute "LOCATION" "J9B2"
					( Origin gFrontEnd )
				)
				( attribute "MATERIAL" "CONN"
					( Origin gFrontEnd )
				)
				( attribute "PACK_TYPE" "PIP"
					( Origin gFrontEnd )
				)
				( attribute "PART_NUMBER" "C95678-002"
					( Origin gFrontEnd )
				)
				( attribute "PHYS_PAGE" "156"
					( Origin gFrontEnd )
				)
				( attribute "ROOM" "DEBUG"
					( Origin gFrontEnd )
				)
				( attribute "ROT" "0"
					( Origin gFrontEnd )
				)
				( attribute "SEC" "1"
					( Origin gFrontEnd )
				)
				( attribute "SEC_TYPE" "PIP"
					( Origin gFrontEnd )
				)
				( attribute "VER" "1"
					( Origin gFrontEnd )
				)
				( attribute "XY" "(-7575,3700)"
					( Origin gFrontEnd )
				)
				( attribute "CHIPS_PART_NAME" "CONN3_C95678002"
					( Origin gPackager )
				)
				( attribute "CDS_PART_NAME" "CONN3_C95678002_PIP-CONN,C9567A"
					( Origin gPackager )
				)
				( objectStatus "J9B2" )
				( pin "io1"
					( attribute "PN" "1"
						( Origin gPackager )
					)
					( objectStatus "J9B2.1" )
				)
				( pin "io2"
					( attribute "PN" "2"
						( Origin gPackager )
					)
					( objectStatus "J9B2.2" )
				)
				( pin "io3"
					( attribute "PN" "3"
						( Origin gPackager )
					)
					( objectStatus "J9B2.3" )
				)
			)
			( gate "@baseboard_fab2_lib.baseboard_fab2(sch_1):page156_i285"
				( attribute "BOM_COST" "DEBUG"
					( Origin gFrontEnd )
				)
				( attribute "CDS_LIB" "mstr_conn"
					( Origin gPackager )
				)
				( attribute "CDS_LOCATION" "J8C1"
					( Origin gPackager )
				)
				( attribute "CDS_SEC" "1"
					( Origin gPackager )
				)
				( attribute "LOCATION" "J8C1"
					( Origin gFrontEnd )
				)
				( attribute "MATERIAL" "CONN"
					( Origin gFrontEnd )
				)
				( attribute "PACK_TYPE" "PIP"
					( Origin gFrontEnd )
				)
				( attribute "PART_NUMBER" "C95678-002"
					( Origin gFrontEnd )
				)
				( attribute "PHYS_PAGE" "156"
					( Origin gFrontEnd )
				)
				( attribute "ROOM" "DEBUG"
					( Origin gFrontEnd )
				)
				( attribute "ROT" "0"
					( Origin gFrontEnd )
				)
				( attribute "SEC" "1"
					( Origin gFrontEnd )
				)
				( attribute "SEC_TYPE" "PIP"
					( Origin gFrontEnd )
				)
				( attribute "VER" "1"
					( Origin gFrontEnd )
				)
				( attribute "XY" "(-7600,4475)"
					( Origin gFrontEnd )
				)
				( attribute "CHIPS_PART_NAME" "CONN3_C95678002"
					( Origin gPackager )
				)
				( attribute "CDS_PART_NAME" "CONN3_C95678002_PIP-CONN,C9567A"
					( Origin gPackager )
				)
				( objectStatus "J8C1" )
				( pin "io1"
					( attribute "PN" "1"
						( Origin gPackager )
					)
					( objectStatus "J8C1.1" )
				)
				( pin "io2"
					( attribute "PN" "2"
						( Origin gPackager )
					)
					( objectStatus "J8C1.2" )
				)
				( pin "io3"
					( attribute "PN" "3"
						( Origin gPackager )
					)
					( objectStatus "J8C1.3" )
				)
			)
			( gate "@baseboard_fab2_lib.baseboard_fab2(sch_1):page156_i288"
				( attribute "BOM_COST" "SM_CONTROLLER"
					( Origin gFrontEnd )
				)
				( attribute "CDS_LIB" "mstr_discrete"
					( Origin gPackager )
				)
				( attribute "CDS_LOCATION" "R2T18"
					( Origin gPackager )
				)
				( attribute "CDS_SEC" "1"
					( Origin gPackager )
				)
				( attribute "LOCATION" "R2T18"
					( Origin gFrontEnd )
				)
				( attribute "MATERIAL" "CHIP"
					( Origin gFrontEnd )
				)
				( attribute "PACK_TYPE" "0402"
					( Origin gFrontEnd )
				)
				( attribute "PART_NUMBER" "G21796-047"
					( Origin gFrontEnd )
				)
				( attribute "PHYS_PAGE" "156"
					( Origin gFrontEnd )
				)
				( attribute "ROOM" "BMC_MISC"
					( Origin gFrontEnd )
				)
				( attribute "ROT" "0"
					( Origin gFrontEnd )
				)
				( attribute "SEC" "1"
					( Origin gFrontEnd )
				)
				( attribute "SEC_TYPE" "0402"
					( Origin gFrontEnd )
				)
				( attribute "TOLERANCE" "1%"
					( Origin gFrontEnd )
				)
				( attribute "VALUE" "49.9"
					( Origin gFrontEnd )
				)
				( attribute "VER" "1"
					( Origin gFrontEnd )
				)
				( attribute "WATTAGE" "1/16W"
					( Origin gFrontEnd )
				)
				( attribute "XY" "(-1700,4150)"
					( Origin gFrontEnd )
				)
				( attribute "CHIPS_PART_NAME" "RES"
					( Origin gPackager )
				)
				( attribute "CDS_PART_NAME" "RES_0402-49.9,1%,1/16W,CHIP,G2A"
					( Origin gPackager )
				)
				( objectStatus "R2T18" )
				( pin "a"
					( attribute "PN" "1"
						( Origin gPackager )
					)
					( objectStatus "R2T18.1" )
				)
				( pin "b"
					( attribute "PN" "2"
						( Origin gPackager )
					)
					( objectStatus "R2T18.2" )
				)
			)
			( gate "@baseboard_fab2_lib.baseboard_fab2(sch_1):page156_i289"
				( attribute "BOM_COST" "SM_CONTROLLER"
					( Origin gFrontEnd )
				)
				( attribute "CDS_LIB" "mstr_discrete"
					( Origin gPackager )
				)
				( attribute "CDS_LOCATION" "R2T28"
					( Origin gPackager )
				)
				( attribute "CDS_SEC" "1"
					( Origin gPackager )
				)
				( attribute "LOCATION" "R2T28"
					( Origin gFrontEnd )
				)
				( attribute "MATERIAL" "CHIP"
					( Origin gFrontEnd )
				)
				( attribute "PACK_TYPE" "0402"
					( Origin gFrontEnd )
				)
				( attribute "PART_NUMBER" "G21796-074"
					( Origin gFrontEnd )
				)
				( attribute "PHYS_PAGE" "156"
					( Origin gFrontEnd )
				)
				( attribute "ROOM" "BMC_MISC"
					( Origin gFrontEnd )
				)
				( attribute "ROT" "6"
					( Origin gFrontEnd )
				)
				( attribute "SEC" "1"
					( Origin gFrontEnd )
				)
				( attribute "SEC_TYPE" "0402"
					( Origin gFrontEnd )
				)
				( attribute "TOLERANCE" "1%"
					( Origin gFrontEnd )
				)
				( attribute "VALUE" "33.2"
					( Origin gFrontEnd )
				)
				( attribute "VER" "1"
					( Origin gFrontEnd )
				)
				( attribute "WATTAGE" "1/16W"
					( Origin gFrontEnd )
				)
				( attribute "XY" "(-1700,4100)"
					( Origin gFrontEnd )
				)
				( attribute "CHIPS_PART_NAME" "RES"
					( Origin gPackager )
				)
				( attribute "CDS_PART_NAME" "RES_0402-33.2,1%,1/16W,CHIP,G2A"
					( Origin gPackager )
				)
				( objectStatus "R2T28" )
				( pin "a"
					( attribute "PN" "1"
						( Origin gPackager )
					)
					( objectStatus "R2T28.1" )
				)
				( pin "b"
					( attribute "PN" "2"
						( Origin gPackager )
					)
					( objectStatus "R2T28.2" )
				)
			)
			( gate "@baseboard_fab2_lib.baseboard_fab2(sch_1):page156_i299"
				( attribute "BOM_COST" "SM_CONTROLLER"
					( Origin gFrontEnd )
				)
				( attribute "CDS_LIB" "mstr_discrete"
					( Origin gPackager )
				)
				( attribute "CDS_LOCATION" "R6D16"
					( Origin gPackager )
				)
				( attribute "CDS_SEC" "1"
					( Origin gPackager )
				)
				( attribute "LOCATION" "R6D16"
					( Origin gFrontEnd )
				)
				( attribute "MATERIAL" "EMPTY"
					( Origin gFrontEnd )
				)
				( attribute "PACK_TYPE" "0402"
					( Origin gFrontEnd )
				)
				( attribute "PART_NUMBER" "G21497-005"
					( Origin gFrontEnd )
				)
				( attribute "PHYS_PAGE" "156"
					( Origin gFrontEnd )
				)
				( attribute "ROOM" "BMC_MISC"
					( Origin gFrontEnd )
				)
				( attribute "ROT" "0"
					( Origin gFrontEnd )
				)
				( attribute "SEC" "1"
					( Origin gFrontEnd )
				)
				( attribute "SEC_TYPE" "0402"
					( Origin gFrontEnd )
				)
				( attribute "TOLERANCE" "5%"
					( Origin gFrontEnd )
				)
				( attribute "VALUE" "0.0"
					( Origin gFrontEnd )
				)
				( attribute "VER" "1"
					( Origin gFrontEnd )
				)
				( attribute "WATTAGE" "1/16W"
					( Origin gFrontEnd )
				)
				( attribute "XY" "(-2900,1825)"
					( Origin gFrontEnd )
				)
				( attribute "CHIPS_PART_NAME" "RES"
					( Origin gPackager )
				)
				( attribute "CDS_PART_NAME" "RES_0402-0.0,5%,1/16W,EMPTY,G2A"
					( Origin gPackager )
				)
				( objectStatus "R6D16" )
				( pin "a"
					( attribute "PN" "1"
						( Origin gPackager )
					)
					( objectStatus "R6D16.1" )
				)
				( pin "b"
					( attribute "PN" "2"
						( Origin gPackager )
					)
					( objectStatus "R6D16.2" )
				)
			)
			( gate "@baseboard_fab2_lib.baseboard_fab2(sch_1):page156_i300"
				( attribute "BOM_COST" "SM_CONTROLLER"
					( Origin gFrontEnd )
				)
				( attribute "CDS_LIB" "mstr_discrete"
					( Origin gPackager )
				)
				( attribute "CDS_LOCATION" "R3D31"
					( Origin gPackager )
				)
				( attribute "CDS_SEC" "1"
					( Origin gPackager )
				)
				( attribute "LOCATION" "R3D31"
					( Origin gFrontEnd )
				)
				( attribute "MATERIAL" "EMPTY"
					( Origin gFrontEnd )
				)
				( attribute "PACK_TYPE" "0402"
					( Origin gFrontEnd )
				)
				( attribute "PART_NUMBER" "G21497-005"
					( Origin gFrontEnd )
				)
				( attribute "PHYS_PAGE" "156"
					( Origin gFrontEnd )
				)
				( attribute "ROOM" "BMC_MISC"
					( Origin gFrontEnd )
				)
				( attribute "ROT" "0"
					( Origin gFrontEnd )
				)
				( attribute "SEC" "1"
					( Origin gFrontEnd )
				)
				( attribute "SEC_TYPE" "0402"
					( Origin gFrontEnd )
				)
				( attribute "TOLERANCE" "5%"
					( Origin gFrontEnd )
				)
				( attribute "VALUE" "0.0"
					( Origin gFrontEnd )
				)
				( attribute "VER" "1"
					( Origin gFrontEnd )
				)
				( attribute "WATTAGE" "1/16W"
					( Origin gFrontEnd )
				)
				( attribute "XY" "(-2900,1550)"
					( Origin gFrontEnd )
				)
				( attribute "CHIPS_PART_NAME" "RES"
					( Origin gPackager )
				)
				( attribute "CDS_PART_NAME" "RES_0402-0.0,5%,1/16W,EMPTY,G2A"
					( Origin gPackager )
				)
				( objectStatus "R3D31" )
				( pin "a"
					( attribute "PN" "1"
						( Origin gPackager )
					)
					( objectStatus "R3D31.1" )
				)
				( pin "b"
					( attribute "PN" "2"
						( Origin gPackager )
					)
					( objectStatus "R3D31.2" )
				)
			)
			( gate "@baseboard_fab2_lib.baseboard_fab2(sch_1):page156_i302"
				( attribute "CDS_LIB" "mstr_discrete"
					( Origin gPackager )
				)
				( attribute "CDS_LOCATION" "R6N14"
					( Origin gPackager )
				)
				( attribute "CDS_SEC" "1"
					( Origin gPackager )
				)
				( attribute "LOCATION" "R6N14"
					( Origin gFrontEnd )
				)
				( attribute "MATERIAL" "CHIP"
					( Origin gFrontEnd )
				)
				( attribute "PACK_TYPE" "0402"
					( Origin gFrontEnd )
				)
				( attribute "PART_NUMBER" "G21796-026"
					( Origin gFrontEnd )
				)
				( attribute "PHYS_PAGE" "156"
					( Origin gFrontEnd )
				)
				( attribute "ROOM" "CPU0"
					( Origin gFrontEnd )
				)
				( attribute "ROT" "0"
					( Origin gFrontEnd )
				)
				( attribute "SEC" "1"
					( Origin gFrontEnd )
				)
				( attribute "SEC_TYPE" "0402"
					( Origin gFrontEnd )
				)
				( attribute "TOLERANCE" "1%"
					( Origin gFrontEnd )
				)
				( attribute "VALUE" "1.00K"
					( Origin gFrontEnd )
				)
				( attribute "VER" "1"
					( Origin gFrontEnd )
				)
				( attribute "WATTAGE" "1/16W"
					( Origin gFrontEnd )
				)
				( attribute "XY" "(-4000,975)"
					( Origin gFrontEnd )
				)
				( attribute "CHIPS_PART_NAME" "RES"
					( Origin gPackager )
				)
				( attribute "CDS_PART_NAME" "RES_0402-1.00K,1%,1/16W,CHIP,GA"
					( Origin gPackager )
				)
				( objectStatus "R6N14" )
				( pin "a"
					( attribute "PN" "1"
						( Origin gPackager )
					)
					( objectStatus "R6N14.1" )
				)
				( pin "b"
					( attribute "PN" "2"
						( Origin gPackager )
					)
					( objectStatus "R6N14.2" )
				)
			)
			( gate "@baseboard_fab2_lib.baseboard_fab2(sch_1):page156_i303"
				( attribute "CDS_LIB" "mstr_discrete"
					( Origin gPackager )
				)
				( attribute "CDS_LOCATION" "R6N13"
					( Origin gPackager )
				)
				( attribute "CDS_SEC" "1"
					( Origin gPackager )
				)
				( attribute "LOCATION" "R6N13"
					( Origin gFrontEnd )
				)
				( attribute "MATERIAL" "CHIP"
					( Origin gFrontEnd )
				)
				( attribute "PACK_TYPE" "0402"
					( Origin gFrontEnd )
				)
				( attribute "PART_NUMBER" "G21796-026"
					( Origin gFrontEnd )
				)
				( attribute "PHYS_PAGE" "156"
					( Origin gFrontEnd )
				)
				( attribute "ROOM" "CPU0"
					( Origin gFrontEnd )
				)
				( attribute "ROT" "0"
					( Origin gFrontEnd )
				)
				( attribute "SEC" "1"
					( Origin gFrontEnd )
				)
				( attribute "SEC_TYPE" "0402"
					( Origin gFrontEnd )
				)
				( attribute "TOLERANCE" "1%"
					( Origin gFrontEnd )
				)
				( attribute "VALUE" "1.00K"
					( Origin gFrontEnd )
				)
				( attribute "VER" "1"
					( Origin gFrontEnd )
				)
				( attribute "WATTAGE" "1/16W"
					( Origin gFrontEnd )
				)
				( attribute "XY" "(-4000,775)"
					( Origin gFrontEnd )
				)
				( attribute "CHIPS_PART_NAME" "RES"
					( Origin gPackager )
				)
				( attribute "CDS_PART_NAME" "RES_0402-1.00K,1%,1/16W,CHIP,GA"
					( Origin gPackager )
				)
				( objectStatus "R6N13" )
				( pin "a"
					( attribute "PN" "1"
						( Origin gPackager )
					)
					( objectStatus "R6N13.1" )
				)
				( pin "b"
					( attribute "PN" "2"
						( Origin gPackager )
					)
					( objectStatus "R6N13.2" )
				)
			)
			( gate "@baseboard_fab2_lib.baseboard_fab2(sch_1):page156_i304"
				( attribute "CDS_LIB" "mstr_discrete"
					( Origin gPackager )
				)
				( attribute "CDS_LOCATION" "R6N15"
					( Origin gPackager )
				)
				( attribute "CDS_SEC" "1"
					( Origin gPackager )
				)
				( attribute "LOCATION" "R6N15"
					( Origin gFrontEnd )
				)
				( attribute "MATERIAL" "CHIP"
					( Origin gFrontEnd )
				)
				( attribute "PACK_TYPE" "0402"
					( Origin gFrontEnd )
				)
				( attribute "PART_NUMBER" "G21796-026"
					( Origin gFrontEnd )
				)
				( attribute "PHYS_PAGE" "156"
					( Origin gFrontEnd )
				)
				( attribute "ROOM" "CPU0"
					( Origin gFrontEnd )
				)
				( attribute "ROT" "0"
					( Origin gFrontEnd )
				)
				( attribute "SEC" "1"
					( Origin gFrontEnd )
				)
				( attribute "SEC_TYPE" "0402"
					( Origin gFrontEnd )
				)
				( attribute "TOLERANCE" "1%"
					( Origin gFrontEnd )
				)
				( attribute "VALUE" "1.00K"
					( Origin gFrontEnd )
				)
				( attribute "VER" "1"
					( Origin gFrontEnd )
				)
				( attribute "WATTAGE" "1/16W"
					( Origin gFrontEnd )
				)
				( attribute "XY" "(-4000,575)"
					( Origin gFrontEnd )
				)
				( attribute "CHIPS_PART_NAME" "RES"
					( Origin gPackager )
				)
				( attribute "CDS_PART_NAME" "RES_0402-1.00K,1%,1/16W,CHIP,GA"
					( Origin gPackager )
				)
				( objectStatus "R6N15" )
				( pin "a"
					( attribute "PN" "1"
						( Origin gPackager )
					)
					( objectStatus "R6N15.1" )
				)
				( pin "b"
					( attribute "PN" "2"
						( Origin gPackager )
					)
					( objectStatus "R6N15.2" )
				)
			)
			( gate "@baseboard_fab2_lib.baseboard_fab2(sch_1):page156_i312"
				( attribute "CDS_LIB" "mstr_discrete"
					( Origin gPackager )
				)
				( attribute "CDS_LOCATION" "R1C32"
					( Origin gPackager )
				)
				( attribute "CDS_SEC" "1"
					( Origin gPackager )
				)
				( attribute "LOCATION" "R1C32"
					( Origin gFrontEnd )
				)
				( attribute "MATERIAL" "CHIP"
					( Origin gFrontEnd )
				)
				( attribute "PACK_TYPE" "0402"
					( Origin gFrontEnd )
				)
				( attribute "PART_NUMBER" "G21796-026"
					( Origin gFrontEnd )
				)
				( attribute "PHYS_PAGE" "156"
					( Origin gFrontEnd )
				)
				( attribute "ROOM" "CPU1"
					( Origin gFrontEnd )
				)
				( attribute "ROT" "0"
					( Origin gFrontEnd )
				)
				( attribute "SEC" "1"
					( Origin gFrontEnd )
				)
				( attribute "SEC_TYPE" "0402"
					( Origin gFrontEnd )
				)
				( attribute "TOLERANCE" "1%"
					( Origin gFrontEnd )
				)
				( attribute "VALUE" "1.00K"
					( Origin gFrontEnd )
				)
				( attribute "VER" "1"
					( Origin gFrontEnd )
				)
				( attribute "WATTAGE" "1/16W"
					( Origin gFrontEnd )
				)
				( attribute "XY" "(-1900,575)"
					( Origin gFrontEnd )
				)
				( attribute "CHIPS_PART_NAME" "RES"
					( Origin gPackager )
				)
				( attribute "CDS_PART_NAME" "RES_0402-1.00K,1%,1/16W,CHIP,GA"
					( Origin gPackager )
				)
				( objectStatus "R1C32" )
				( pin "a"
					( attribute "PN" "1"
						( Origin gPackager )
					)
					( objectStatus "R1C32.1" )
				)
				( pin "b"
					( attribute "PN" "2"
						( Origin gPackager )
					)
					( objectStatus "R1C32.2" )
				)
			)
			( gate "@baseboard_fab2_lib.baseboard_fab2(sch_1):page156_i313"
				( attribute "CDS_LIB" "mstr_discrete"
					( Origin gPackager )
				)
				( attribute "CDS_LOCATION" "R1C33"
					( Origin gPackager )
				)
				( attribute "CDS_SEC" "1"
					( Origin gPackager )
				)
				( attribute "LOCATION" "R1C33"
					( Origin gFrontEnd )
				)
				( attribute "MATERIAL" "CHIP"
					( Origin gFrontEnd )
				)
				( attribute "PACK_TYPE" "0402"
					( Origin gFrontEnd )
				)
				( attribute "PART_NUMBER" "G21796-026"
					( Origin gFrontEnd )
				)
				( attribute "PHYS_PAGE" "156"
					( Origin gFrontEnd )
				)
				( attribute "ROOM" "CPU1"
					( Origin gFrontEnd )
				)
				( attribute "ROT" "0"
					( Origin gFrontEnd )
				)
				( attribute "SEC" "1"
					( Origin gFrontEnd )
				)
				( attribute "SEC_TYPE" "0402"
					( Origin gFrontEnd )
				)
				( attribute "TOLERANCE" "1%"
					( Origin gFrontEnd )
				)
				( attribute "VALUE" "1.00K"
					( Origin gFrontEnd )
				)
				( attribute "VER" "1"
					( Origin gFrontEnd )
				)
				( attribute "WATTAGE" "1/16W"
					( Origin gFrontEnd )
				)
				( attribute "XY" "(-1900,775)"
					( Origin gFrontEnd )
				)
				( attribute "CHIPS_PART_NAME" "RES"
					( Origin gPackager )
				)
				( attribute "CDS_PART_NAME" "RES_0402-1.00K,1%,1/16W,CHIP,GA"
					( Origin gPackager )
				)
				( objectStatus "R1C33" )
				( pin "a"
					( attribute "PN" "1"
						( Origin gPackager )
					)
					( objectStatus "R1C33.1" )
				)
				( pin "b"
					( attribute "PN" "2"
						( Origin gPackager )
					)
					( objectStatus "R1C33.2" )
				)
			)
			( gate "@baseboard_fab2_lib.baseboard_fab2(sch_1):page156_i320"
				( attribute "CDS_LIB" "mstr_discrete"
					( Origin gPackager )
				)
				( attribute "CDS_LOCATION" "R1C34"
					( Origin gPackager )
				)
				( attribute "CDS_SEC" "1"
					( Origin gPackager )
				)
				( attribute "LOCATION" "R1C34"
					( Origin gFrontEnd )
				)
				( attribute "MATERIAL" "CHIP"
					( Origin gFrontEnd )
				)
				( attribute "PACK_TYPE" "0402"
					( Origin gFrontEnd )
				)
				( attribute "PART_NUMBER" "G21796-016"
					( Origin gFrontEnd )
				)
				( attribute "PHYS_PAGE" "156"
					( Origin gFrontEnd )
				)
				( attribute "ROOM" "CPU1"
					( Origin gFrontEnd )
				)
				( attribute "ROT" "0"
					( Origin gFrontEnd )
				)
				( attribute "SEC" "1"
					( Origin gFrontEnd )
				)
				( attribute "SEC_TYPE" "0402"
					( Origin gFrontEnd )
				)
				( attribute "TOLERANCE" "1%"
					( Origin gFrontEnd )
				)
				( attribute "VALUE" "10.0K"
					( Origin gFrontEnd )
				)
				( attribute "VER" "1"
					( Origin gFrontEnd )
				)
				( attribute "WATTAGE" "1/16W"
					( Origin gFrontEnd )
				)
				( attribute "XY" "(-1900,975)"
					( Origin gFrontEnd )
				)
				( attribute "CHIPS_PART_NAME" "RES"
					( Origin gPackager )
				)
				( attribute "CDS_PART_NAME" "RES_0402-10.0K,1%,1/16W,CHIP,GA"
					( Origin gPackager )
				)
				( objectStatus "R1C34" )
				( pin "a"
					( attribute "PN" "1"
						( Origin gPackager )
					)
					( objectStatus "R1C34.1" )
				)
				( pin "b"
					( attribute "PN" "2"
						( Origin gPackager )
					)
					( objectStatus "R1C34.2" )
				)
			)
			( gate "@baseboard_fab2_lib.baseboard_fab2(sch_1):page156_i321"
				( attribute "CDS_LIB" "mstr_discrete"
					( Origin gPackager )
				)
				( attribute "CDS_LOCATION" "R9M21"
					( Origin gPackager )
				)
				( attribute "CDS_SEC" "1"
					( Origin gPackager )
				)
				( attribute "LOCATION" "R9M21"
					( Origin gFrontEnd )
				)
				( attribute "MATERIAL" "CHIP"
					( Origin gFrontEnd )
				)
				( attribute "PACK_TYPE" "0402"
					( Origin gFrontEnd )
				)
				( attribute "PART_NUMBER" "G21497-005"
					( Origin gFrontEnd )
				)
				( attribute "PHYS_PAGE" "156"
					( Origin gFrontEnd )
				)
				( attribute "ROOM" "CPU1"
					( Origin gFrontEnd )
				)
				( attribute "ROT" "0"
					( Origin gFrontEnd )
				)
				( attribute "SEC" "1"
					( Origin gFrontEnd )
				)
				( attribute "SEC_TYPE" "0402"
					( Origin gFrontEnd )
				)
				( attribute "TOLERANCE" "5%"
					( Origin gFrontEnd )
				)
				( attribute "VALUE" "0.0"
					( Origin gFrontEnd )
				)
				( attribute "VER" "1"
					( Origin gFrontEnd )
				)
				( attribute "WATTAGE" "1/16W"
					( Origin gFrontEnd )
				)
				( attribute "XY" "(-6425,850)"
					( Origin gFrontEnd )
				)
				( attribute "CHIPS_PART_NAME" "RES"
					( Origin gPackager )
				)
				( attribute "CDS_PART_NAME" "RES_0402-0.0,5%,1/16W,CHIP,G21A"
					( Origin gPackager )
				)
				( objectStatus "R9M21" )
				( pin "a"
					( attribute "PN" "1"
						( Origin gPackager )
					)
					( objectStatus "R9M21.1" )
				)
				( pin "b"
					( attribute "PN" "2"
						( Origin gPackager )
					)
					( objectStatus "R9M21.2" )
				)
			)
			( gate "@baseboard_fab2_lib.baseboard_fab2(sch_1):page156_i322"
				( attribute "CDS_LIB" "mstr_discrete"
					( Origin gPackager )
				)
				( attribute "CDS_LOCATION" "R4A8"
					( Origin gPackager )
				)
				( attribute "CDS_SEC" "1"
					( Origin gPackager )
				)
				( attribute "LOCATION" "R4A8"
					( Origin gFrontEnd )
				)
				( attribute "MATERIAL" "CHIP"
					( Origin gFrontEnd )
				)
				( attribute "PACK_TYPE" "0402"
					( Origin gFrontEnd )
				)
				( attribute "PART_NUMBER" "G21497-005"
					( Origin gFrontEnd )
				)
				( attribute "PHYS_PAGE" "156"
					( Origin gFrontEnd )
				)
				( attribute "ROOM" "CPU0"
					( Origin gFrontEnd )
				)
				( attribute "ROT" "0"
					( Origin gFrontEnd )
				)
				( attribute "SEC" "1"
					( Origin gFrontEnd )
				)
				( attribute "SEC_TYPE" "0402"
					( Origin gFrontEnd )
				)
				( attribute "TOLERANCE" "5%"
					( Origin gFrontEnd )
				)
				( attribute "VALUE" "0.0"
					( Origin gFrontEnd )
				)
				( attribute "VER" "1"
					( Origin gFrontEnd )
				)
				( attribute "WATTAGE" "1/16W"
					( Origin gFrontEnd )
				)
				( attribute "XY" "(-6425,700)"
					( Origin gFrontEnd )
				)
				( attribute "CHIPS_PART_NAME" "RES"
					( Origin gPackager )
				)
				( attribute "CDS_PART_NAME" "RES_0402-0.0,5%,1/16W,CHIP,G21A"
					( Origin gPackager )
				)
				( objectStatus "R4A8" )
				( pin "a"
					( attribute "PN" "1"
						( Origin gPackager )
					)
					( objectStatus "R4A8.1" )
				)
				( pin "b"
					( attribute "PN" "2"
						( Origin gPackager )
					)
					( objectStatus "R4A8.2" )
				)
			)
			( gate "@baseboard_fab2_lib.baseboard_fab2(sch_1):page156_i323"
				( attribute "CDS_LIB" "mstr_discrete"
					( Origin gPackager )
				)
				( attribute "CDS_LOCATION" "R9M20"
					( Origin gPackager )
				)
				( attribute "CDS_SEC" "1"
					( Origin gPackager )
				)
				( attribute "LOCATION" "R9M20"
					( Origin gFrontEnd )
				)
				( attribute "MATERIAL" "CHIP"
					( Origin gFrontEnd )
				)
				( attribute "PACK_TYPE" "0402"
					( Origin gFrontEnd )
				)
				( attribute "PART_NUMBER" "G21497-005"
					( Origin gFrontEnd )
				)
				( attribute "PHYS_PAGE" "156"
					( Origin gFrontEnd )
				)
				( attribute "ROOM" "CPU1"
					( Origin gFrontEnd )
				)
				( attribute "ROT" "0"
					( Origin gFrontEnd )
				)
				( attribute "SEC" "1"
					( Origin gFrontEnd )
				)
				( attribute "SEC_TYPE" "0402"
					( Origin gFrontEnd )
				)
				( attribute "TOLERANCE" "5%"
					( Origin gFrontEnd )
				)
				( attribute "VALUE" "0.0"
					( Origin gFrontEnd )
				)
				( attribute "VER" "1"
					( Origin gFrontEnd )
				)
				( attribute "WATTAGE" "1/16W"
					( Origin gFrontEnd )
				)
				( attribute "XY" "(-6425,550)"
					( Origin gFrontEnd )
				)
				( attribute "CHIPS_PART_NAME" "RES"
					( Origin gPackager )
				)
				( attribute "CDS_PART_NAME" "RES_0402-0.0,5%,1/16W,CHIP,G21A"
					( Origin gPackager )
				)
				( objectStatus "R9M20" )
				( pin "a"
					( attribute "PN" "1"
						( Origin gPackager )
					)
					( objectStatus "R9M20.1" )
				)
				( pin "b"
					( attribute "PN" "2"
						( Origin gPackager )
					)
					( objectStatus "R9M20.2" )
				)
			)
			( gate "@baseboard_fab2_lib.baseboard_fab2(sch_1):page156_i324"
				( attribute "CDS_LIB" "mstr_discrete"
					( Origin gPackager )
				)
				( attribute "CDS_LOCATION" "R4A9"
					( Origin gPackager )
				)
				( attribute "CDS_SEC" "1"
					( Origin gPackager )
				)
				( attribute "LOCATION" "R4A9"
					( Origin gFrontEnd )
				)
				( attribute "MATERIAL" "CHIP"
					( Origin gFrontEnd )
				)
				( attribute "PACK_TYPE" "0402"
					( Origin gFrontEnd )
				)
				( attribute "PART_NUMBER" "G21497-005"
					( Origin gFrontEnd )
				)
				( attribute "PHYS_PAGE" "156"
					( Origin gFrontEnd )
				)
				( attribute "ROOM" "CPU0"
					( Origin gFrontEnd )
				)
				( attribute "ROT" "0"
					( Origin gFrontEnd )
				)
				( attribute "SEC" "1"
					( Origin gFrontEnd )
				)
				( attribute "SEC_TYPE" "0402"
					( Origin gFrontEnd )
				)
				( attribute "TOLERANCE" "5%"
					( Origin gFrontEnd )
				)
				( attribute "VALUE" "0.0"
					( Origin gFrontEnd )
				)
				( attribute "VER" "1"
					( Origin gFrontEnd )
				)
				( attribute "WATTAGE" "1/16W"
					( Origin gFrontEnd )
				)
				( attribute "XY" "(-6425,400)"
					( Origin gFrontEnd )
				)
				( attribute "CHIPS_PART_NAME" "RES"
					( Origin gPackager )
				)
				( attribute "CDS_PART_NAME" "RES_0402-0.0,5%,1/16W,CHIP,G21A"
					( Origin gPackager )
				)
				( objectStatus "R4A9" )
				( pin "a"
					( attribute "PN" "1"
						( Origin gPackager )
					)
					( objectStatus "R4A9.1" )
				)
				( pin "b"
					( attribute "PN" "2"
						( Origin gPackager )
					)
					( objectStatus "R4A9.2" )
				)
			)
			( gate "@baseboard_fab2_lib.baseboard_fab2(sch_1):page156_i331"
				( attribute "CDS_LIB" "mstr_discrete"
					( Origin gPackager )
				)
				( attribute "CDS_LOCATION" "R3P54"
					( Origin gPackager )
				)
				( attribute "CDS_SEC" "1"
					( Origin gPackager )
				)
				( attribute "LOCATION" "R3P54"
					( Origin gFrontEnd )
				)
				( attribute "MATERIAL" "EMPTY"
					( Origin gFrontEnd )
				)
				( attribute "PACK_TYPE" "0402"
					( Origin gFrontEnd )
				)
				( attribute "PART_NUMBER" "G21796-027"
					( Origin gFrontEnd )
				)
				( attribute "PHYS_PAGE" "156"
					( Origin gFrontEnd )
				)
				( attribute "ROOM" "CPU0"
					( Origin gFrontEnd )
				)
				( attribute "ROT" "0"
					( Origin gFrontEnd )
				)
				( attribute "SEC" "1"
					( Origin gFrontEnd )
				)
				( attribute "SEC_TYPE" "0402"
					( Origin gFrontEnd )
				)
				( attribute "TOLERANCE" "1%"
					( Origin gFrontEnd )
				)
				( attribute "VALUE" "3.32K"
					( Origin gFrontEnd )
				)
				( attribute "VER" "2"
					( Origin gFrontEnd )
				)
				( attribute "WATTAGE" "1/16W"
					( Origin gFrontEnd )
				)
				( attribute "XY" "(-7650,1700)"
					( Origin gFrontEnd )
				)
				( attribute "CHIPS_PART_NAME" "RES"
					( Origin gPackager )
				)
				( attribute "CDS_PART_NAME" "RES_0402-3.32K,1%,1/16W,EMPTY,A"
					( Origin gPackager )
				)
				( objectStatus "R3P54" )
				( pin "a"
					( attribute "PN" "1"
						( Origin gPackager )
					)
					( objectStatus "R3P54.1" )
				)
				( pin "b"
					( attribute "PN" "2"
						( Origin gPackager )
					)
					( objectStatus "R3P54.2" )
				)
			)
			( gate "@baseboard_fab2_lib.baseboard_fab2(sch_1):page156_i333"
				( attribute "CDS_LIB" "mstr_discrete"
					( Origin gPackager )
				)
				( attribute "CDS_LOCATION" "R3P56"
					( Origin gPackager )
				)
				( attribute "CDS_SEC" "1"
					( Origin gPackager )
				)
				( attribute "LOCATION" "R3P56"
					( Origin gFrontEnd )
				)
				( attribute "MATERIAL" "CHIP"
					( Origin gFrontEnd )
				)
				( attribute "PACK_TYPE" "0402"
					( Origin gFrontEnd )
				)
				( attribute "PART_NUMBER" "G21796-026"
					( Origin gFrontEnd )
				)
				( attribute "PHYS_PAGE" "156"
					( Origin gFrontEnd )
				)
				( attribute "ROOM" "CPU0"
					( Origin gFrontEnd )
				)
				( attribute "ROT" "0"
					( Origin gFrontEnd )
				)
				( attribute "SEC" "1"
					( Origin gFrontEnd )
				)
				( attribute "SEC_TYPE" "0402"
					( Origin gFrontEnd )
				)
				( attribute "TOLERANCE" "1%"
					( Origin gFrontEnd )
				)
				( attribute "VALUE" "1.00K"
					( Origin gFrontEnd )
				)
				( attribute "VER" "2"
					( Origin gFrontEnd )
				)
				( attribute "WATTAGE" "1/16W"
					( Origin gFrontEnd )
				)
				( attribute "XY" "(-7650,1325)"
					( Origin gFrontEnd )
				)
				( attribute "CHIPS_PART_NAME" "RES"
					( Origin gPackager )
				)
				( attribute "CDS_PART_NAME" "RES_0402-1.00K,1%,1/16W,CHIP,GA"
					( Origin gPackager )
				)
				( objectStatus "R3P56" )
				( pin "a"
					( attribute "PN" "1"
						( Origin gPackager )
					)
					( objectStatus "R3P56.1" )
				)
				( pin "b"
					( attribute "PN" "2"
						( Origin gPackager )
					)
					( objectStatus "R3P56.2" )
				)
			)
			( gate "@baseboard_fab2_lib.baseboard_fab2(sch_1):page156_i336"
				( attribute "CDS_LIB" "mstr_discrete"
					( Origin gPackager )
				)
				( attribute "CDS_LOCATION" "R1C35"
					( Origin gPackager )
				)
				( attribute "CDS_SEC" "1"
					( Origin gPackager )
				)
				( attribute "LOCATION" "R1C35"
					( Origin gFrontEnd )
				)
				( attribute "MATERIAL" "EMPTY"
					( Origin gFrontEnd )
				)
				( attribute "PACK_TYPE" "0402"
					( Origin gFrontEnd )
				)
				( attribute "PART_NUMBER" "G21796-027"
					( Origin gFrontEnd )
				)
				( attribute "PHYS_PAGE" "156"
					( Origin gFrontEnd )
				)
				( attribute "ROOM" "CPU1"
					( Origin gFrontEnd )
				)
				( attribute "ROT" "0"
					( Origin gFrontEnd )
				)
				( attribute "SEC" "1"
					( Origin gFrontEnd )
				)
				( attribute "SEC_TYPE" "0402"
					( Origin gFrontEnd )
				)
				( attribute "TOLERANCE" "1%"
					( Origin gFrontEnd )
				)
				( attribute "VALUE" "3.32K"
					( Origin gFrontEnd )
				)
				( attribute "VER" "2"
					( Origin gFrontEnd )
				)
				( attribute "WATTAGE" "1/16W"
					( Origin gFrontEnd )
				)
				( attribute "XY" "(-6025,1725)"
					( Origin gFrontEnd )
				)
				( attribute "CHIPS_PART_NAME" "RES"
					( Origin gPackager )
				)
				( attribute "CDS_PART_NAME" "RES_0402-3.32K,1%,1/16W,EMPTY,A"
					( Origin gPackager )
				)
				( objectStatus "R1C35" )
				( pin "a"
					( attribute "PN" "1"
						( Origin gPackager )
					)
					( objectStatus "R1C35.1" )
				)
				( pin "b"
					( attribute "PN" "2"
						( Origin gPackager )
					)
					( objectStatus "R1C35.2" )
				)
			)
			( gate "@baseboard_fab2_lib.baseboard_fab2(sch_1):page156_i337"
				( attribute "CDS_LIB" "mstr_discrete"
					( Origin gPackager )
				)
				( attribute "CDS_LOCATION" "R1C36"
					( Origin gPackager )
				)
				( attribute "CDS_SEC" "1"
					( Origin gPackager )
				)
				( attribute "LOCATION" "R1C36"
					( Origin gFrontEnd )
				)
				( attribute "MATERIAL" "CHIP"
					( Origin gFrontEnd )
				)
				( attribute "PACK_TYPE" "0402"
					( Origin gFrontEnd )
				)
				( attribute "PART_NUMBER" "G21796-026"
					( Origin gFrontEnd )
				)
				( attribute "PHYS_PAGE" "156"
					( Origin gFrontEnd )
				)
				( attribute "ROOM" "CPU1"
					( Origin gFrontEnd )
				)
				( attribute "ROT" "0"
					( Origin gFrontEnd )
				)
				( attribute "SEC" "1"
					( Origin gFrontEnd )
				)
				( attribute "SEC_TYPE" "0402"
					( Origin gFrontEnd )
				)
				( attribute "TOLERANCE" "1%"
					( Origin gFrontEnd )
				)
				( attribute "VALUE" "1.00K"
					( Origin gFrontEnd )
				)
				( attribute "VER" "2"
					( Origin gFrontEnd )
				)
				( attribute "WATTAGE" "1/16W"
					( Origin gFrontEnd )
				)
				( attribute "XY" "(-6025,1350)"
					( Origin gFrontEnd )
				)
				( attribute "CHIPS_PART_NAME" "RES"
					( Origin gPackager )
				)
				( attribute "CDS_PART_NAME" "RES_0402-1.00K,1%,1/16W,CHIP,GA"
					( Origin gPackager )
				)
				( objectStatus "R1C36" )
				( pin "a"
					( attribute "PN" "1"
						( Origin gPackager )
					)
					( objectStatus "R1C36.1" )
				)
				( pin "b"
					( attribute "PN" "2"
						( Origin gPackager )
					)
					( objectStatus "R1C36.2" )
				)
			)
			( gate "@baseboard_fab2_lib.baseboard_fab2(sch_1):page157_i97"
				( attribute "BOM_COST" "SM_CONTROLLER"
					( Origin gFrontEnd )
				)
				( attribute "CDS_LIB" "mstr_discrete"
					( Origin gPackager )
				)
				( attribute "CDS_LOCATION" "R2N27"
					( Origin gPackager )
				)
				( attribute "CDS_SEC" "1"
					( Origin gPackager )
				)
				( attribute "LOCATION" "R2N27"
					( Origin gFrontEnd )
				)
				( attribute "MATERIAL" "CHIP"
					( Origin gFrontEnd )
				)
				( attribute "PACK_TYPE" "0402"
					( Origin gFrontEnd )
				)
				( attribute "PART_NUMBER" "G21796-072"
					( Origin gFrontEnd )
				)
				( attribute "PHYS_PAGE" "157"
					( Origin gFrontEnd )
				)
				( attribute "ROOM" "BMC_MISC"
					( Origin gFrontEnd )
				)
				( attribute "ROT" "0"
					( Origin gFrontEnd )
				)
				( attribute "SEC" "1"
					( Origin gFrontEnd )
				)
				( attribute "SEC_TYPE" "0402"
					( Origin gFrontEnd )
				)
				( attribute "TOLERANCE" "1%"
					( Origin gFrontEnd )
				)
				( attribute "VALUE" "4.75K"
					( Origin gFrontEnd )
				)
				( attribute "VER" "2"
					( Origin gFrontEnd )
				)
				( attribute "WATTAGE" "1/16W"
					( Origin gFrontEnd )
				)
				( attribute "XY" "(-1850,4025)"
					( Origin gFrontEnd )
				)
				( attribute "CHIPS_PART_NAME" "RES"
					( Origin gPackager )
				)
				( attribute "CDS_PART_NAME" "RES_0402-4.75K,1%,1/16W,CHIP,GA"
					( Origin gPackager )
				)
				( objectStatus "R2N27" )
				( pin "a"
					( attribute "PN" "1"
						( Origin gPackager )
					)
					( objectStatus "R2N27.1" )
				)
				( pin "b"
					( attribute "PN" "2"
						( Origin gPackager )
					)
					( objectStatus "R2N27.2" )
				)
			)
			( gate "@baseboard_fab2_lib.baseboard_fab2(sch_1):page157_i296"
				( attribute "BOM_COST" "SM_CONTROLLER"
					( Origin gFrontEnd )
				)
				( attribute "CDS_LIB" "mstr_discrete"
					( Origin gPackager )
				)
				( attribute "CDS_LOCATION" "R8F23"
					( Origin gPackager )
				)
				( attribute "CDS_SEC" "1"
					( Origin gPackager )
				)
				( attribute "LOCATION" "R8F23"
					( Origin gFrontEnd )
				)
				( attribute "MATERIAL" "CHIP"
					( Origin gFrontEnd )
				)
				( attribute "PACK_TYPE" "0402"
					( Origin gFrontEnd )
				)
				( attribute "PART_NUMBER" "G21796-112"
					( Origin gFrontEnd )
				)
				( attribute "PHYS_PAGE" "157"
					( Origin gFrontEnd )
				)
				( attribute "ROOM" "BMC_MISC"
					( Origin gFrontEnd )
				)
				( attribute "ROT" "0"
					( Origin gFrontEnd )
				)
				( attribute "SEC" "1"
					( Origin gFrontEnd )
				)
				( attribute "SEC_TYPE" "0402"
					( Origin gFrontEnd )
				)
				( attribute "TOLERANCE" "1%"
					( Origin gFrontEnd )
				)
				( attribute "VALUE" "2.21K"
					( Origin gFrontEnd )
				)
				( attribute "VER" "1"
					( Origin gFrontEnd )
				)
				( attribute "WATTAGE" "1/16W"
					( Origin gFrontEnd )
				)
				( attribute "XY" "(-7200,4225)"
					( Origin gFrontEnd )
				)
				( attribute "CHIPS_PART_NAME" "RES"
					( Origin gPackager )
				)
				( attribute "CDS_PART_NAME" "RES_0402-2.21K,1%,1/16W,CHIP,GA"
					( Origin gPackager )
				)
				( objectStatus "R8F23" )
				( pin "a"
					( attribute "PN" "1"
						( Origin gPackager )
					)
					( objectStatus "R8F23.1" )
				)
				( pin "b"
					( attribute "PN" "2"
						( Origin gPackager )
					)
					( objectStatus "R8F23.2" )
				)
			)
			( gate "@baseboard_fab2_lib.baseboard_fab2(sch_1):page157_i298"
				( attribute "BOM_COST" "SM_CONTROLLER"
					( Origin gFrontEnd )
				)
				( attribute "CDS_LIB" "mstr_discrete"
					( Origin gPackager )
				)
				( attribute "CDS_LOCATION" "R2T29"
					( Origin gPackager )
				)
				( attribute "CDS_SEC" "1"
					( Origin gPackager )
				)
				( attribute "LOCATION" "R2T29"
					( Origin gFrontEnd )
				)
				( attribute "MATERIAL" "CHIP"
					( Origin gFrontEnd )
				)
				( attribute "PACK_TYPE" "0402"
					( Origin gFrontEnd )
				)
				( attribute "PART_NUMBER" "G21796-112"
					( Origin gFrontEnd )
				)
				( attribute "PHYS_PAGE" "157"
					( Origin gFrontEnd )
				)
				( attribute "ROOM" "BMC_MISC"
					( Origin gFrontEnd )
				)
				( attribute "ROT" "0"
					( Origin gFrontEnd )
				)
				( attribute "SEC" "1"
					( Origin gFrontEnd )
				)
				( attribute "SEC_TYPE" "0402"
					( Origin gFrontEnd )
				)
				( attribute "TOLERANCE" "1%"
					( Origin gFrontEnd )
				)
				( attribute "VALUE" "2.21K"
					( Origin gFrontEnd )
				)
				( attribute "VER" "1"
					( Origin gFrontEnd )
				)
				( attribute "WATTAGE" "1/16W"
					( Origin gFrontEnd )
				)
				( attribute "XY" "(-7175,3975)"
					( Origin gFrontEnd )
				)
				( attribute "CHIPS_PART_NAME" "RES"
					( Origin gPackager )
				)
				( attribute "CDS_PART_NAME" "RES_0402-2.21K,1%,1/16W,CHIP,GA"
					( Origin gPackager )
				)
				( objectStatus "R2T29" )
				( pin "a"
					( attribute "PN" "1"
						( Origin gPackager )
					)
					( objectStatus "R2T29.1" )
				)
				( pin "b"
					( attribute "PN" "2"
						( Origin gPackager )
					)
					( objectStatus "R2T29.2" )
				)
			)
			( gate "@baseboard_fab2_lib.baseboard_fab2(sch_1):page157_i302"
				( attribute "BOM_COST" "SM_CONTROLLER"
					( Origin gFrontEnd )
				)
				( attribute "CDS_LIB" "mstr_discrete"
					( Origin gPackager )
				)
				( attribute "CDS_LOCATION" "R2N25"
					( Origin gPackager )
				)
				( attribute "CDS_SEC" "1"
					( Origin gPackager )
				)
				( attribute "LOCATION" "R2N25"
					( Origin gFrontEnd )
				)
				( attribute "MATERIAL" "CHIP"
					( Origin gFrontEnd )
				)
				( attribute "PACK_TYPE" "0402"
					( Origin gFrontEnd )
				)
				( attribute "PART_NUMBER" "G21796-208"
					( Origin gFrontEnd )
				)
				( attribute "PHYS_PAGE" "157"
					( Origin gFrontEnd )
				)
				( attribute "ROOM" "BMC_MISC"
					( Origin gFrontEnd )
				)
				( attribute "ROT" "0"
					( Origin gFrontEnd )
				)
				( attribute "SEC" "1"
					( Origin gFrontEnd )
				)
				( attribute "SEC_TYPE" "0402"
					( Origin gFrontEnd )
				)
				( attribute "TOLERANCE" "1.0%"
					( Origin gFrontEnd )
				)
				( attribute "VALUE" "51.1"
					( Origin gFrontEnd )
				)
				( attribute "VER" "1"
					( Origin gFrontEnd )
				)
				( attribute "WATTAGE" "1/16W"
					( Origin gFrontEnd )
				)
				( attribute "XY" "(-2050,3825)"
					( Origin gFrontEnd )
				)
				( attribute "CHIPS_PART_NAME" "RES"
					( Origin gPackager )
				)
				( attribute "CDS_PART_NAME" "RES_0402-51.1,1.0%,1/16W,CHIP,A"
					( Origin gPackager )
				)
				( objectStatus "R2N25" )
				( pin "a"
					( attribute "PN" "1"
						( Origin gPackager )
					)
					( objectStatus "R2N25.1" )
				)
				( pin "b"
					( attribute "PN" "2"
						( Origin gPackager )
					)
					( objectStatus "R2N25.2" )
				)
			)
			( gate "@baseboard_fab2_lib.baseboard_fab2(sch_1):page157_i316"
				( attribute "BOM_COST" "SM_CONTROLLER"
					( Origin gFrontEnd )
				)
				( attribute "CDS_LIB" "mstr_discrete"
					( Origin gPackager )
				)
				( attribute "CDS_LOCATION" "R8F24"
					( Origin gPackager )
				)
				( attribute "CDS_SEC" "1"
					( Origin gPackager )
				)
				( attribute "LOCATION" "R8F24"
					( Origin gFrontEnd )
				)
				( attribute "MATERIAL" "CHIP"
					( Origin gFrontEnd )
				)
				( attribute "PACK_TYPE" "0402"
					( Origin gFrontEnd )
				)
				( attribute "PART_NUMBER" "G21796-072"
					( Origin gFrontEnd )
				)
				( attribute "PHYS_PAGE" "157"
					( Origin gFrontEnd )
				)
				( attribute "ROOM" "BMC_MISC"
					( Origin gFrontEnd )
				)
				( attribute "ROT" "0"
					( Origin gFrontEnd )
				)
				( attribute "SEC" "1"
					( Origin gFrontEnd )
				)
				( attribute "SEC_TYPE" "0402"
					( Origin gFrontEnd )
				)
				( attribute "TOLERANCE" "1%"
					( Origin gFrontEnd )
				)
				( attribute "VALUE" "4.75K"
					( Origin gFrontEnd )
				)
				( attribute "VER" "1"
					( Origin gFrontEnd )
				)
				( attribute "WATTAGE" "1/16W"
					( Origin gFrontEnd )
				)
				( attribute "XY" "(-7175,3725)"
					( Origin gFrontEnd )
				)
				( attribute "CHIPS_PART_NAME" "RES"
					( Origin gPackager )
				)
				( attribute "CDS_PART_NAME" "RES_0402-4.75K,1%,1/16W,CHIP,GA"
					( Origin gPackager )
				)
				( objectStatus "R8F24" )
				( pin "a"
					( attribute "PN" "1"
						( Origin gPackager )
					)
					( objectStatus "R8F24.1" )
				)
				( pin "b"
					( attribute "PN" "2"
						( Origin gPackager )
					)
					( objectStatus "R8F24.2" )
				)
			)
			( gate "@baseboard_fab2_lib.baseboard_fab2(sch_1):page157_i326"
				( attribute "BOM_COST" "PROC_SIDEBAND"
					( Origin gFrontEnd )
				)
				( attribute "CDS_LIB" "mstr_discrete"
					( Origin gPackager )
				)
				( attribute "CDS_LOCATION" "R2T5"
					( Origin gPackager )
				)
				( attribute "CDS_SEC" "1"
					( Origin gPackager )
				)
				( attribute "LOCATION" "R2T5"
					( Origin gFrontEnd )
				)
				( attribute "MATERIAL" "CHIP"
					( Origin gFrontEnd )
				)
				( attribute "PACK_TYPE" "0402"
					( Origin gFrontEnd )
				)
				( attribute "PART_NUMBER" "G21796-026"
					( Origin gFrontEnd )
				)
				( attribute "PHYS_PAGE" "157"
					( Origin gFrontEnd )
				)
				( attribute "ROOM" "PROC_SIDEBAND"
					( Origin gFrontEnd )
				)
				( attribute "ROT" "0"
					( Origin gFrontEnd )
				)
				( attribute "SEC" "1"
					( Origin gFrontEnd )
				)
				( attribute "SEC_TYPE" "0402"
					( Origin gFrontEnd )
				)
				( attribute "TOLERANCE" "1%"
					( Origin gFrontEnd )
				)
				( attribute "VALUE" "1.00K"
					( Origin gFrontEnd )
				)
				( attribute "VER" "2"
					( Origin gFrontEnd )
				)
				( attribute "WATTAGE" "1/16W"
					( Origin gFrontEnd )
				)
				( attribute "XY" "(-6225,1250)"
					( Origin gFrontEnd )
				)
				( attribute "CHIPS_PART_NAME" "RES"
					( Origin gPackager )
				)
				( attribute "CDS_PART_NAME" "RES_0402-1.00K,1%,1/16W,CHIP,GA"
					( Origin gPackager )
				)
				( objectStatus "R2T5" )
				( pin "a"
					( attribute "PN" "1"
						( Origin gPackager )
					)
					( objectStatus "R2T5.1" )
				)
				( pin "b"
					( attribute "PN" "2"
						( Origin gPackager )
					)
					( objectStatus "R2T5.2" )
				)
			)
			( gate "@baseboard_fab2_lib.baseboard_fab2(sch_1):page157_i327"
				( attribute "BOM_COST" "PROC_SIDEBAND"
					( Origin gFrontEnd )
				)
				( attribute "CDS_LIB" "mstr_discrete"
					( Origin gPackager )
				)
				( attribute "CDS_LOCATION" "R2T7"
					( Origin gPackager )
				)
				( attribute "CDS_SEC" "1"
					( Origin gPackager )
				)
				( attribute "LOCATION" "R2T7"
					( Origin gFrontEnd )
				)
				( attribute "MATERIAL" "CHIP"
					( Origin gFrontEnd )
				)
				( attribute "PACK_TYPE" "0402"
					( Origin gFrontEnd )
				)
				( attribute "PART_NUMBER" "G21796-026"
					( Origin gFrontEnd )
				)
				( attribute "PHYS_PAGE" "157"
					( Origin gFrontEnd )
				)
				( attribute "ROOM" "PROC_SIDEBAND"
					( Origin gFrontEnd )
				)
				( attribute "ROT" "0"
					( Origin gFrontEnd )
				)
				( attribute "SEC" "1"
					( Origin gFrontEnd )
				)
				( attribute "SEC_TYPE" "0402"
					( Origin gFrontEnd )
				)
				( attribute "TOLERANCE" "1%"
					( Origin gFrontEnd )
				)
				( attribute "VALUE" "1.00K"
					( Origin gFrontEnd )
				)
				( attribute "VER" "2"
					( Origin gFrontEnd )
				)
				( attribute "WATTAGE" "1/16W"
					( Origin gFrontEnd )
				)
				( attribute "XY" "(-5575,1650)"
					( Origin gFrontEnd )
				)
				( attribute "CHIPS_PART_NAME" "RES"
					( Origin gPackager )
				)
				( attribute "CDS_PART_NAME" "RES_0402-1.00K,1%,1/16W,CHIP,GA"
					( Origin gPackager )
				)
				( objectStatus "R2T7" )
				( pin "a"
					( attribute "PN" "1"
						( Origin gPackager )
					)
					( objectStatus "R2T7.1" )
				)
				( pin "b"
					( attribute "PN" "2"
						( Origin gPackager )
					)
					( objectStatus "R2T7.2" )
				)
			)
			( gate "@baseboard_fab2_lib.baseboard_fab2(sch_1):page157_i330"
				( attribute "BOM_COST" "PROC_SIDEBAND"
					( Origin gFrontEnd )
				)
				( attribute "CDS_LIB" "mstr_discrete"
					( Origin gPackager )
				)
				( attribute "CDS_LOCATION" "Q2T1"
					( Origin gPackager )
				)
				( attribute "CDS_SEC" "1"
					( Origin gPackager )
				)
				( attribute "LOCATION" "Q2T1"
					( Origin gFrontEnd )
				)
				( attribute "MATERIAL" "IC"
					( Origin gFrontEnd )
				)
				( attribute "PACK_TYPE" "SM"
					( Origin gFrontEnd )
				)
				( attribute "PART_NUMBER" "C52245-001"
					( Origin gFrontEnd )
				)
				( attribute "PHYS_PAGE" "157"
					( Origin gFrontEnd )
				)
				( attribute "ROOM" "PROC_SIDEBAND"
					( Origin gFrontEnd )
				)
				( attribute "ROT" "0"
					( Origin gFrontEnd )
				)
				( attribute "SEC" "1"
					( Origin gFrontEnd )
				)
				( attribute "SEC_TYPE" "SM"
					( Origin gFrontEnd )
				)
				( attribute "VALUE" "MMBT3904"
					( Origin gFrontEnd )
				)
				( attribute "VER" "1"
					( Origin gFrontEnd )
				)
				( attribute "XY" "(-6275,775)"
					( Origin gFrontEnd )
				)
				( attribute "CHIPS_PART_NAME" "NPN"
					( Origin gPackager )
				)
				( attribute "CDS_PART_NAME" "NPN_SM-MMBT3904,IC,C52245-001"
					( Origin gPackager )
				)
				( objectStatus "Q2T1" )
				( pin "b"
					( attribute "PN" "1"
						( Origin gPackager )
					)
					( objectStatus "Q2T1.1" )
				)
				( pin "c"
					( attribute "PN" "3"
						( Origin gPackager )
					)
					( objectStatus "Q2T1.3" )
				)
				( pin "e"
					( attribute "PN" "2"
						( Origin gPackager )
					)
					( objectStatus "Q2T1.2" )
				)
			)
			( gate "@baseboard_fab2_lib.baseboard_fab2(sch_1):page157_i335"
				( attribute "BOM_COST" "SM_CONTROLLER"
					( Origin gFrontEnd )
				)
				( attribute "CDS_LIB" "mstr_discrete"
					( Origin gPackager )
				)
				( attribute "CDS_LOCATION" "R8D25"
					( Origin gPackager )
				)
				( attribute "CDS_SEC" "1"
					( Origin gPackager )
				)
				( attribute "LOCATION" "R8D25"
					( Origin gFrontEnd )
				)
				( attribute "MATERIAL" "CHIP"
					( Origin gFrontEnd )
				)
				( attribute "PACK_TYPE" "0402"
					( Origin gFrontEnd )
				)
				( attribute "PART_NUMBER" "G21796-072"
					( Origin gFrontEnd )
				)
				( attribute "PHYS_PAGE" "157"
					( Origin gFrontEnd )
				)
				( attribute "ROOM" "BMC_MISC"
					( Origin gFrontEnd )
				)
				( attribute "ROT" "0"
					( Origin gFrontEnd )
				)
				( attribute "SEC" "1"
					( Origin gFrontEnd )
				)
				( attribute "SEC_TYPE" "0402"
					( Origin gFrontEnd )
				)
				( attribute "TOLERANCE" "1%"
					( Origin gFrontEnd )
				)
				( attribute "VALUE" "4.75K"
					( Origin gFrontEnd )
				)
				( attribute "VER" "2"
					( Origin gFrontEnd )
				)
				( attribute "WATTAGE" "1/16W"
					( Origin gFrontEnd )
				)
				( attribute "XY" "(-2275,1525)"
					( Origin gFrontEnd )
				)
				( attribute "CHIPS_PART_NAME" "RES"
					( Origin gPackager )
				)
				( attribute "CDS_PART_NAME" "RES_0402-4.75K,1%,1/16W,CHIP,GA"
					( Origin gPackager )
				)
				( objectStatus "R8D25" )
				( pin "a"
					( attribute "PN" "1"
						( Origin gPackager )
					)
					( objectStatus "R8D25.1" )
				)
				( pin "b"
					( attribute "PN" "2"
						( Origin gPackager )
					)
					( objectStatus "R8D25.2" )
				)
			)
			( gate "@baseboard_fab2_lib.baseboard_fab2(sch_1):page157_i340"
				( attribute "BOM_COST" "PROC_SIDEBAND"
					( Origin gFrontEnd )
				)
				( attribute "CDS_LIB" "mstr_discrete"
					( Origin gPackager )
				)
				( attribute "CDS_LOCATION" "Q2T2"
					( Origin gPackager )
				)
				( attribute "CDS_SEC" "1"
					( Origin gPackager )
				)
				( attribute "LOCATION" "Q2T2"
					( Origin gFrontEnd )
				)
				( attribute "MATERIAL" "FET"
					( Origin gFrontEnd )
				)
				( attribute "PACK_TYPE" "SOT23LF"
					( Origin gFrontEnd )
				)
				( attribute "PART_NUMBER" "C79254-001"
					( Origin gFrontEnd )
				)
				( attribute "PHYS_PAGE" "157"
					( Origin gFrontEnd )
				)
				( attribute "ROOM" "PROC_SIDEBAND"
					( Origin gFrontEnd )
				)
				( attribute "ROT" "0"
					( Origin gFrontEnd )
				)
				( attribute "SEC" "1"
					( Origin gFrontEnd )
				)
				( attribute "SEC_TYPE" "SOT23LF"
					( Origin gFrontEnd )
				)
				( attribute "VALUE" "2N7002"
					( Origin gFrontEnd )
				)
				( attribute "VER" "8"
					( Origin gFrontEnd )
				)
				( attribute "XY" "(-5575,1100)"
					( Origin gFrontEnd )
				)
				( attribute "CHIPS_PART_NAME" "FET_N"
					( Origin gPackager )
				)
				( attribute "CDS_PART_NAME" "FET_N_SOT23LF-2N7002,FET,C7925A"
					( Origin gPackager )
				)
				( objectStatus "Q2T2" )
				( pin "drn"
					( attribute "PN" "3"
						( Origin gPackager )
					)
					( objectStatus "Q2T2.3" )
				)
				( pin "gate"
					( attribute "PN" "1"
						( Origin gPackager )
					)
					( objectStatus "Q2T2.1" )
				)
				( pin "src"
					( attribute "PN" "2"
						( Origin gPackager )
					)
					( objectStatus "Q2T2.2" )
				)
			)
			( gate "@baseboard_fab2_lib.baseboard_fab2(sch_1):page157_i342"
				( attribute "BOM_COST" "SM_CONTROLLER"
					( Origin gFrontEnd )
				)
				( attribute "CDS_LIB" "mstr_discrete"
					( Origin gPackager )
				)
				( attribute "CDS_LOCATION" "R3N12"
					( Origin gPackager )
				)
				( attribute "CDS_SEC" "1"
					( Origin gPackager )
				)
				( attribute "LOCATION" "R3N12"
					( Origin gFrontEnd )
				)
				( attribute "MATERIAL" "CHIP"
					( Origin gFrontEnd )
				)
				( attribute "PACK_TYPE" "0402"
					( Origin gFrontEnd )
				)
				( attribute "PART_NUMBER" "G21796-072"
					( Origin gFrontEnd )
				)
				( attribute "PHYS_PAGE" "157"
					( Origin gFrontEnd )
				)
				( attribute "ROOM" "BMC_MISC"
					( Origin gFrontEnd )
				)
				( attribute "ROT" "0"
					( Origin gFrontEnd )
				)
				( attribute "SEC" "1"
					( Origin gFrontEnd )
				)
				( attribute "SEC_TYPE" "0402"
					( Origin gFrontEnd )
				)
				( attribute "TOLERANCE" "1%"
					( Origin gFrontEnd )
				)
				( attribute "VALUE" "4.75K"
					( Origin gFrontEnd )
				)
				( attribute "VER" "1"
					( Origin gFrontEnd )
				)
				( attribute "WATTAGE" "1/16W"
					( Origin gFrontEnd )
				)
				( attribute "XY" "(-7175,3100)"
					( Origin gFrontEnd )
				)
				( attribute "CHIPS_PART_NAME" "RES"
					( Origin gPackager )
				)
				( attribute "CDS_PART_NAME" "RES_0402-4.75K,1%,1/16W,CHIP,GA"
					( Origin gPackager )
				)
				( objectStatus "R3N12" )
				( pin "a"
					( attribute "PN" "1"
						( Origin gPackager )
					)
					( objectStatus "R3N12.1" )
				)
				( pin "b"
					( attribute "PN" "2"
						( Origin gPackager )
					)
					( objectStatus "R3N12.2" )
				)
			)
			( gate "@baseboard_fab2_lib.baseboard_fab2(sch_1):page157_i344"
				( attribute "BOM_COST" "SM_CONTROLLER"
					( Origin gFrontEnd )
				)
				( attribute "CDS_LIB" "mstr_discrete"
					( Origin gPackager )
				)
				( attribute "CDS_LOCATION" "R3N11"
					( Origin gPackager )
				)
				( attribute "CDS_SEC" "1"
					( Origin gPackager )
				)
				( attribute "LOCATION" "R3N11"
					( Origin gFrontEnd )
				)
				( attribute "MATERIAL" "CHIP"
					( Origin gFrontEnd )
				)
				( attribute "PACK_TYPE" "0402"
					( Origin gFrontEnd )
				)
				( attribute "PART_NUMBER" "G21796-072"
					( Origin gFrontEnd )
				)
				( attribute "PHYS_PAGE" "157"
					( Origin gFrontEnd )
				)
				( attribute "ROOM" "BMC_MISC"
					( Origin gFrontEnd )
				)
				( attribute "ROT" "0"
					( Origin gFrontEnd )
				)
				( attribute "SEC" "1"
					( Origin gFrontEnd )
				)
				( attribute "SEC_TYPE" "0402"
					( Origin gFrontEnd )
				)
				( attribute "TOLERANCE" "1%"
					( Origin gFrontEnd )
				)
				( attribute "VALUE" "4.75K"
					( Origin gFrontEnd )
				)
				( attribute "VER" "1"
					( Origin gFrontEnd )
				)
				( attribute "WATTAGE" "1/16W"
					( Origin gFrontEnd )
				)
				( attribute "XY" "(-7175,2875)"
					( Origin gFrontEnd )
				)
				( attribute "CHIPS_PART_NAME" "RES"
					( Origin gPackager )
				)
				( attribute "CDS_PART_NAME" "RES_0402-4.75K,1%,1/16W,CHIP,GA"
					( Origin gPackager )
				)
				( objectStatus "R3N11" )
				( pin "a"
					( attribute "PN" "1"
						( Origin gPackager )
					)
					( objectStatus "R3N11.1" )
				)
				( pin "b"
					( attribute "PN" "2"
						( Origin gPackager )
					)
					( objectStatus "R3N11.2" )
				)
			)
			( gate "@baseboard_fab2_lib.baseboard_fab2(sch_1):page157_i346"
				( attribute "BOM_COST" "SM_CONTROLLER"
					( Origin gFrontEnd )
				)
				( attribute "CDS_LIB" "mstr_discrete"
					( Origin gPackager )
				)
				( attribute "CDS_LOCATION" "R2M2"
					( Origin gPackager )
				)
				( attribute "CDS_SEC" "1"
					( Origin gPackager )
				)
				( attribute "LOCATION" "R2M2"
					( Origin gFrontEnd )
				)
				( attribute "MATERIAL" "CHIP"
					( Origin gFrontEnd )
				)
				( attribute "PACK_TYPE" "0402"
					( Origin gFrontEnd )
				)
				( attribute "PART_NUMBER" "G21796-072"
					( Origin gFrontEnd )
				)
				( attribute "PHYS_PAGE" "157"
					( Origin gFrontEnd )
				)
				( attribute "ROOM" "BMC_MISC"
					( Origin gFrontEnd )
				)
				( attribute "ROT" "0"
					( Origin gFrontEnd )
				)
				( attribute "SEC" "1"
					( Origin gFrontEnd )
				)
				( attribute "SEC_TYPE" "0402"
					( Origin gFrontEnd )
				)
				( attribute "TOLERANCE" "1%"
					( Origin gFrontEnd )
				)
				( attribute "VALUE" "4.75K"
					( Origin gFrontEnd )
				)
				( attribute "VER" "1"
					( Origin gFrontEnd )
				)
				( attribute "WATTAGE" "1/16W"
					( Origin gFrontEnd )
				)
				( attribute "XY" "(-7175,2650)"
					( Origin gFrontEnd )
				)
				( attribute "CHIPS_PART_NAME" "RES"
					( Origin gPackager )
				)
				( attribute "CDS_PART_NAME" "RES_0402-4.75K,1%,1/16W,CHIP,GA"
					( Origin gPackager )
				)
				( objectStatus "R2M2" )
				( pin "a"
					( attribute "PN" "1"
						( Origin gPackager )
					)
					( objectStatus "R2M2.1" )
				)
				( pin "b"
					( attribute "PN" "2"
						( Origin gPackager )
					)
					( objectStatus "R2M2.2" )
				)
			)
			( gate "@baseboard_fab2_lib.baseboard_fab2(sch_1):page157_i348"
				( attribute "BOM_COST" "SM_CONTROLLER"
					( Origin gFrontEnd )
				)
				( attribute "CDS_LIB" "mstr_discrete"
					( Origin gPackager )
				)
				( attribute "CDS_LOCATION" "R2M5"
					( Origin gPackager )
				)
				( attribute "CDS_SEC" "1"
					( Origin gPackager )
				)
				( attribute "LOCATION" "R2M5"
					( Origin gFrontEnd )
				)
				( attribute "MATERIAL" "CHIP"
					( Origin gFrontEnd )
				)
				( attribute "PACK_TYPE" "0402"
					( Origin gFrontEnd )
				)
				( attribute "PART_NUMBER" "G21796-072"
					( Origin gFrontEnd )
				)
				( attribute "PHYS_PAGE" "157"
					( Origin gFrontEnd )
				)
				( attribute "ROOM" "BMC_MISC"
					( Origin gFrontEnd )
				)
				( attribute "ROT" "0"
					( Origin gFrontEnd )
				)
				( attribute "SEC" "1"
					( Origin gFrontEnd )
				)
				( attribute "SEC_TYPE" "0402"
					( Origin gFrontEnd )
				)
				( attribute "TOLERANCE" "1%"
					( Origin gFrontEnd )
				)
				( attribute "VALUE" "4.75K"
					( Origin gFrontEnd )
				)
				( attribute "VER" "1"
					( Origin gFrontEnd )
				)
				( attribute "WATTAGE" "1/16W"
					( Origin gFrontEnd )
				)
				( attribute "XY" "(-7175,2425)"
					( Origin gFrontEnd )
				)
				( attribute "CHIPS_PART_NAME" "RES"
					( Origin gPackager )
				)
				( attribute "CDS_PART_NAME" "RES_0402-4.75K,1%,1/16W,CHIP,GA"
					( Origin gPackager )
				)
				( objectStatus "R2M5" )
				( pin "a"
					( attribute "PN" "1"
						( Origin gPackager )
					)
					( objectStatus "R2M5.1" )
				)
				( pin "b"
					( attribute "PN" "2"
						( Origin gPackager )
					)
					( objectStatus "R2M5.2" )
				)
			)
			( gate "@baseboard_fab2_lib.baseboard_fab2(sch_1):page157_i351"
				( attribute "BOM_COST" "MIO_CHASSIS"
					( Origin gFrontEnd )
				)
				( attribute "CDS_LIB" "mstr_misc"
					( Origin gPackager )
				)
				( attribute "CDS_LOCATION" "S8E1"
					( Origin gPackager )
				)
				( attribute "CDS_SEC" "1"
					( Origin gPackager )
				)
				( attribute "LOCATION" "S8E1"
					( Origin gFrontEnd )
				)
				( attribute "MATERIAL" "IC"
					( Origin gFrontEnd )
				)
				( attribute "PACK_TYPE" "SMLF"
					( Origin gFrontEnd )
				)
				( attribute "PART_NAME" "SWITCH_D90553001"
					( Origin gFrontEnd )
				)
				( attribute "PART_NUMBER" "D90553-001"
					( Origin gFrontEnd )
				)
				( attribute "PHYS_PAGE" "157"
					( Origin gFrontEnd )
				)
				( attribute "ROOM" "MIO_CHASSIS"
					( Origin gFrontEnd )
				)
				( attribute "ROT" "0"
					( Origin gFrontEnd )
				)
				( attribute "SEC" "1"
					( Origin gFrontEnd )
				)
				( attribute "SEC_TYPE" "SMLF"
					( Origin gFrontEnd )
				)
				( attribute "VER" "1"
					( Origin gFrontEnd )
				)
				( attribute "XY" "(-4375,2375)"
					( Origin gFrontEnd )
				)
				( attribute "CHIPS_PART_NAME" "SWITCH_D90553001"
					( Origin gPackager )
				)
				( attribute "CDS_PART_NAME" "SWITCH_D90553001_SMLF-IC,D9055A"
					( Origin gPackager )
				)
				( objectStatus "S8E1" )
				( pin "a"
					( attribute "PN" "1"
						( Origin gPackager )
					)
					( objectStatus "S8E1.1" )
				)
				( pin "b"
					( attribute "PN" "2"
						( Origin gPackager )
					)
					( objectStatus "S8E1.2" )
				)
			)
			( gate "@baseboard_fab2_lib.baseboard_fab2(sch_1):page157_i352"
				( attribute "BOM_COST" "MIO_CHASSIS"
					( Origin gFrontEnd )
				)
				( attribute "CDS_LIB" "mstr_discrete"
					( Origin gPackager )
				)
				( attribute "CDS_LOCATION" "R2R9"
					( Origin gPackager )
				)
				( attribute "CDS_SEC" "1"
					( Origin gPackager )
				)
				( attribute "LOCATION" "R2R9"
					( Origin gFrontEnd )
				)
				( attribute "MATERIAL" "CHIP"
					( Origin gFrontEnd )
				)
				( attribute "PACK_TYPE" "0402"
					( Origin gFrontEnd )
				)
				( attribute "PART_NUMBER" "G21796-004"
					( Origin gFrontEnd )
				)
				( attribute "PHYS_PAGE" "157"
					( Origin gFrontEnd )
				)
				( attribute "ROOM" "MIO_CHASSIS"
					( Origin gFrontEnd )
				)
				( attribute "ROT" "0"
					( Origin gFrontEnd )
				)
				( attribute "SEC" "1"
					( Origin gFrontEnd )
				)
				( attribute "SEC_TYPE" "0402"
					( Origin gFrontEnd )
				)
				( attribute "TOLERANCE" "1%"
					( Origin gFrontEnd )
				)
				( attribute "VALUE" "200.0"
					( Origin gFrontEnd )
				)
				( attribute "VER" "1"
					( Origin gFrontEnd )
				)
				( attribute "WATTAGE" "1/16W"
					( Origin gFrontEnd )
				)
				( attribute "XY" "(-3650,2375)"
					( Origin gFrontEnd )
				)
				( attribute "CHIPS_PART_NAME" "RES"
					( Origin gPackager )
				)
				( attribute "CDS_PART_NAME" "RES_0402-200.0,1%,1/16W,CHIP,GA"
					( Origin gPackager )
				)
				( objectStatus "R2R9" )
				( pin "a"
					( attribute "PN" "1"
						( Origin gPackager )
					)
					( objectStatus "R2R9.1" )
				)
				( pin "b"
					( attribute "PN" "2"
						( Origin gPackager )
					)
					( objectStatus "R2R9.2" )
				)
			)
			( gate "@baseboard_fab2_lib.baseboard_fab2(sch_1):page157_i353"
				( attribute "BOM_COST" "MIO_CHASSIS"
					( Origin gFrontEnd )
				)
				( attribute "CDS_LIB" "dev_discrete"
					( Origin gPackager )
				)
				( attribute "CDS_LOCATION" "C2R12"
					( Origin gPackager )
				)
				( attribute "CDS_SEC" "1"
					( Origin gPackager )
				)
				( attribute "LOCATION" "C2R12"
					( Origin gFrontEnd )
				)
				( attribute "MATERIAL" "X6S"
					( Origin gFrontEnd )
				)
				( attribute "PACK_TYPE" "0402V"
					( Origin gFrontEnd )
				)
				( attribute "PART_NUMBER" "D97712-004"
					( Origin gFrontEnd )
				)
				( attribute "PHYS_PAGE" "157"
					( Origin gFrontEnd )
				)
				( attribute "ROOM" "MIO_CHASSIS"
					( Origin gFrontEnd )
				)
				( attribute "ROT" "0"
					( Origin gFrontEnd )
				)
				( attribute "SEC" "1"
					( Origin gFrontEnd )
				)
				( attribute "SEC_TYPE" "0402V"
					( Origin gFrontEnd )
				)
				( attribute "TOLERANCE" "10%"
					( Origin gFrontEnd )
				)
				( attribute "VALUE" "1.0UF"
					( Origin gFrontEnd )
				)
				( attribute "VER" "1"
					( Origin gFrontEnd )
				)
				( attribute "VOLTAGE" "6.3V"
					( Units "uVoltage" "V" 1.000000)
					( Origin gFrontEnd )
				)
				( attribute "XY" "(-3200,2150)"
					( Origin gFrontEnd )
				)
				( attribute "CHIPS_PART_NAME" "CAP_A"
					( Origin gPackager )
				)
				( attribute "CDS_PART_NAME" "CAP_A_0402V-1.0UF,6.3V,10%,X6SA"
					( Origin gPackager )
				)
				( objectStatus "C2R12" )
				( pin "a"
					( attribute "PN" "1"
						( Origin gPackager )
					)
					( objectStatus "C2R12.1" )
				)
				( pin "b"
					( attribute "PN" "2"
						( Origin gPackager )
					)
					( objectStatus "C2R12.2" )
				)
			)
			( gate "@baseboard_fab2_lib.baseboard_fab2(sch_1):page157_i356"
				( attribute "BOM_COST" "MIO_CHASSIS"
					( Origin gFrontEnd )
				)
				( attribute "CDS_LIB" "mstr_ttl"
					( Origin gPackager )
				)
				( attribute "CDS_LOCATION" "U2R1"
					( Origin gPackager )
				)
				( attribute "CDS_SEC" "2"
					( Origin gPackager )
				)
				( attribute "LOCATION" "U2R1"
					( Origin gFrontEnd )
				)
				( attribute "MATERIAL" "IC"
					( Origin gFrontEnd )
				)
				( attribute "PACK_TYPE" "SMLF"
					( Origin gFrontEnd )
				)
				( attribute "PART_NUMBER" "D18476-001"
					( Origin gFrontEnd )
				)
				( attribute "PHYS_PAGE" "157"
					( Origin gFrontEnd )
				)
				( attribute "ROOM" "MIO_CHASSIS"
					( Origin gFrontEnd )
				)
				( attribute "ROT" "0"
					( Origin gFrontEnd )
				)
				( attribute "SEC" "2"
					( Origin gFrontEnd )
				)
				( attribute "SEC_TYPE" "SMLF"
					( Origin gFrontEnd )
				)
				( attribute "VALUE" "74LVC2G14"
					( Origin gFrontEnd )
				)
				( attribute "VER" "1"
					( Origin gFrontEnd )
				)
				( attribute "XY" "(-2900,2375)"
					( Origin gFrontEnd )
				)
				( attribute "CHIPS_PART_NAME" "TTL2G14"
					( Origin gPackager )
				)
				( attribute "CDS_PART_NAME" "TTL2G14_SMLF-74LVC2G14,IC,D184B"
					( Origin gPackager )
				)
				( objectStatus "U2R1" )
				( pin "a(0)"
					( attribute "PN" "3"
						( Origin gPackager )
					)
					( objectStatus "U2R1.3" )
				)
				( pin "y(0)"
					( attribute "PN" "4"
						( Origin gPackager )
					)
					( objectStatus "U2R1.4" )
				)
			)
			( gate "@baseboard_fab2_lib.baseboard_fab2(sch_1):page157_i357"
				( attribute "BOM_COST" "MIO_CHASSIS"
					( Origin gFrontEnd )
				)
				( attribute "CDS_LIB" "mstr_ttl"
					( Origin gPackager )
				)
				( attribute "CDS_LOCATION" "U2R1"
					( Origin gPackager )
				)
				( attribute "CDS_SEC" "1"
					( Origin gPackager )
				)
				( attribute "LOCATION" "U2R1"
					( Origin gFrontEnd )
				)
				( attribute "MATERIAL" "IC"
					( Origin gFrontEnd )
				)
				( attribute "PACK_TYPE" "SMLF"
					( Origin gFrontEnd )
				)
				( attribute "PART_NUMBER" "D18476-001"
					( Origin gFrontEnd )
				)
				( attribute "PHYS_PAGE" "157"
					( Origin gFrontEnd )
				)
				( attribute "ROOM" "MIO_CHASSIS"
					( Origin gFrontEnd )
				)
				( attribute "ROT" "0"
					( Origin gFrontEnd )
				)
				( attribute "SEC" "1"
					( Origin gFrontEnd )
				)
				( attribute "SEC_TYPE" "SMLF"
					( Origin gFrontEnd )
				)
				( attribute "VALUE" "74LVC2G14"
					( Origin gFrontEnd )
				)
				( attribute "VER" "1"
					( Origin gFrontEnd )
				)
				( attribute "XY" "(-2150,2375)"
					( Origin gFrontEnd )
				)
				( attribute "CHIPS_PART_NAME" "TTL2G14"
					( Origin gPackager )
				)
				( attribute "CDS_PART_NAME" "TTL2G14_SMLF-74LVC2G14,IC,D184B"
					( Origin gPackager )
				)
				( objectStatus "U2R1" )
				( pin "a(0)"
					( attribute "PN" "1"
						( Origin gPackager )
					)
					( objectStatus "U2R1.1" )
				)
				( pin "y(0)"
					( attribute "PN" "6"
						( Origin gPackager )
					)
					( objectStatus "U2R1.6" )
				)
			)
			( gate "@baseboard_fab2_lib.baseboard_fab2(sch_1):page157_i358"
				( attribute "BOM_COST" "MIO_CHASSIS"
					( Origin gFrontEnd )
				)
				( attribute "CDS_LIB" "mstr_discrete"
					( Origin gPackager )
				)
				( attribute "CDS_LOCATION" "R2R10"
					( Origin gPackager )
				)
				( attribute "CDS_SEC" "1"
					( Origin gPackager )
				)
				( attribute "LOCATION" "R2R10"
					( Origin gFrontEnd )
				)
				( attribute "MATERIAL" "CHIP"
					( Origin gFrontEnd )
				)
				( attribute "PACK_TYPE" "0402"
					( Origin gFrontEnd )
				)
				( attribute "PART_NUMBER" "G21796-074"
					( Origin gFrontEnd )
				)
				( attribute "PHYS_PAGE" "157"
					( Origin gFrontEnd )
				)
				( attribute "ROOM" "MIO_CHASSIS"
					( Origin gFrontEnd )
				)
				( attribute "ROT" "0"
					( Origin gFrontEnd )
				)
				( attribute "SEC" "1"
					( Origin gFrontEnd )
				)
				( attribute "SEC_TYPE" "0402"
					( Origin gFrontEnd )
				)
				( attribute "TOLERANCE" "1%"
					( Origin gFrontEnd )
				)
				( attribute "VALUE" "33.2"
					( Origin gFrontEnd )
				)
				( attribute "VER" "1"
					( Origin gFrontEnd )
				)
				( attribute "WATTAGE" "1/16W"
					( Origin gFrontEnd )
				)
				( attribute "XY" "(-1400,2375)"
					( Origin gFrontEnd )
				)
				( attribute "CHIPS_PART_NAME" "RES"
					( Origin gPackager )
				)
				( attribute "CDS_PART_NAME" "RES_0402-33.2,1%,1/16W,CHIP,G2A"
					( Origin gPackager )
				)
				( objectStatus "R2R10" )
				( pin "a"
					( attribute "PN" "1"
						( Origin gPackager )
					)
					( objectStatus "R2R10.1" )
				)
				( pin "b"
					( attribute "PN" "2"
						( Origin gPackager )
					)
					( objectStatus "R2R10.2" )
				)
			)
			( gate "@baseboard_fab2_lib.baseboard_fab2(sch_1):page157_i361"
				( attribute "BOM_COST" "SM_CONTROLLER"
					( Origin gFrontEnd )
				)
				( attribute "CDS_LIB" "mstr_discrete"
					( Origin gPackager )
				)
				( attribute "CDS_LOCATION" "R8E19"
					( Origin gPackager )
				)
				( attribute "CDS_SEC" "1"
					( Origin gPackager )
				)
				( attribute "LOCATION" "R8E19"
					( Origin gFrontEnd )
				)
				( attribute "MATERIAL" "EMPTY"
					( Origin gFrontEnd )
				)
				( attribute "PACK_TYPE" "0402"
					( Origin gFrontEnd )
				)
				( attribute "PART_NUMBER" "G21796-072"
					( Origin gFrontEnd )
				)
				( attribute "PHYS_PAGE" "157"
					( Origin gFrontEnd )
				)
				( attribute "ROOM" "BMC_MISC"
					( Origin gFrontEnd )
				)
				( attribute "ROT" "0"
					( Origin gFrontEnd )
				)
				( attribute "SEC" "1"
					( Origin gFrontEnd )
				)
				( attribute "SEC_TYPE" "0402"
					( Origin gFrontEnd )
				)
				( attribute "TOLERANCE" "1%"
					( Origin gFrontEnd )
				)
				( attribute "VALUE" "4.75K"
					( Origin gFrontEnd )
				)
				( attribute "VER" "1"
					( Origin gFrontEnd )
				)
				( attribute "WATTAGE" "1/16W"
					( Origin gFrontEnd )
				)
				( attribute "XY" "(-7175,2200)"
					( Origin gFrontEnd )
				)
				( attribute "CHIPS_PART_NAME" "RES"
					( Origin gPackager )
				)
				( attribute "CDS_PART_NAME" "RES_0402-4.75K,1%,1/16W,EMPTY,A"
					( Origin gPackager )
				)
				( objectStatus "R8E19" )
				( pin "a"
					( attribute "PN" "1"
						( Origin gPackager )
					)
					( objectStatus "R8E19.1" )
				)
				( pin "b"
					( attribute "PN" "2"
						( Origin gPackager )
					)
					( objectStatus "R8E19.2" )
				)
			)
			( gate "@baseboard_fab2_lib.baseboard_fab2(sch_1):page157_i367"
				( attribute "BOM_COST" "SM_CONTROLLER"
					( Origin gFrontEnd )
				)
				( attribute "CDS_LIB" "mstr_discrete"
					( Origin gPackager )
				)
				( attribute "CDS_LOCATION" "R2U4"
					( Origin gPackager )
				)
				( attribute "CDS_SEC" "1"
					( Origin gPackager )
				)
				( attribute "LOCATION" "R2U4"
					( Origin gFrontEnd )
				)
				( attribute "MATERIAL" "CHIP"
					( Origin gFrontEnd )
				)
				( attribute "PACK_TYPE" "0402"
					( Origin gFrontEnd )
				)
				( attribute "PART_NUMBER" "G21796-072"
					( Origin gFrontEnd )
				)
				( attribute "PHYS_PAGE" "157"
					( Origin gFrontEnd )
				)
				( attribute "ROOM" "BMC_MISC"
					( Origin gFrontEnd )
				)
				( attribute "ROT" "0"
					( Origin gFrontEnd )
				)
				( attribute "SEC" "1"
					( Origin gFrontEnd )
				)
				( attribute "SEC_TYPE" "0402"
					( Origin gFrontEnd )
				)
				( attribute "TOLERANCE" "1%"
					( Origin gFrontEnd )
				)
				( attribute "VALUE" "4.75K"
					( Origin gFrontEnd )
				)
				( attribute "VER" "1"
					( Origin gFrontEnd )
				)
				( attribute "WATTAGE" "1/16W"
					( Origin gFrontEnd )
				)
				( attribute "XY" "(-4925,4025)"
					( Origin gFrontEnd )
				)
				( attribute "CHIPS_PART_NAME" "RES"
					( Origin gPackager )
				)
				( attribute "CDS_PART_NAME" "RES_0402-4.75K,1%,1/16W,CHIP,GA"
					( Origin gPackager )
				)
				( objectStatus "R2U4" )
				( pin "a"
					( attribute "PN" "1"
						( Origin gPackager )
					)
					( objectStatus "R2U4.1" )
				)
				( pin "b"
					( attribute "PN" "2"
						( Origin gPackager )
					)
					( objectStatus "R2U4.2" )
				)
			)
			( gate "@baseboard_fab2_lib.baseboard_fab2(sch_1):page157_i368"
				( attribute "BOM_COST" "MIO_CHASSIS"
					( Origin gFrontEnd )
				)
				( attribute "CDS_LIB" "mstr_discrete"
					( Origin gPackager )
				)
				( attribute "CDS_LOCATION" "R4R1"
					( Origin gPackager )
				)
				( attribute "CDS_SEC" "1"
					( Origin gPackager )
				)
				( attribute "LOCATION" "R4R1"
					( Origin gFrontEnd )
				)
				( attribute "MATERIAL" "CHIP"
					( Origin gFrontEnd )
				)
				( attribute "PACK_TYPE" "0402"
					( Origin gFrontEnd )
				)
				( attribute "PART_NUMBER" "G21796-026"
					( Origin gFrontEnd )
				)
				( attribute "PHYS_PAGE" "157"
					( Origin gFrontEnd )
				)
				( attribute "ROOM" "MIO_CHASSIS"
					( Origin gFrontEnd )
				)
				( attribute "ROT" "0"
					( Origin gFrontEnd )
				)
				( attribute "SEC" "1"
					( Origin gFrontEnd )
				)
				( attribute "SEC_TYPE" "0402"
					( Origin gFrontEnd )
				)
				( attribute "TOLERANCE" "1%"
					( Origin gFrontEnd )
				)
				( attribute "VALUE" "1.00K"
					( Origin gFrontEnd )
				)
				( attribute "VER" "1"
					( Origin gFrontEnd )
				)
				( attribute "WATTAGE" "1/16W"
					( Origin gFrontEnd )
				)
				( attribute "XY" "(-6975,775)"
					( Origin gFrontEnd )
				)
				( attribute "CHIPS_PART_NAME" "RES"
					( Origin gPackager )
				)
				( attribute "CDS_PART_NAME" "RES_0402-1.00K,1%,1/16W,CHIP,GA"
					( Origin gPackager )
				)
				( objectStatus "R4R1" )
				( pin "a"
					( attribute "PN" "1"
						( Origin gPackager )
					)
					( objectStatus "R4R1.1" )
				)
				( pin "b"
					( attribute "PN" "2"
						( Origin gPackager )
					)
					( objectStatus "R4R1.2" )
				)
			)
			( gate "@baseboard_fab2_lib.baseboard_fab2(sch_1):page157_i370"
				( attribute "BOM_COST" "MIO_CHASSIS"
					( Origin gFrontEnd )
				)
				( attribute "CDS_LIB" "dev_discrete"
					( Origin gPackager )
				)
				( attribute "CDS_LOCATION" "C2T3"
					( Origin gPackager )
				)
				( attribute "CDS_SEC" "1"
					( Origin gPackager )
				)
				( attribute "LOCATION" "C2T3"
					( Origin gFrontEnd )
				)
				( attribute "MATERIAL" "X7R"
					( Origin gFrontEnd )
				)
				( attribute "PACK_TYPE" "0402V"
					( Origin gFrontEnd )
				)
				( attribute "PART_NUMBER" "A36096-030"
					( Origin gFrontEnd )
				)
				( attribute "PHYS_PAGE" "157"
					( Origin gFrontEnd )
				)
				( attribute "ROOM" "MIO_CHASSIS"
					( Origin gFrontEnd )
				)
				( attribute "ROT" "0"
					( Origin gFrontEnd )
				)
				( attribute "SEC" "1"
					( Origin gFrontEnd )
				)
				( attribute "SEC_TYPE" "0402V"
					( Origin gFrontEnd )
				)
				( attribute "TOLERANCE" "10%"
					( Origin gFrontEnd )
				)
				( attribute "VALUE" "0.1UF"
					( Origin gFrontEnd )
				)
				( attribute "VER" "1"
					( Origin gFrontEnd )
				)
				( attribute "VOLTAGE" "16V"
					( Units "uVoltage" "V" 1.000000)
					( Origin gFrontEnd )
				)
				( attribute "XY" "(-1825,2925)"
					( Origin gFrontEnd )
				)
				( attribute "CHIPS_PART_NAME" "CAP_A"
					( Origin gPackager )
				)
				( attribute "CDS_PART_NAME" "CAP_A_0402V-0.1UF,16V,10%,X7R,A"
					( Origin gPackager )
				)
				( objectStatus "C2T3" )
				( pin "a"
					( attribute "PN" "1"
						( Origin gPackager )
					)
					( objectStatus "C2T3.1" )
				)
				( pin "b"
					( attribute "PN" "2"
						( Origin gPackager )
					)
					( objectStatus "C2T3.2" )
				)
			)
			( gate "@baseboard_fab2_lib.baseboard_fab2(sch_1):page157_i374"
				( attribute "CDS_LIB" "mstr_ttl"
					( Origin gPackager )
				)
				( attribute "CDS_LOCATION" "U8D2"
					( Origin gPackager )
				)
				( attribute "CDS_SEC" "1"
					( Origin gPackager )
				)
				( attribute "LOCATION" "U8D2"
					( Origin gFrontEnd )
				)
				( attribute "MATERIAL" "IC"
					( Origin gFrontEnd )
				)
				( attribute "PACK_TYPE" "SOP"
					( Origin gFrontEnd )
				)
				( attribute "PART_NUMBER" "C88419-001"
					( Origin gFrontEnd )
				)
				( attribute "PHYS_PAGE" "157"
					( Origin gFrontEnd )
				)
				( attribute "ROT" "0"
					( Origin gFrontEnd )
				)
				( attribute "SEC" "1"
					( Origin gFrontEnd )
				)
				( attribute "SEC_TYPE" "SOP"
					( Origin gFrontEnd )
				)
				( attribute "VALUE" "74LVC1G07"
					( Origin gFrontEnd )
				)
				( attribute "VER" "1"
					( Origin gFrontEnd )
				)
				( attribute "XY" "(-2800,1150)"
					( Origin gFrontEnd )
				)
				( attribute "CHIPS_PART_NAME" "TTL1G07_A"
					( Origin gPackager )
				)
				( attribute "CDS_PART_NAME" "TTL1G07_A_SOP-74LVC1G07,IC,C88B"
					( Origin gPackager )
				)
				( objectStatus "U8D2" )
				( pin "a"
					( attribute "PN" "2"
						( Origin gPackager )
					)
					( objectStatus "U8D2.2" )
				)
				( pin "y"
					( attribute "PN" "4"
						( Origin gPackager )
					)
					( objectStatus "U8D2.4" )
				)
			)
			( gate "@baseboard_fab2_lib.baseboard_fab2(sch_1):page157_i376"
				( attribute "CDS_LIB" "dev_discrete"
					( Origin gPackager )
				)
				( attribute "CDS_LOCATION" "C8D1"
					( Origin gPackager )
				)
				( attribute "CDS_SEC" "1"
					( Origin gPackager )
				)
				( attribute "LOCATION" "C8D1"
					( Origin gFrontEnd )
				)
				( attribute "MATERIAL" "X7R"
					( Origin gFrontEnd )
				)
				( attribute "PACK_TYPE" "0402V"
					( Origin gFrontEnd )
				)
				( attribute "PART_NUMBER" "A36096-030"
					( Origin gFrontEnd )
				)
				( attribute "PHYS_PAGE" "157"
					( Origin gFrontEnd )
				)
				( attribute "ROT" "0"
					( Origin gFrontEnd )
				)
				( attribute "SEC" "1"
					( Origin gFrontEnd )
				)
				( attribute "SEC_TYPE" "0402V"
					( Origin gFrontEnd )
				)
				( attribute "TOLERANCE" "10%"
					( Origin gFrontEnd )
				)
				( attribute "VALUE" "0.1UF"
					( Origin gFrontEnd )
				)
				( attribute "VER" "1"
					( Origin gFrontEnd )
				)
				( attribute "VOLTAGE" "16V"
					( Units "uVoltage" "V" 1.000000)
					( Origin gFrontEnd )
				)
				( attribute "XY" "(-500,1725)"
					( Origin gFrontEnd )
				)
				( attribute "CHIPS_PART_NAME" "CAP_A"
					( Origin gPackager )
				)
				( attribute "CDS_PART_NAME" "CAP_A_0402V-0.1UF,16V,10%,X7R,A"
					( Origin gPackager )
				)
				( objectStatus "C8D1" )
				( pin "a"
					( attribute "PN" "1"
						( Origin gPackager )
					)
					( objectStatus "C8D1.1" )
				)
				( pin "b"
					( attribute "PN" "2"
						( Origin gPackager )
					)
					( objectStatus "C8D1.2" )
				)
			)
			( gate "@baseboard_fab2_lib.baseboard_fab2(sch_1):page157_i379"
				( attribute "CDS_LIB" "mstr_discrete"
					( Origin gPackager )
				)
				( attribute "CDS_LOCATION" "R9E14"
					( Origin gPackager )
				)
				( attribute "CDS_SEC" "1"
					( Origin gPackager )
				)
				( attribute "LOCATION" "R9E14"
					( Origin gFrontEnd )
				)
				( attribute "MATERIAL" "CHIP"
					( Origin gFrontEnd )
				)
				( attribute "PACK_TYPE" "0402"
					( Origin gFrontEnd )
				)
				( attribute "PART_NUMBER" "G21497-005"
					( Origin gFrontEnd )
				)
				( attribute "PHYS_PAGE" "157"
					( Origin gFrontEnd )
				)
				( attribute "ROT" "0"
					( Origin gFrontEnd )
				)
				( attribute "SEC" "1"
					( Origin gFrontEnd )
				)
				( attribute "SEC_TYPE" "0402"
					( Origin gFrontEnd )
				)
				( attribute "TOLERANCE" "5%"
					( Origin gFrontEnd )
				)
				( attribute "VALUE" "0.0"
					( Origin gFrontEnd )
				)
				( attribute "VER" "1"
					( Origin gFrontEnd )
				)
				( attribute "WATTAGE" "1/16W"
					( Origin gFrontEnd )
				)
				( attribute "XY" "(-1450,875)"
					( Origin gFrontEnd )
				)
				( attribute "CHIPS_PART_NAME" "RES"
					( Origin gPackager )
				)
				( attribute "CDS_PART_NAME" "RES_0402-0.0,5%,1/16W,CHIP,G21A"
					( Origin gPackager )
				)
				( objectStatus "R9E14" )
				( pin "a"
					( attribute "PN" "1"
						( Origin gPackager )
					)
					( objectStatus "R9E14.1" )
				)
				( pin "b"
					( attribute "PN" "2"
						( Origin gPackager )
					)
					( objectStatus "R9E14.2" )
				)
			)
			( gate "@baseboard_fab2_lib.baseboard_fab2(sch_1):page157_i382"
				( attribute "BOM_COST" "SM_CONTROLLER"
					( Origin gFrontEnd )
				)
				( attribute "CDS_LIB" "mstr_discrete"
					( Origin gPackager )
				)
				( attribute "CDS_LOCATION" "R1L7"
					( Origin gPackager )
				)
				( attribute "CDS_SEC" "1"
					( Origin gPackager )
				)
				( attribute "LOCATION" "R1L7"
					( Origin gFrontEnd )
				)
				( attribute "MATERIAL" "CHIP"
					( Origin gFrontEnd )
				)
				( attribute "PACK_TYPE" "0402"
					( Origin gFrontEnd )
				)
				( attribute "PART_NUMBER" "G21796-072"
					( Origin gFrontEnd )
				)
				( attribute "PHYS_PAGE" "157"
					( Origin gFrontEnd )
				)
				( attribute "ROOM" "BMC_MISC"
					( Origin gFrontEnd )
				)
				( attribute "ROT" "0"
					( Origin gFrontEnd )
				)
				( attribute "SEC" "1"
					( Origin gFrontEnd )
				)
				( attribute "SEC_TYPE" "0402"
					( Origin gFrontEnd )
				)
				( attribute "TOLERANCE" "1%"
					( Origin gFrontEnd )
				)
				( attribute "VALUE" "4.75K"
					( Origin gFrontEnd )
				)
				( attribute "VER" "1"
					( Origin gFrontEnd )
				)
				( attribute "WATTAGE" "1/16W"
					( Origin gFrontEnd )
				)
				( attribute "XY" "(-7175,3425)"
					( Origin gFrontEnd )
				)
				( attribute "CHIPS_PART_NAME" "RES"
					( Origin gPackager )
				)
				( attribute "CDS_PART_NAME" "RES_0402-4.75K,1%,1/16W,CHIP,GA"
					( Origin gPackager )
				)
				( objectStatus "R1L7" )
				( pin "a"
					( attribute "PN" "1"
						( Origin gPackager )
					)
					( objectStatus "R1L7.1" )
				)
				( pin "b"
					( attribute "PN" "2"
						( Origin gPackager )
					)
					( objectStatus "R1L7.2" )
				)
			)
			( gate "@baseboard_fab2_lib.baseboard_fab2(sch_1):page157_i385"
				( attribute "BOM_COST" "MIO_CHASSIS"
					( Origin gFrontEnd )
				)
				( attribute "CDS_LIB" "mstr_discrete"
					( Origin gPackager )
				)
				( attribute "CDS_LOCATION" "R8E32"
					( Origin gPackager )
				)
				( attribute "CDS_SEC" "1"
					( Origin gPackager )
				)
				( attribute "LOCATION" "R8E32"
					( Origin gFrontEnd )
				)
				( attribute "MATERIAL" "CHIP"
					( Origin gFrontEnd )
				)
				( attribute "PACK_TYPE" "0402"
					( Origin gFrontEnd )
				)
				( attribute "PART_NUMBER" "G21796-072"
					( Origin gFrontEnd )
				)
				( attribute "PHYS_PAGE" "157"
					( Origin gFrontEnd )
				)
				( attribute "ROOM" "MIO_CHASSIS"
					( Origin gFrontEnd )
				)
				( attribute "ROT" "0"
					( Origin gFrontEnd )
				)
				( attribute "SEC" "1"
					( Origin gFrontEnd )
				)
				( attribute "SEC_TYPE" "0402"
					( Origin gFrontEnd )
				)
				( attribute "TOLERANCE" "1%"
					( Origin gFrontEnd )
				)
				( attribute "VALUE" "4.75K"
					( Origin gFrontEnd )
				)
				( attribute "VER" "2"
					( Origin gFrontEnd )
				)
				( attribute "WATTAGE" "1/16W"
					( Origin gFrontEnd )
				)
				( attribute "XY" "(-3950,2650)"
					( Origin gFrontEnd )
				)
				( attribute "CHIPS_PART_NAME" "RES"
					( Origin gPackager )
				)
				( attribute "CDS_PART_NAME" "RES_0402-4.75K,1%,1/16W,CHIP,GA"
					( Origin gPackager )
				)
				( objectStatus "R8E32" )
				( pin "a"
					( attribute "PN" "1"
						( Origin gPackager )
					)
					( objectStatus "R8E32.1" )
				)
				( pin "b"
					( attribute "PN" "2"
						( Origin gPackager )
					)
					( objectStatus "R8E32.2" )
				)
			)
			( gate "@baseboard_fab2_lib.baseboard_fab2(sch_1):page157_i386"
				( attribute "BOM_COST" "SM"
					( Origin gFrontEnd )
				)
				( attribute "CDS_LIB" "mstr_discrete"
					( Origin gPackager )
				)
				( attribute "CDS_LOCATION" "R8D22"
					( Origin gPackager )
				)
				( attribute "CDS_SEC" "1"
					( Origin gPackager )
				)
				( attribute "LOCATION" "R8D22"
					( Origin gFrontEnd )
				)
				( attribute "MATERIAL" "CHIP"
					( Origin gFrontEnd )
				)
				( attribute "PACK_TYPE" "0402"
					( Origin gFrontEnd )
				)
				( attribute "PART_NUMBER" "G21796-074"
					( Origin gFrontEnd )
				)
				( attribute "PHYS_PAGE" "157"
					( Origin gFrontEnd )
				)
				( attribute "ROOM" "BMC_MISC"
					( Origin gFrontEnd )
				)
				( attribute "ROT" "0"
					( Origin gFrontEnd )
				)
				( attribute "SEC" "1"
					( Origin gFrontEnd )
				)
				( attribute "SEC_TYPE" "0402"
					( Origin gFrontEnd )
				)
				( attribute "TOLERANCE" "1%"
					( Origin gFrontEnd )
				)
				( attribute "VALUE" "33.2"
					( Origin gFrontEnd )
				)
				( attribute "VER" "1"
					( Origin gFrontEnd )
				)
				( attribute "WATTAGE" "1/16W"
					( Origin gFrontEnd )
				)
				( attribute "XY" "(-1925,1150)"
					( Origin gFrontEnd )
				)
				( attribute "CHIPS_PART_NAME" "RES"
					( Origin gPackager )
				)
				( attribute "CDS_PART_NAME" "RES_0402-33.2,1%,1/16W,CHIP,G2A"
					( Origin gPackager )
				)
				( objectStatus "R8D22" )
				( pin "a"
					( attribute "PN" "1"
						( Origin gPackager )
					)
					( objectStatus "R8D22.1" )
				)
				( pin "b"
					( attribute "PN" "2"
						( Origin gPackager )
					)
					( objectStatus "R8D22.2" )
				)
			)
			( gate "@baseboard_fab2_lib.baseboard_fab2(sch_1):page157_i388"
				( attribute "BOM_COST" "SM"
					( Origin gFrontEnd )
				)
				( attribute "CDS_LIB" "mstr_discrete"
					( Origin gPackager )
				)
				( attribute "CDS_LOCATION" "R8D36"
					( Origin gPackager )
				)
				( attribute "CDS_SEC" "1"
					( Origin gPackager )
				)
				( attribute "LOCATION" "R8D36"
					( Origin gFrontEnd )
				)
				( attribute "MATERIAL" "CHIP"
					( Origin gFrontEnd )
				)
				( attribute "PACK_TYPE" "0402"
					( Origin gFrontEnd )
				)
				( attribute "PART_NUMBER" "G21796-074"
					( Origin gFrontEnd )
				)
				( attribute "PHYS_PAGE" "157"
					( Origin gFrontEnd )
				)
				( attribute "ROOM" "BMC_MISC"
					( Origin gFrontEnd )
				)
				( attribute "ROT" "0"
					( Origin gFrontEnd )
				)
				( attribute "SEC" "1"
					( Origin gFrontEnd )
				)
				( attribute "SEC_TYPE" "0402"
					( Origin gFrontEnd )
				)
				( attribute "TOLERANCE" "1%"
					( Origin gFrontEnd )
				)
				( attribute "VALUE" "33.2"
					( Origin gFrontEnd )
				)
				( attribute "VER" "1"
					( Origin gFrontEnd )
				)
				( attribute "WATTAGE" "1/16W"
					( Origin gFrontEnd )
				)
				( attribute "XY" "(-1425,1375)"
					( Origin gFrontEnd )
				)
				( attribute "CHIPS_PART_NAME" "RES"
					( Origin gPackager )
				)
				( attribute "CDS_PART_NAME" "RES_0402-33.2,1%,1/16W,CHIP,G2A"
					( Origin gPackager )
				)
				( objectStatus "R8D36" )
				( pin "a"
					( attribute "PN" "1"
						( Origin gPackager )
					)
					( objectStatus "R8D36.1" )
				)
				( pin "b"
					( attribute "PN" "2"
						( Origin gPackager )
					)
					( objectStatus "R8D36.2" )
				)
			)
			( gate "@baseboard_fab2_lib.baseboard_fab2(sch_1):page158_i70"
				( attribute "BOM_COST" "DEBUG"
					( Origin gFrontEnd )
				)
				( attribute "CDS_LIB" "dev_discrete"
					( Origin gPackager )
				)
				( attribute "CDS_LOCATION" "C1T10"
					( Origin gPackager )
				)
				( attribute "CDS_SEC" "1"
					( Origin gPackager )
				)
				( attribute "LOCATION" "C1T10"
					( Origin gFrontEnd )
				)
				( attribute "MATERIAL" "X7R"
					( Origin gFrontEnd )
				)
				( attribute "PACK_TYPE" "0402V"
					( Origin gFrontEnd )
				)
				( attribute "PART_NUMBER" "A36096-030"
					( Origin gFrontEnd )
				)
				( attribute "PHYS_PAGE" "158"
					( Origin gFrontEnd )
				)
				( attribute "ROOM" "UART_MUX"
					( Origin gFrontEnd )
				)
				( attribute "ROT" "0"
					( Origin gFrontEnd )
				)
				( attribute "SEC" "1"
					( Origin gFrontEnd )
				)
				( attribute "SEC_TYPE" "0402V"
					( Origin gFrontEnd )
				)
				( attribute "TOLERANCE" "10%"
					( Origin gFrontEnd )
				)
				( attribute "VALUE" "0.1UF"
					( Origin gFrontEnd )
				)
				( attribute "VER" "1"
					( Origin gFrontEnd )
				)
				( attribute "VOLTAGE" "16V"
					( Units "uVoltage" "V" 1.000000)
					( Origin gFrontEnd )
				)
				( attribute "XY" "(-1775,2950)"
					( Origin gFrontEnd )
				)
				( attribute "CHIPS_PART_NAME" "CAP_A"
					( Origin gPackager )
				)
				( attribute "CDS_PART_NAME" "CAP_A_0402V-0.1UF,16V,10%,X7R,A"
					( Origin gPackager )
				)
				( objectStatus "C1T10" )
				( pin "a"
					( attribute "PN" "1"
						( Origin gPackager )
					)
					( objectStatus "C1T10.1" )
				)
				( pin "b"
					( attribute "PN" "2"
						( Origin gPackager )
					)
					( objectStatus "C1T10.2" )
				)
			)
			( gate "@baseboard_fab2_lib.baseboard_fab2(sch_1):page158_i74"
				( attribute "BOM_COST" "DEBUG"
					( Origin gFrontEnd )
				)
				( attribute "CDS_LIB" "mstr_analog"
					( Origin gPackager )
				)
				( attribute "CDS_LOCATION" "U9F2"
					( Origin gPackager )
				)
				( attribute "CDS_SEC" "1"
					( Origin gPackager )
				)
				( attribute "LOCATION" "U9F2"
					( Origin gFrontEnd )
				)
				( attribute "MATERIAL" "IC"
					( Origin gFrontEnd )
				)
				( attribute "PACK_TYPE" "SM"
					( Origin gFrontEnd )
				)
				( attribute "PART_NUMBER" "C63273-001"
					( Origin gFrontEnd )
				)
				( attribute "PHYS_PAGE" "158"
					( Origin gFrontEnd )
				)
				( attribute "ROOM" "UART_MUX"
					( Origin gFrontEnd )
				)
				( attribute "ROT" "2"
					( Origin gFrontEnd )
				)
				( attribute "SEC" "1"
					( Origin gFrontEnd )
				)
				( attribute "SEC_TYPE" "SM"
					( Origin gFrontEnd )
				)
				( attribute "VER" "1"
					( Origin gFrontEnd )
				)
				( attribute "XY" "(-2275,2575)"
					( Origin gFrontEnd )
				)
				( attribute "CHIPS_PART_NAME" "FSA3357"
					( Origin gPackager )
				)
				( attribute "CDS_PART_NAME" "FSA3357_SM-IC,C63273-001"
					( Origin gPackager )
				)
				( objectStatus "U9F2" )
				( pin "a"
					( attribute "PN" "7"
						( Origin gPackager )
					)
					( objectStatus "U9F2.7" )
				)
				( pin "b0"
					( attribute "PN" "1"
						( Origin gPackager )
					)
					( objectStatus "U9F2.1" )
				)
				( pin "b1"
					( attribute "PN" "2"
						( Origin gPackager )
					)
					( objectStatus "U9F2.2" )
				)
				( pin "b2"
					( attribute "PN" "3"
						( Origin gPackager )
					)
					( objectStatus "U9F2.3" )
				)
				( pin "gnd"
					( attribute "PN" "4"
						( Origin gPackager )
					)
					( objectStatus "U9F2.4" )
				)
				( pin "s1"
					( attribute "PN" "6"
						( Origin gPackager )
					)
					( objectStatus "U9F2.6" )
				)
				( pin "s2"
					( attribute "PN" "5"
						( Origin gPackager )
					)
					( objectStatus "U9F2.5" )
				)
				( pin "vcc"
					( attribute "PN" "8"
						( Origin gPackager )
					)
					( objectStatus "U9F2.8" )
				)
			)
			( gate "@baseboard_fab2_lib.baseboard_fab2(sch_1):page158_i75"
				( attribute "BOM_COST" "DEBUG"
					( Origin gFrontEnd )
				)
				( attribute "CDS_LIB" "mstr_analog"
					( Origin gPackager )
				)
				( attribute "CDS_LOCATION" "U9F1"
					( Origin gPackager )
				)
				( attribute "CDS_SEC" "1"
					( Origin gPackager )
				)
				( attribute "LOCATION" "U9F1"
					( Origin gFrontEnd )
				)
				( attribute "MATERIAL" "IC"
					( Origin gFrontEnd )
				)
				( attribute "PACK_TYPE" "SM"
					( Origin gFrontEnd )
				)
				( attribute "PART_NUMBER" "C63273-001"
					( Origin gFrontEnd )
				)
				( attribute "PHYS_PAGE" "158"
					( Origin gFrontEnd )
				)
				( attribute "ROOM" "UART_MUX"
					( Origin gFrontEnd )
				)
				( attribute "ROT" "0"
					( Origin gFrontEnd )
				)
				( attribute "SEC" "1"
					( Origin gFrontEnd )
				)
				( attribute "SEC_TYPE" "SM"
					( Origin gFrontEnd )
				)
				( attribute "VER" "1"
					( Origin gFrontEnd )
				)
				( attribute "XY" "(-2650,850)"
					( Origin gFrontEnd )
				)
				( attribute "CHIPS_PART_NAME" "FSA3357"
					( Origin gPackager )
				)
				( attribute "CDS_PART_NAME" "FSA3357_SM-IC,C63273-001"
					( Origin gPackager )
				)
				( objectStatus "U9F1" )
				( pin "a"
					( attribute "PN" "7"
						( Origin gPackager )
					)
					( objectStatus "U9F1.7" )
				)
				( pin "b0"
					( attribute "PN" "1"
						( Origin gPackager )
					)
					( objectStatus "U9F1.1" )
				)
				( pin "b1"
					( attribute "PN" "2"
						( Origin gPackager )
					)
					( objectStatus "U9F1.2" )
				)
				( pin "b2"
					( attribute "PN" "3"
						( Origin gPackager )
					)
					( objectStatus "U9F1.3" )
				)
				( pin "gnd"
					( attribute "PN" "4"
						( Origin gPackager )
					)
					( objectStatus "U9F1.4" )
				)
				( pin "s1"
					( attribute "PN" "6"
						( Origin gPackager )
					)
					( objectStatus "U9F1.6" )
				)
				( pin "s2"
					( attribute "PN" "5"
						( Origin gPackager )
					)
					( objectStatus "U9F1.5" )
				)
				( pin "vcc"
					( attribute "PN" "8"
						( Origin gPackager )
					)
					( objectStatus "U9F1.8" )
				)
			)
			( gate "@baseboard_fab2_lib.baseboard_fab2(sch_1):page158_i86"
				( attribute "BOM_COST" "DEBUG"
					( Origin gFrontEnd )
				)
				( attribute "CDS_LIB" "mstr_discrete"
					( Origin gPackager )
				)
				( attribute "CDS_LOCATION" "R9F25"
					( Origin gPackager )
				)
				( attribute "CDS_SEC" "1"
					( Origin gPackager )
				)
				( attribute "LOCATION" "R9F25"
					( Origin gFrontEnd )
				)
				( attribute "MATERIAL" "CHIP"
					( Origin gFrontEnd )
				)
				( attribute "PACK_TYPE" "0402"
					( Origin gFrontEnd )
				)
				( attribute "PART_NUMBER" "G21796-017"
					( Origin gFrontEnd )
				)
				( attribute "PHYS_PAGE" "158"
					( Origin gFrontEnd )
				)
				( attribute "ROOM" "UART_MUX"
					( Origin gFrontEnd )
				)
				( attribute "ROT" "0"
					( Origin gFrontEnd )
				)
				( attribute "SEC" "1"
					( Origin gFrontEnd )
				)
				( attribute "SEC_TYPE" "0402"
					( Origin gFrontEnd )
				)
				( attribute "TOLERANCE" "1%"
					( Origin gFrontEnd )
				)
				( attribute "VALUE" "100.0"
					( Origin gFrontEnd )
				)
				( attribute "VER" "1"
					( Origin gFrontEnd )
				)
				( attribute "WATTAGE" "1/16W"
					( Origin gFrontEnd )
				)
				( attribute "XY" "(-3625,900)"
					( Origin gFrontEnd )
				)
				( attribute "CHIPS_PART_NAME" "RES"
					( Origin gPackager )
				)
				( attribute "CDS_PART_NAME" "RES_0402-100.0,1%,1/16W,CHIP,GA"
					( Origin gPackager )
				)
				( objectStatus "R9F25" )
				( pin "a"
					( attribute "PN" "1"
						( Origin gPackager )
					)
					( objectStatus "R9F25.1" )
				)
				( pin "b"
					( attribute "PN" "2"
						( Origin gPackager )
					)
					( objectStatus "R9F25.2" )
				)
			)
			( gate "@baseboard_fab2_lib.baseboard_fab2(sch_1):page158_i91"
				( attribute "BOM_COST" "DEBUG"
					( Origin gFrontEnd )
				)
				( attribute "CDS_LIB" "mstr_discrete"
					( Origin gPackager )
				)
				( attribute "CDS_LOCATION" "R9F27"
					( Origin gPackager )
				)
				( attribute "CDS_SEC" "1"
					( Origin gPackager )
				)
				( attribute "LOCATION" "R9F27"
					( Origin gFrontEnd )
				)
				( attribute "MATERIAL" "CHIP"
					( Origin gFrontEnd )
				)
				( attribute "PACK_TYPE" "0402"
					( Origin gFrontEnd )
				)
				( attribute "PART_NUMBER" "G21497-005"
					( Origin gFrontEnd )
				)
				( attribute "PHYS_PAGE" "158"
					( Origin gFrontEnd )
				)
				( attribute "ROOM" "UART_MUX"
					( Origin gFrontEnd )
				)
				( attribute "ROT" "0"
					( Origin gFrontEnd )
				)
				( attribute "SEC" "1"
					( Origin gFrontEnd )
				)
				( attribute "SEC_TYPE" "0402"
					( Origin gFrontEnd )
				)
				( attribute "TOLERANCE" "5%"
					( Origin gFrontEnd )
				)
				( attribute "VALUE" "0.0"
					( Origin gFrontEnd )
				)
				( attribute "VER" "1"
					( Origin gFrontEnd )
				)
				( attribute "WATTAGE" "1/16W"
					( Origin gFrontEnd )
				)
				( attribute "XY" "(-1325,2625)"
					( Origin gFrontEnd )
				)
				( attribute "CHIPS_PART_NAME" "RES"
					( Origin gPackager )
				)
				( attribute "CDS_PART_NAME" "RES_0402-0.0,5%,1/16W,CHIP,G21A"
					( Origin gPackager )
				)
				( objectStatus "R9F27" )
				( pin "a"
					( attribute "PN" "1"
						( Origin gPackager )
					)
					( objectStatus "R9F27.1" )
				)
				( pin "b"
					( attribute "PN" "2"
						( Origin gPackager )
					)
					( objectStatus "R9F27.2" )
				)
			)
			( gate "@baseboard_fab2_lib.baseboard_fab2(sch_1):page158_i97"
				( attribute "BOM_COST" "DEBUG"
					( Origin gFrontEnd )
				)
				( attribute "CDS_LIB" "dev_discrete"
					( Origin gPackager )
				)
				( attribute "CDS_LOCATION" "C1T11"
					( Origin gPackager )
				)
				( attribute "CDS_SEC" "1"
					( Origin gPackager )
				)
				( attribute "LOCATION" "C1T11"
					( Origin gFrontEnd )
				)
				( attribute "MATERIAL" "X7R"
					( Origin gFrontEnd )
				)
				( attribute "PACK_TYPE" "0402V"
					( Origin gFrontEnd )
				)
				( attribute "PART_NUMBER" "A36096-030"
					( Origin gFrontEnd )
				)
				( attribute "PHYS_PAGE" "158"
					( Origin gFrontEnd )
				)
				( attribute "ROOM" "UART_MUX"
					( Origin gFrontEnd )
				)
				( attribute "ROT" "0"
					( Origin gFrontEnd )
				)
				( attribute "SEC" "1"
					( Origin gFrontEnd )
				)
				( attribute "SEC_TYPE" "0402V"
					( Origin gFrontEnd )
				)
				( attribute "TOLERANCE" "10%"
					( Origin gFrontEnd )
				)
				( attribute "VALUE" "0.1UF"
					( Origin gFrontEnd )
				)
				( attribute "VER" "1"
					( Origin gFrontEnd )
				)
				( attribute "VOLTAGE" "16V"
					( Units "uVoltage" "V" 1.000000)
					( Origin gFrontEnd )
				)
				( attribute "XY" "(-3475,1200)"
					( Origin gFrontEnd )
				)
				( attribute "CHIPS_PART_NAME" "CAP_A"
					( Origin gPackager )
				)
				( attribute "CDS_PART_NAME" "CAP_A_0402V-0.1UF,16V,10%,X7R,A"
					( Origin gPackager )
				)
				( objectStatus "C1T11" )
				( pin "a"
					( attribute "PN" "1"
						( Origin gPackager )
					)
					( objectStatus "C1T11.1" )
				)
				( pin "b"
					( attribute "PN" "2"
						( Origin gPackager )
					)
					( objectStatus "C1T11.2" )
				)
			)
			( gate "@baseboard_fab2_lib.baseboard_fab2(sch_1):page158_i99"
				( attribute "BOM_COST" "DEBUG"
					( Origin gFrontEnd )
				)
				( attribute "CDS_LIB" "mstr_discrete"
					( Origin gPackager )
				)
				( attribute "CDS_LOCATION" "R9F26"
					( Origin gPackager )
				)
				( attribute "CDS_SEC" "1"
					( Origin gPackager )
				)
				( attribute "LOCATION" "R9F26"
					( Origin gFrontEnd )
				)
				( attribute "MATERIAL" "EMPTY"
					( Origin gFrontEnd )
				)
				( attribute "PACK_TYPE" "0402"
					( Origin gFrontEnd )
				)
				( attribute "PART_NUMBER" "G21497-005"
					( Origin gFrontEnd )
				)
				( attribute "PHYS_PAGE" "158"
					( Origin gFrontEnd )
				)
				( attribute "ROOM" "UART_MUX"
					( Origin gFrontEnd )
				)
				( attribute "ROT" "0"
					( Origin gFrontEnd )
				)
				( attribute "SEC" "1"
					( Origin gFrontEnd )
				)
				( attribute "SEC_TYPE" "0402"
					( Origin gFrontEnd )
				)
				( attribute "TOLERANCE" "5%"
					( Origin gFrontEnd )
				)
				( attribute "VALUE" "0.0"
					( Origin gFrontEnd )
				)
				( attribute "VER" "1"
					( Origin gFrontEnd )
				)
				( attribute "WATTAGE" "1/16W"
					( Origin gFrontEnd )
				)
				( attribute "XY" "(-1900,3450)"
					( Origin gFrontEnd )
				)
				( attribute "CHIPS_PART_NAME" "RES"
					( Origin gPackager )
				)
				( attribute "CDS_PART_NAME" "RES_0402-0.0,5%,1/16W,EMPTY,G2A"
					( Origin gPackager )
				)
				( objectStatus "R9F26" )
				( pin "a"
					( attribute "PN" "1"
						( Origin gPackager )
					)
					( objectStatus "R9F26.1" )
				)
				( pin "b"
					( attribute "PN" "2"
						( Origin gPackager )
					)
					( objectStatus "R9F26.2" )
				)
			)
			( gate "@baseboard_fab2_lib.baseboard_fab2(sch_1):page158_i100"
				( attribute "BOM_COST" "DEBUG"
					( Origin gFrontEnd )
				)
				( attribute "CDS_LIB" "mstr_discrete"
					( Origin gPackager )
				)
				( attribute "CDS_LOCATION" "R9F24"
					( Origin gPackager )
				)
				( attribute "CDS_SEC" "1"
					( Origin gPackager )
				)
				( attribute "LOCATION" "R9F24"
					( Origin gFrontEnd )
				)
				( attribute "MATERIAL" "EMPTY"
					( Origin gFrontEnd )
				)
				( attribute "PACK_TYPE" "0402"
					( Origin gFrontEnd )
				)
				( attribute "PART_NUMBER" "G21497-005"
					( Origin gFrontEnd )
				)
				( attribute "PHYS_PAGE" "158"
					( Origin gFrontEnd )
				)
				( attribute "ROOM" "UART_MUX"
					( Origin gFrontEnd )
				)
				( attribute "ROT" "0"
					( Origin gFrontEnd )
				)
				( attribute "SEC" "1"
					( Origin gFrontEnd )
				)
				( attribute "SEC_TYPE" "0402"
					( Origin gFrontEnd )
				)
				( attribute "TOLERANCE" "5%"
					( Origin gFrontEnd )
				)
				( attribute "VALUE" "0.0"
					( Origin gFrontEnd )
				)
				( attribute "VER" "1"
					( Origin gFrontEnd )
				)
				( attribute "WATTAGE" "1/16W"
					( Origin gFrontEnd )
				)
				( attribute "XY" "(-2650,1525)"
					( Origin gFrontEnd )
				)
				( attribute "CHIPS_PART_NAME" "RES"
					( Origin gPackager )
				)
				( attribute "CDS_PART_NAME" "RES_0402-0.0,5%,1/16W,EMPTY,G2A"
					( Origin gPackager )
				)
				( objectStatus "R9F24" )
				( pin "a"
					( attribute "PN" "1"
						( Origin gPackager )
					)
					( objectStatus "R9F24.1" )
				)
				( pin "b"
					( attribute "PN" "2"
						( Origin gPackager )
					)
					( objectStatus "R9F24.2" )
				)
			)
			( gate "@baseboard_fab2_lib.baseboard_fab2(sch_1):page158_i130"
				( attribute "BOM_COST" "DEBUG"
					( Origin gFrontEnd )
				)
				( attribute "CDS_LIB" "mstr_discrete"
					( Origin gPackager )
				)
				( attribute "CDS_LOCATION" "DS9A4"
					( Origin gPackager )
				)
				( attribute "CDS_SEC" "1"
					( Origin gPackager )
				)
				( attribute "COLOR" "GREEN"
					( Origin gFrontEnd )
				)
				( attribute "LOCATION" "DS9A4"
					( Origin gFrontEnd )
				)
				( attribute "MATERIAL" "IC"
					( Origin gFrontEnd )
				)
				( attribute "PACK_TYPE" "A1LF"
					( Origin gFrontEnd )
				)
				( attribute "PART_NUMBER" "D14725-022"
					( Origin gFrontEnd )
				)
				( attribute "PHYS_PAGE" "158"
					( Origin gFrontEnd )
				)
				( attribute "ROOM" "UART_MUX"
					( Origin gFrontEnd )
				)
				( attribute "ROT" "0"
					( Origin gFrontEnd )
				)
				( attribute "SEC" "1"
					( Origin gFrontEnd )
				)
				( attribute "SEC_TYPE" "A1LF"
					( Origin gFrontEnd )
				)
				( attribute "VER" "3"
					( Origin gFrontEnd )
				)
				( attribute "XY" "(-5725,3200)"
					( Origin gFrontEnd )
				)
				( attribute "CHIPS_PART_NAME" "LED"
					( Origin gPackager )
				)
				( attribute "CDS_PART_NAME" "LED_A1LF-GREEN,IC,D14725-022"
					( Origin gPackager )
				)
				( objectStatus "DS9A4" )
				( pin "a"
					( attribute "PN" "1"
						( Origin gPackager )
					)
					( objectStatus "DS9A4.1" )
				)
				( pin "c"
					( attribute "PN" "2"
						( Origin gPackager )
					)
					( objectStatus "DS9A4.2" )
				)
			)
			( gate "@baseboard_fab2_lib.baseboard_fab2(sch_1):page158_i131"
				( attribute "BOM_COST" "DEBUG"
					( Origin gFrontEnd )
				)
				( attribute "CDS_LIB" "mstr_discrete"
					( Origin gPackager )
				)
				( attribute "CDS_LOCATION" "R1L43"
					( Origin gPackager )
				)
				( attribute "CDS_SEC" "1"
					( Origin gPackager )
				)
				( attribute "LOCATION" "R1L43"
					( Origin gFrontEnd )
				)
				( attribute "MATERIAL" "CHIP"
					( Origin gFrontEnd )
				)
				( attribute "PACK_TYPE" "0402"
					( Origin gFrontEnd )
				)
				( attribute "PART_NUMBER" "G21497-028"
					( Origin gFrontEnd )
				)
				( attribute "PHYS_PAGE" "158"
					( Origin gFrontEnd )
				)
				( attribute "ROOM" "UART_MUX"
					( Origin gFrontEnd )
				)
				( attribute "ROT" "0"
					( Origin gFrontEnd )
				)
				( attribute "SEC" "1"
					( Origin gFrontEnd )
				)
				( attribute "SEC_TYPE" "0402"
					( Origin gFrontEnd )
				)
				( attribute "TOLERANCE" "5%"
					( Origin gFrontEnd )
				)
				( attribute "VALUE" "330"
					( Origin gFrontEnd )
				)
				( attribute "VER" "1"
					( Origin gFrontEnd )
				)
				( attribute "WATTAGE" "1/16W"
					( Origin gFrontEnd )
				)
				( attribute "XY" "(-4875,3200)"
					( Origin gFrontEnd )
				)
				( attribute "CHIPS_PART_NAME" "RES"
					( Origin gPackager )
				)
				( attribute "CDS_PART_NAME" "RES_0402-330,5%,1/16W,CHIP,G21A"
					( Origin gPackager )
				)
				( objectStatus "R1L43" )
				( pin "a"
					( attribute "PN" "1"
						( Origin gPackager )
					)
					( objectStatus "R1L43.1" )
				)
				( pin "b"
					( attribute "PN" "2"
						( Origin gPackager )
					)
					( objectStatus "R1L43.2" )
				)
			)
			( gate "@baseboard_fab2_lib.baseboard_fab2(sch_1):page158_i134"
				( attribute "BOM_COST" "DEBUG"
					( Origin gFrontEnd )
				)
				( attribute "CDS_LIB" "mstr_discrete"
					( Origin gPackager )
				)
				( attribute "CDS_LOCATION" "DS9A7"
					( Origin gPackager )
				)
				( attribute "CDS_SEC" "1"
					( Origin gPackager )
				)
				( attribute "COLOR" "GREEN"
					( Origin gFrontEnd )
				)
				( attribute "LOCATION" "DS9A7"
					( Origin gFrontEnd )
				)
				( attribute "MATERIAL" "IC"
					( Origin gFrontEnd )
				)
				( attribute "PACK_TYPE" "A1LF"
					( Origin gFrontEnd )
				)
				( attribute "PART_NUMBER" "D14725-022"
					( Origin gFrontEnd )
				)
				( attribute "PHYS_PAGE" "158"
					( Origin gFrontEnd )
				)
				( attribute "ROOM" "UART_MUX"
					( Origin gFrontEnd )
				)
				( attribute "ROT" "0"
					( Origin gFrontEnd )
				)
				( attribute "SEC" "1"
					( Origin gFrontEnd )
				)
				( attribute "SEC_TYPE" "A1LF"
					( Origin gFrontEnd )
				)
				( attribute "VER" "3"
					( Origin gFrontEnd )
				)
				( attribute "XY" "(-5725,3600)"
					( Origin gFrontEnd )
				)
				( attribute "CHIPS_PART_NAME" "LED"
					( Origin gPackager )
				)
				( attribute "CDS_PART_NAME" "LED_A1LF-GREEN,IC,D14725-022"
					( Origin gPackager )
				)
				( objectStatus "DS9A7" )
				( pin "a"
					( attribute "PN" "1"
						( Origin gPackager )
					)
					( objectStatus "DS9A7.1" )
				)
				( pin "c"
					( attribute "PN" "2"
						( Origin gPackager )
					)
					( objectStatus "DS9A7.2" )
				)
			)
			( gate "@baseboard_fab2_lib.baseboard_fab2(sch_1):page158_i136"
				( attribute "BOM_COST" "DEBUG"
					( Origin gFrontEnd )
				)
				( attribute "CDS_LIB" "mstr_discrete"
					( Origin gPackager )
				)
				( attribute "CDS_LOCATION" "R1L44"
					( Origin gPackager )
				)
				( attribute "CDS_SEC" "1"
					( Origin gPackager )
				)
				( attribute "LOCATION" "R1L44"
					( Origin gFrontEnd )
				)
				( attribute "MATERIAL" "CHIP"
					( Origin gFrontEnd )
				)
				( attribute "PACK_TYPE" "0402"
					( Origin gFrontEnd )
				)
				( attribute "PART_NUMBER" "G21497-028"
					( Origin gFrontEnd )
				)
				( attribute "PHYS_PAGE" "158"
					( Origin gFrontEnd )
				)
				( attribute "ROOM" "UART_MUX"
					( Origin gFrontEnd )
				)
				( attribute "ROT" "0"
					( Origin gFrontEnd )
				)
				( attribute "SEC" "1"
					( Origin gFrontEnd )
				)
				( attribute "SEC_TYPE" "0402"
					( Origin gFrontEnd )
				)
				( attribute "TOLERANCE" "5%"
					( Origin gFrontEnd )
				)
				( attribute "VALUE" "330"
					( Origin gFrontEnd )
				)
				( attribute "VER" "1"
					( Origin gFrontEnd )
				)
				( attribute "WATTAGE" "1/16W"
					( Origin gFrontEnd )
				)
				( attribute "XY" "(-4875,3600)"
					( Origin gFrontEnd )
				)
				( attribute "CHIPS_PART_NAME" "RES"
					( Origin gPackager )
				)
				( attribute "CDS_PART_NAME" "RES_0402-330,5%,1/16W,CHIP,G21A"
					( Origin gPackager )
				)
				( objectStatus "R1L44" )
				( pin "a"
					( attribute "PN" "1"
						( Origin gPackager )
					)
					( objectStatus "R1L44.1" )
				)
				( pin "b"
					( attribute "PN" "2"
						( Origin gPackager )
					)
					( objectStatus "R1L44.2" )
				)
			)
			( gate "@baseboard_fab2_lib.baseboard_fab2(sch_1):page239_i98"
				( attribute "CDS_LIB" "w_hdl"
					( Origin gPackager )
				)
				( attribute "CDS_LMAN_SYM_OUTLINE" "-50,75,50,-75"
					( Origin gPackager )
				)
				( attribute "LOCATION" "R9F31"
					( Origin gFrontEnd )
				)
				( attribute "PACK_TYPE" "SMD-RG"
					( Origin gFrontEnd )
				)
				( attribute "PART_NUMBER" "64.51015.6DL"
					( Origin gFrontEnd )
				)
				( attribute "PHYS_PAGE" "239"
					( Origin gFrontEnd )
				)
				( attribute "ROT" "0"
					( Origin gFrontEnd )
				)
				( attribute "VALUE" "5K1R2F-2-GP"
					( Origin gFrontEnd )
				)
				( attribute "VER" "1"
					( Origin gFrontEnd )
				)
				( attribute "XY" "(10350,3525)"
					( Origin gFrontEnd )
				)
				( attribute "CHIPS_PART_NAME" "5K1R2F-2-GP"
					( Origin gPackager )
				)
				( attribute "CDS_PART_NAME" "5K1R2F-2-GP_SMD-RG-5K1R2F-2-GPA"
					( Origin gPackager )
				)
				( attribute "CDS_LOCATION" "R9F31"
					( Origin gPackager )
				)
				( attribute "CDS_SEC" "1"
					( Origin gPackager )
				)
				( attribute "SEC" "1"
					( Origin gPackager )
				)
				( objectStatus "R9F31" )
				( pin "\1\"
					( attribute "PN" "1"
						( Origin gPackager )
					)
					( objectStatus "R9F31.1" )
				)
				( pin "\2\"
					( attribute "PN" "2"
						( Origin gPackager )
					)
					( objectStatus "R9F31.2" )
				)
			)
			( gate "@baseboard_fab2_lib.baseboard_fab2(sch_1):page181_i279"
				( attribute "CDS_LIB" "mstr_discrete"
					( Origin gPackager )
				)
				( attribute "CDS_LOCATION" "R9F67"
					( Origin gPackager )
				)
				( attribute "CDS_SEC" "1"
					( Origin gPackager )
				)
				( attribute "LOCATION" "R9F67"
					( Origin gFrontEnd )
				)
				( attribute "MATERIAL" "CHIP"
					( Origin gFrontEnd )
				)
				( attribute "PACK_TYPE" "0402"
					( Origin gFrontEnd )
				)
				( attribute "PART_NUMBER" "G21497-005"
					( Origin gFrontEnd )
				)
				( attribute "PHYS_PAGE" "181"
					( Origin gFrontEnd )
				)
				( attribute "ROOM" "UART_MUX"
					( Origin gFrontEnd )
				)
				( attribute "ROT" "0"
					( Origin gFrontEnd )
				)
				( attribute "SEC" "1"
					( Origin gPackager )
				)
				( attribute "TOLERANCE" "5%"
					( Origin gFrontEnd )
				)
				( attribute "VALUE" "0.0"
					( Origin gFrontEnd )
				)
				( attribute "VER" "1"
					( Origin gFrontEnd )
				)
				( attribute "WATTAGE" "1/16W"
					( Origin gFrontEnd )
				)
				( attribute "XY" "(-2375,3850)"
					( Origin gFrontEnd )
				)
				( attribute "CHIPS_PART_NAME" "RES"
					( Origin gPackager )
				)
				( attribute "CDS_PART_NAME" "RES_0402-0.0,5%,1/16W,CHIP,G21A"
					( Origin gPackager )
				)
				( objectStatus "R9F67" )
				( pin "a"
					( attribute "PN" "1"
						( Origin gPackager )
					)
					( objectStatus "R9F67.1" )
				)
				( pin "b"
					( attribute "PN" "2"
						( Origin gPackager )
					)
					( objectStatus "R9F67.2" )
				)
			)
			( gate "@baseboard_fab2_lib.baseboard_fab2(sch_1):page159_i210"
				( attribute "BOM_COST" "SM_CONTROLLER"
					( Origin gFrontEnd )
				)
				( attribute "CDS_LIB" "mstr_discrete"
					( Origin gPackager )
				)
				( attribute "CDS_LOCATION" "R8G3"
					( Origin gPackager )
				)
				( attribute "CDS_SEC" "1"
					( Origin gPackager )
				)
				( attribute "LOCATION" "R8G3"
					( Origin gFrontEnd )
				)
				( attribute "MATERIAL" "EMPTY"
					( Origin gFrontEnd )
				)
				( attribute "PACK_TYPE" "0402"
					( Origin gFrontEnd )
				)
				( attribute "PART_NUMBER" "G21796-311"
					( Origin gFrontEnd )
				)
				( attribute "PHYS_PAGE" "159"
					( Origin gFrontEnd )
				)
				( attribute "ROOM" "SMBUS"
					( Origin gFrontEnd )
				)
				( attribute "ROT" "0"
					( Origin gFrontEnd )
				)
				( attribute "SEC" "1"
					( Origin gPackager )
				)
				( attribute "SKU" "B"
					( Origin gFrontEnd )
				)
				( attribute "TOLERANCE" "1.0%"
					( Origin gFrontEnd )
				)
				( attribute "VALUE" "2.26K"
					( Origin gFrontEnd )
				)
				( attribute "VER" "2"
					( Origin gFrontEnd )
				)
				( attribute "WATTAGE" "1/16W"
					( Origin gFrontEnd )
				)
				( attribute "XY" "(-3375,2900)"
					( Origin gFrontEnd )
				)
				( attribute "CHIPS_PART_NAME" "RES"
					( Origin gPackager )
				)
				( attribute "CDS_PART_NAME" "RES_0402-2.26K,1.0%,1/16W,EMPTA"
					( Origin gPackager )
				)
				( objectStatus "R8G3" )
				( pin "a"
					( attribute "PN" "1"
						( Origin gPackager )
					)
					( objectStatus "R8G3.1" )
				)
				( pin "b"
					( attribute "PN" "2"
						( Origin gPackager )
					)
					( objectStatus "R8G3.2" )
				)
			)
			( gate "@baseboard_fab2_lib.baseboard_fab2(sch_1):page159_i212"
				( attribute "BOM_COST" "SM_CONTROLLER"
					( Origin gFrontEnd )
				)
				( attribute "CDS_LIB" "mstr_discrete"
					( Origin gPackager )
				)
				( attribute "CDS_LOCATION" "R8G6"
					( Origin gPackager )
				)
				( attribute "CDS_SEC" "1"
					( Origin gPackager )
				)
				( attribute "LOCATION" "R8G6"
					( Origin gFrontEnd )
				)
				( attribute "MATERIAL" "EMPTY"
					( Origin gFrontEnd )
				)
				( attribute "PACK_TYPE" "0402"
					( Origin gFrontEnd )
				)
				( attribute "PART_NUMBER" "G21796-311"
					( Origin gFrontEnd )
				)
				( attribute "PHYS_PAGE" "159"
					( Origin gFrontEnd )
				)
				( attribute "ROOM" "SMBUS"
					( Origin gFrontEnd )
				)
				( attribute "ROT" "0"
					( Origin gFrontEnd )
				)
				( attribute "SEC" "1"
					( Origin gPackager )
				)
				( attribute "SKU" "B"
					( Origin gFrontEnd )
				)
				( attribute "TOLERANCE" "1.0%"
					( Origin gFrontEnd )
				)
				( attribute "VALUE" "2.26K"
					( Origin gFrontEnd )
				)
				( attribute "VER" "2"
					( Origin gFrontEnd )
				)
				( attribute "WATTAGE" "1/16W"
					( Origin gFrontEnd )
				)
				( attribute "XY" "(-3725,2900)"
					( Origin gFrontEnd )
				)
				( attribute "CHIPS_PART_NAME" "RES"
					( Origin gPackager )
				)
				( attribute "CDS_PART_NAME" "RES_0402-2.26K,1.0%,1/16W,EMPTA"
					( Origin gPackager )
				)
				( objectStatus "R8G6" )
				( pin "a"
					( attribute "PN" "1"
						( Origin gPackager )
					)
					( objectStatus "R8G6.1" )
				)
				( pin "b"
					( attribute "PN" "2"
						( Origin gPackager )
					)
					( objectStatus "R8G6.2" )
				)
			)
			( gate "@baseboard_fab2_lib.baseboard_fab2(sch_1):page159_i214"
				( attribute "BOM_COST" "SM_CONTROLLER"
					( Origin gFrontEnd )
				)
				( attribute "CDS_LIB" "mstr_discrete"
					( Origin gPackager )
				)
				( attribute "CDS_LOCATION" "R2U5"
					( Origin gPackager )
				)
				( attribute "CDS_SEC" "1"
					( Origin gPackager )
				)
				( attribute "LOCATION" "R2U5"
					( Origin gFrontEnd )
				)
				( attribute "MATERIAL" "CHIP"
					( Origin gFrontEnd )
				)
				( attribute "PACK_TYPE" "0402"
					( Origin gFrontEnd )
				)
				( attribute "PART_NUMBER" "G21796-311"
					( Origin gFrontEnd )
				)
				( attribute "PHYS_PAGE" "159"
					( Origin gFrontEnd )
				)
				( attribute "ROOM" "SMBUS"
					( Origin gFrontEnd )
				)
				( attribute "ROT" "0"
					( Origin gFrontEnd )
				)
				( attribute "SEC" "1"
					( Origin gPackager )
				)
				( attribute "SKU" "B"
					( Origin gFrontEnd )
				)
				( attribute "TOLERANCE" "1.0%"
					( Origin gFrontEnd )
				)
				( attribute "VALUE" "2.26K"
					( Origin gFrontEnd )
				)
				( attribute "VER" "2"
					( Origin gFrontEnd )
				)
				( attribute "WATTAGE" "1/16W"
					( Origin gFrontEnd )
				)
				( attribute "XY" "(550,4825)"
					( Origin gFrontEnd )
				)
				( attribute "CHIPS_PART_NAME" "RES"
					( Origin gPackager )
				)
				( attribute "CDS_PART_NAME" "RES_0402-2.26K,1.0%,1/16W,CHIPA"
					( Origin gPackager )
				)
				( objectStatus "R2U5" )
				( pin "a"
					( attribute "PN" "1"
						( Origin gPackager )
					)
					( objectStatus "R2U5.1" )
				)
				( pin "b"
					( attribute "PN" "2"
						( Origin gPackager )
					)
					( objectStatus "R2U5.2" )
				)
			)
			( gate "@baseboard_fab2_lib.baseboard_fab2(sch_1):page159_i216"
				( attribute "BOM_COST" "SM_CONTROLLER"
					( Origin gFrontEnd )
				)
				( attribute "CDS_LIB" "mstr_discrete"
					( Origin gPackager )
				)
				( attribute "CDS_LOCATION" "R2U13"
					( Origin gPackager )
				)
				( attribute "CDS_SEC" "1"
					( Origin gPackager )
				)
				( attribute "LOCATION" "R2U13"
					( Origin gFrontEnd )
				)
				( attribute "MATERIAL" "CHIP"
					( Origin gFrontEnd )
				)
				( attribute "PACK_TYPE" "0402"
					( Origin gFrontEnd )
				)
				( attribute "PART_NUMBER" "G21796-311"
					( Origin gFrontEnd )
				)
				( attribute "PHYS_PAGE" "159"
					( Origin gFrontEnd )
				)
				( attribute "ROOM" "SMBUS"
					( Origin gFrontEnd )
				)
				( attribute "ROT" "0"
					( Origin gFrontEnd )
				)
				( attribute "SEC" "1"
					( Origin gPackager )
				)
				( attribute "SKU" "B"
					( Origin gFrontEnd )
				)
				( attribute "TOLERANCE" "1.0%"
					( Origin gFrontEnd )
				)
				( attribute "VALUE" "2.26K"
					( Origin gFrontEnd )
				)
				( attribute "VER" "2"
					( Origin gFrontEnd )
				)
				( attribute "WATTAGE" "1/16W"
					( Origin gFrontEnd )
				)
				( attribute "XY" "(200,4825)"
					( Origin gFrontEnd )
				)
				( attribute "CHIPS_PART_NAME" "RES"
					( Origin gPackager )
				)
				( attribute "CDS_PART_NAME" "RES_0402-2.26K,1.0%,1/16W,CHIPA"
					( Origin gPackager )
				)
				( objectStatus "R2U13" )
				( pin "a"
					( attribute "PN" "1"
						( Origin gPackager )
					)
					( objectStatus "R2U13.1" )
				)
				( pin "b"
					( attribute "PN" "2"
						( Origin gPackager )
					)
					( objectStatus "R2U13.2" )
				)
			)
			( gate "@baseboard_fab2_lib.baseboard_fab2(sch_1):page159_i218"
				( attribute "BOM_COST" "SM_CONTROLLER"
					( Origin gFrontEnd )
				)
				( attribute "CDS_LIB" "mstr_discrete"
					( Origin gPackager )
				)
				( attribute "CDS_LOCATION" "R2U1"
					( Origin gPackager )
				)
				( attribute "CDS_SEC" "1"
					( Origin gPackager )
				)
				( attribute "LOCATION" "R2U1"
					( Origin gFrontEnd )
				)
				( attribute "MATERIAL" "CHIP"
					( Origin gFrontEnd )
				)
				( attribute "PACK_TYPE" "0402"
					( Origin gFrontEnd )
				)
				( attribute "PART_NUMBER" "G21796-173"
					( Origin gFrontEnd )
				)
				( attribute "PHYS_PAGE" "159"
					( Origin gFrontEnd )
				)
				( attribute "ROOM" "SMBUS"
					( Origin gFrontEnd )
				)
				( attribute "ROT" "0"
					( Origin gFrontEnd )
				)
				( attribute "SEC" "1"
					( Origin gPackager )
				)
				( attribute "TOLERANCE" "1%"
					( Origin gFrontEnd )
				)
				( attribute "VALUE" "20.0"
					( Origin gFrontEnd )
				)
				( attribute "VER" "1"
					( Origin gFrontEnd )
				)
				( attribute "WATTAGE" "1/16W"
					( Origin gFrontEnd )
				)
				( attribute "XY" "(700,3375)"
					( Origin gFrontEnd )
				)
				( attribute "CHIPS_PART_NAME" "RES"
					( Origin gPackager )
				)
				( attribute "CDS_PART_NAME" "RES_0402-20.0,1%,1/16W,CHIP,G2A"
					( Origin gPackager )
				)
				( objectStatus "R2U1" )
				( pin "a"
					( attribute "PN" "1"
						( Origin gPackager )
					)
					( objectStatus "R2U1.1" )
				)
				( pin "b"
					( attribute "PN" "2"
						( Origin gPackager )
					)
					( objectStatus "R2U1.2" )
				)
			)
			( gate "@baseboard_fab2_lib.baseboard_fab2(sch_1):page159_i219"
				( attribute "BOM_COST" "SM_CONTROLLER"
					( Origin gFrontEnd )
				)
				( attribute "CDS_LIB" "mstr_discrete"
					( Origin gPackager )
				)
				( attribute "CDS_LOCATION" "R2T49"
					( Origin gPackager )
				)
				( attribute "CDS_SEC" "1"
					( Origin gPackager )
				)
				( attribute "LOCATION" "R2T49"
					( Origin gFrontEnd )
				)
				( attribute "MATERIAL" "CHIP"
					( Origin gFrontEnd )
				)
				( attribute "PACK_TYPE" "0402"
					( Origin gFrontEnd )
				)
				( attribute "PART_NUMBER" "G21796-173"
					( Origin gFrontEnd )
				)
				( attribute "PHYS_PAGE" "159"
					( Origin gFrontEnd )
				)
				( attribute "ROOM" "SMBUS"
					( Origin gFrontEnd )
				)
				( attribute "ROT" "0"
					( Origin gFrontEnd )
				)
				( attribute "SEC" "1"
					( Origin gPackager )
				)
				( attribute "TOLERANCE" "1%"
					( Origin gFrontEnd )
				)
				( attribute "VALUE" "20.0"
					( Origin gFrontEnd )
				)
				( attribute "VER" "1"
					( Origin gFrontEnd )
				)
				( attribute "WATTAGE" "1/16W"
					( Origin gFrontEnd )
				)
				( attribute "XY" "(700,3550)"
					( Origin gFrontEnd )
				)
				( attribute "CHIPS_PART_NAME" "RES"
					( Origin gPackager )
				)
				( attribute "CDS_PART_NAME" "RES_0402-20.0,1%,1/16W,CHIP,G2A"
					( Origin gPackager )
				)
				( objectStatus "R2T49" )
				( pin "a"
					( attribute "PN" "1"
						( Origin gPackager )
					)
					( objectStatus "R2T49.1" )
				)
				( pin "b"
					( attribute "PN" "2"
						( Origin gPackager )
					)
					( objectStatus "R2T49.2" )
				)
			)
			( gate "@baseboard_fab2_lib.baseboard_fab2(sch_1):page159_i220"
				( attribute "BOM_COST" "SM_CONTROLLER"
					( Origin gFrontEnd )
				)
				( attribute "CDS_LIB" "mstr_discrete"
					( Origin gPackager )
				)
				( attribute "CDS_LOCATION" "R2U7"
					( Origin gPackager )
				)
				( attribute "CDS_SEC" "1"
					( Origin gPackager )
				)
				( attribute "LOCATION" "R2U7"
					( Origin gFrontEnd )
				)
				( attribute "MATERIAL" "CHIP"
					( Origin gFrontEnd )
				)
				( attribute "PACK_TYPE" "0402"
					( Origin gFrontEnd )
				)
				( attribute "PART_NUMBER" "G21796-173"
					( Origin gFrontEnd )
				)
				( attribute "PHYS_PAGE" "159"
					( Origin gFrontEnd )
				)
				( attribute "ROOM" "SMBUS"
					( Origin gFrontEnd )
				)
				( attribute "ROT" "0"
					( Origin gFrontEnd )
				)
				( attribute "SEC" "1"
					( Origin gPackager )
				)
				( attribute "TOLERANCE" "1%"
					( Origin gFrontEnd )
				)
				( attribute "VALUE" "20.0"
					( Origin gFrontEnd )
				)
				( attribute "VER" "1"
					( Origin gFrontEnd )
				)
				( attribute "WATTAGE" "1/16W"
					( Origin gFrontEnd )
				)
				( attribute "XY" "(1025,4275)"
					( Origin gFrontEnd )
				)
				( attribute "CHIPS_PART_NAME" "RES"
					( Origin gPackager )
				)
				( attribute "CDS_PART_NAME" "RES_0402-20.0,1%,1/16W,CHIP,G2A"
					( Origin gPackager )
				)
				( objectStatus "R2U7" )
				( pin "a"
					( attribute "PN" "1"
						( Origin gPackager )
					)
					( objectStatus "R2U7.1" )
				)
				( pin "b"
					( attribute "PN" "2"
						( Origin gPackager )
					)
					( objectStatus "R2U7.2" )
				)
			)
			( gate "@baseboard_fab2_lib.baseboard_fab2(sch_1):page159_i221"
				( attribute "BOM_COST" "SM_CONTROLLER"
					( Origin gFrontEnd )
				)
				( attribute "CDS_LIB" "mstr_discrete"
					( Origin gPackager )
				)
				( attribute "CDS_LOCATION" "R2U10"
					( Origin gPackager )
				)
				( attribute "CDS_SEC" "1"
					( Origin gPackager )
				)
				( attribute "LOCATION" "R2U10"
					( Origin gFrontEnd )
				)
				( attribute "MATERIAL" "CHIP"
					( Origin gFrontEnd )
				)
				( attribute "PACK_TYPE" "0402"
					( Origin gFrontEnd )
				)
				( attribute "PART_NUMBER" "G21796-173"
					( Origin gFrontEnd )
				)
				( attribute "PHYS_PAGE" "159"
					( Origin gFrontEnd )
				)
				( attribute "ROOM" "SMBUS"
					( Origin gFrontEnd )
				)
				( attribute "ROT" "0"
					( Origin gFrontEnd )
				)
				( attribute "SEC" "1"
					( Origin gPackager )
				)
				( attribute "TOLERANCE" "1%"
					( Origin gFrontEnd )
				)
				( attribute "VALUE" "20.0"
					( Origin gFrontEnd )
				)
				( attribute "VER" "1"
					( Origin gFrontEnd )
				)
				( attribute "WATTAGE" "1/16W"
					( Origin gFrontEnd )
				)
				( attribute "XY" "(1025,4450)"
					( Origin gFrontEnd )
				)
				( attribute "CHIPS_PART_NAME" "RES"
					( Origin gPackager )
				)
				( attribute "CDS_PART_NAME" "RES_0402-20.0,1%,1/16W,CHIP,G2A"
					( Origin gPackager )
				)
				( objectStatus "R2U10" )
				( pin "a"
					( attribute "PN" "1"
						( Origin gPackager )
					)
					( objectStatus "R2U10.1" )
				)
				( pin "b"
					( attribute "PN" "2"
						( Origin gPackager )
					)
					( objectStatus "R2U10.2" )
				)
			)
			( gate "@baseboard_fab2_lib.baseboard_fab2(sch_1):page159_i222"
				( attribute "BOM_COST" "SM_CONTROLLER"
					( Origin gFrontEnd )
				)
				( attribute "CDS_LIB" "mstr_discrete"
					( Origin gPackager )
				)
				( attribute "CDS_LOCATION" "R1U11"
					( Origin gPackager )
				)
				( attribute "CDS_SEC" "1"
					( Origin gPackager )
				)
				( attribute "LOCATION" "R1U11"
					( Origin gFrontEnd )
				)
				( attribute "MATERIAL" "CHIP"
					( Origin gFrontEnd )
				)
				( attribute "PACK_TYPE" "0402"
					( Origin gFrontEnd )
				)
				( attribute "PART_NUMBER" "G21497-005"
					( Origin gFrontEnd )
				)
				( attribute "PHYS_PAGE" "159"
					( Origin gFrontEnd )
				)
				( attribute "ROOM" "SMBUS"
					( Origin gFrontEnd )
				)
				( attribute "ROT" "0"
					( Origin gFrontEnd )
				)
				( attribute "SEC" "1"
					( Origin gPackager )
				)
				( attribute "TOLERANCE" "5%"
					( Origin gFrontEnd )
				)
				( attribute "VALUE" "0.0"
					( Origin gFrontEnd )
				)
				( attribute "VER" "1"
					( Origin gFrontEnd )
				)
				( attribute "WATTAGE" "1/16W"
					( Origin gFrontEnd )
				)
				( attribute "XY" "(700,1600)"
					( Origin gFrontEnd )
				)
				( attribute "CHIPS_PART_NAME" "RES"
					( Origin gPackager )
				)
				( attribute "CDS_PART_NAME" "RES_0402-0.0,5%,1/16W,CHIP,G21A"
					( Origin gPackager )
				)
				( objectStatus "R1U11" )
				( pin "a"
					( attribute "PN" "1"
						( Origin gPackager )
					)
					( objectStatus "R1U11.1" )
				)
				( pin "b"
					( attribute "PN" "2"
						( Origin gPackager )
					)
					( objectStatus "R1U11.2" )
				)
			)
			( gate "@baseboard_fab2_lib.baseboard_fab2(sch_1):page159_i223"
				( attribute "BOM_COST" "SM_CONTROLLER"
					( Origin gFrontEnd )
				)
				( attribute "CDS_LIB" "mstr_discrete"
					( Origin gPackager )
				)
				( attribute "CDS_LOCATION" "R1U8"
					( Origin gPackager )
				)
				( attribute "CDS_SEC" "1"
					( Origin gPackager )
				)
				( attribute "LOCATION" "R1U8"
					( Origin gFrontEnd )
				)
				( attribute "MATERIAL" "CHIP"
					( Origin gFrontEnd )
				)
				( attribute "PACK_TYPE" "0402"
					( Origin gFrontEnd )
				)
				( attribute "PART_NUMBER" "G21497-005"
					( Origin gFrontEnd )
				)
				( attribute "PHYS_PAGE" "159"
					( Origin gFrontEnd )
				)
				( attribute "ROOM" "SMBUS"
					( Origin gFrontEnd )
				)
				( attribute "ROT" "0"
					( Origin gFrontEnd )
				)
				( attribute "SEC" "1"
					( Origin gPackager )
				)
				( attribute "TOLERANCE" "5%"
					( Origin gFrontEnd )
				)
				( attribute "VALUE" "0.0"
					( Origin gFrontEnd )
				)
				( attribute "VER" "1"
					( Origin gFrontEnd )
				)
				( attribute "WATTAGE" "1/16W"
					( Origin gFrontEnd )
				)
				( attribute "XY" "(700,1775)"
					( Origin gFrontEnd )
				)
				( attribute "CHIPS_PART_NAME" "RES"
					( Origin gPackager )
				)
				( attribute "CDS_PART_NAME" "RES_0402-0.0,5%,1/16W,CHIP,G21A"
					( Origin gPackager )
				)
				( objectStatus "R1U8" )
				( pin "a"
					( attribute "PN" "1"
						( Origin gPackager )
					)
					( objectStatus "R1U8.1" )
				)
				( pin "b"
					( attribute "PN" "2"
						( Origin gPackager )
					)
					( objectStatus "R1U8.2" )
				)
			)
			( gate "@baseboard_fab2_lib.baseboard_fab2(sch_1):page159_i224"
				( attribute "BOM_COST" "SM_CONTROLLER"
					( Origin gFrontEnd )
				)
				( attribute "CDS_LIB" "mstr_discrete"
					( Origin gPackager )
				)
				( attribute "CDS_LOCATION" "R9G12"
					( Origin gPackager )
				)
				( attribute "CDS_SEC" "1"
					( Origin gPackager )
				)
				( attribute "LOCATION" "R9G12"
					( Origin gFrontEnd )
				)
				( attribute "MATERIAL" "CHIP"
					( Origin gFrontEnd )
				)
				( attribute "PACK_TYPE" "0402"
					( Origin gFrontEnd )
				)
				( attribute "PART_NUMBER" "G21796-173"
					( Origin gFrontEnd )
				)
				( attribute "PHYS_PAGE" "159"
					( Origin gFrontEnd )
				)
				( attribute "ROOM" "SMBUS"
					( Origin gFrontEnd )
				)
				( attribute "ROT" "0"
					( Origin gFrontEnd )
				)
				( attribute "SEC" "1"
					( Origin gPackager )
				)
				( attribute "TOLERANCE" "1%"
					( Origin gFrontEnd )
				)
				( attribute "VALUE" "20.0"
					( Origin gFrontEnd )
				)
				( attribute "VER" "1"
					( Origin gFrontEnd )
				)
				( attribute "WATTAGE" "1/16W"
					( Origin gFrontEnd )
				)
				( attribute "XY" "(-3625,1575)"
					( Origin gFrontEnd )
				)
				( attribute "CHIPS_PART_NAME" "RES"
					( Origin gPackager )
				)
				( attribute "CDS_PART_NAME" "RES_0402-20.0,1%,1/16W,CHIP,G2A"
					( Origin gPackager )
				)
				( objectStatus "R9G12" )
				( pin "a"
					( attribute "PN" "1"
						( Origin gPackager )
					)
					( objectStatus "R9G12.1" )
				)
				( pin "b"
					( attribute "PN" "2"
						( Origin gPackager )
					)
					( objectStatus "R9G12.2" )
				)
			)
			( gate "@baseboard_fab2_lib.baseboard_fab2(sch_1):page159_i225"
				( attribute "BOM_COST" "SM_CONTROLLER"
					( Origin gFrontEnd )
				)
				( attribute "CDS_LIB" "mstr_discrete"
					( Origin gPackager )
				)
				( attribute "CDS_LOCATION" "R1U20"
					( Origin gPackager )
				)
				( attribute "CDS_SEC" "1"
					( Origin gPackager )
				)
				( attribute "LOCATION" "R1U20"
					( Origin gFrontEnd )
				)
				( attribute "MATERIAL" "CHIP"
					( Origin gFrontEnd )
				)
				( attribute "PACK_TYPE" "0402"
					( Origin gFrontEnd )
				)
				( attribute "PART_NUMBER" "G21796-173"
					( Origin gFrontEnd )
				)
				( attribute "PHYS_PAGE" "159"
					( Origin gFrontEnd )
				)
				( attribute "ROOM" "SMBUS"
					( Origin gFrontEnd )
				)
				( attribute "ROT" "0"
					( Origin gFrontEnd )
				)
				( attribute "SEC" "1"
					( Origin gPackager )
				)
				( attribute "TOLERANCE" "1%"
					( Origin gFrontEnd )
				)
				( attribute "VALUE" "20.0"
					( Origin gFrontEnd )
				)
				( attribute "VER" "1"
					( Origin gFrontEnd )
				)
				( attribute "WATTAGE" "1/16W"
					( Origin gFrontEnd )
				)
				( attribute "XY" "(-3625,1450)"
					( Origin gFrontEnd )
				)
				( attribute "CHIPS_PART_NAME" "RES"
					( Origin gPackager )
				)
				( attribute "CDS_PART_NAME" "RES_0402-20.0,1%,1/16W,CHIP,G2A"
					( Origin gPackager )
				)
				( objectStatus "R1U20" )
				( pin "a"
					( attribute "PN" "1"
						( Origin gPackager )
					)
					( objectStatus "R1U20.1" )
				)
				( pin "b"
					( attribute "PN" "2"
						( Origin gPackager )
					)
					( objectStatus "R1U20.2" )
				)
			)
			( gate "@baseboard_fab2_lib.baseboard_fab2(sch_1):page159_i226"
				( attribute "BOM_COST" "SM_CONTROLLER"
					( Origin gFrontEnd )
				)
				( attribute "CDS_LIB" "mstr_discrete"
					( Origin gPackager )
				)
				( attribute "CDS_LOCATION" "R1U19"
					( Origin gPackager )
				)
				( attribute "CDS_SEC" "1"
					( Origin gPackager )
				)
				( attribute "LOCATION" "R1U19"
					( Origin gFrontEnd )
				)
				( attribute "MATERIAL" "CHIP"
					( Origin gFrontEnd )
				)
				( attribute "PACK_TYPE" "0402"
					( Origin gFrontEnd )
				)
				( attribute "PART_NUMBER" "G21796-173"
					( Origin gFrontEnd )
				)
				( attribute "PHYS_PAGE" "159"
					( Origin gFrontEnd )
				)
				( attribute "ROOM" "SMBUS"
					( Origin gFrontEnd )
				)
				( attribute "ROT" "0"
					( Origin gFrontEnd )
				)
				( attribute "SEC" "1"
					( Origin gPackager )
				)
				( attribute "TOLERANCE" "1%"
					( Origin gFrontEnd )
				)
				( attribute "VALUE" "20.0"
					( Origin gFrontEnd )
				)
				( attribute "VER" "1"
					( Origin gFrontEnd )
				)
				( attribute "WATTAGE" "1/16W"
					( Origin gFrontEnd )
				)
				( attribute "XY" "(-3625,1325)"
					( Origin gFrontEnd )
				)
				( attribute "CHIPS_PART_NAME" "RES"
					( Origin gPackager )
				)
				( attribute "CDS_PART_NAME" "RES_0402-20.0,1%,1/16W,CHIP,G2A"
					( Origin gPackager )
				)
				( objectStatus "R1U19" )
				( pin "a"
					( attribute "PN" "1"
						( Origin gPackager )
					)
					( objectStatus "R1U19.1" )
				)
				( pin "b"
					( attribute "PN" "2"
						( Origin gPackager )
					)
					( objectStatus "R1U19.2" )
				)
			)
			( gate "@baseboard_fab2_lib.baseboard_fab2(sch_1):page159_i227"
				( attribute "BOM_COST" "SM_CONTROLLER"
					( Origin gFrontEnd )
				)
				( attribute "CDS_LIB" "mstr_discrete"
					( Origin gPackager )
				)
				( attribute "CDS_LOCATION" "R9G13"
					( Origin gPackager )
				)
				( attribute "CDS_SEC" "1"
					( Origin gPackager )
				)
				( attribute "LOCATION" "R9G13"
					( Origin gFrontEnd )
				)
				( attribute "MATERIAL" "CHIP"
					( Origin gFrontEnd )
				)
				( attribute "PACK_TYPE" "0402"
					( Origin gFrontEnd )
				)
				( attribute "PART_NUMBER" "G21796-173"
					( Origin gFrontEnd )
				)
				( attribute "PHYS_PAGE" "159"
					( Origin gFrontEnd )
				)
				( attribute "ROOM" "SMBUS"
					( Origin gFrontEnd )
				)
				( attribute "ROT" "0"
					( Origin gFrontEnd )
				)
				( attribute "SEC" "1"
					( Origin gPackager )
				)
				( attribute "TOLERANCE" "1%"
					( Origin gFrontEnd )
				)
				( attribute "VALUE" "20.0"
					( Origin gFrontEnd )
				)
				( attribute "VER" "1"
					( Origin gFrontEnd )
				)
				( attribute "WATTAGE" "1/16W"
					( Origin gFrontEnd )
				)
				( attribute "XY" "(-3625,1200)"
					( Origin gFrontEnd )
				)
				( attribute "CHIPS_PART_NAME" "RES"
					( Origin gPackager )
				)
				( attribute "CDS_PART_NAME" "RES_0402-20.0,1%,1/16W,CHIP,G2A"
					( Origin gPackager )
				)
				( objectStatus "R9G13" )
				( pin "a"
					( attribute "PN" "1"
						( Origin gPackager )
					)
					( objectStatus "R9G13.1" )
				)
				( pin "b"
					( attribute "PN" "2"
						( Origin gPackager )
					)
					( objectStatus "R9G13.2" )
				)
			)
			( gate "@baseboard_fab2_lib.baseboard_fab2(sch_1):page159_i228"
				( attribute "BOM_COST" "SM_CONTROLLER"
					( Origin gFrontEnd )
				)
				( attribute "CDS_LIB" "mstr_discrete"
					( Origin gPackager )
				)
				( attribute "CDS_LOCATION" "R8G5"
					( Origin gPackager )
				)
				( attribute "CDS_SEC" "1"
					( Origin gPackager )
				)
				( attribute "LOCATION" "R8G5"
					( Origin gFrontEnd )
				)
				( attribute "MATERIAL" "CHIP"
					( Origin gFrontEnd )
				)
				( attribute "PACK_TYPE" "0402"
					( Origin gFrontEnd )
				)
				( attribute "PART_NUMBER" "G21796-173"
					( Origin gFrontEnd )
				)
				( attribute "PHYS_PAGE" "159"
					( Origin gFrontEnd )
				)
				( attribute "ROOM" "SMBUS"
					( Origin gFrontEnd )
				)
				( attribute "ROT" "0"
					( Origin gFrontEnd )
				)
				( attribute "SEC" "1"
					( Origin gPackager )
				)
				( attribute "TOLERANCE" "1%"
					( Origin gFrontEnd )
				)
				( attribute "VALUE" "20.0"
					( Origin gFrontEnd )
				)
				( attribute "VER" "1"
					( Origin gFrontEnd )
				)
				( attribute "WATTAGE" "1/16W"
					( Origin gFrontEnd )
				)
				( attribute "XY" "(-2875,2525)"
					( Origin gFrontEnd )
				)
				( attribute "CHIPS_PART_NAME" "RES"
					( Origin gPackager )
				)
				( attribute "CDS_PART_NAME" "RES_0402-20.0,1%,1/16W,CHIP,G2A"
					( Origin gPackager )
				)
				( objectStatus "R8G5" )
				( pin "a"
					( attribute "PN" "1"
						( Origin gPackager )
					)
					( objectStatus "R8G5.1" )
				)
				( pin "b"
					( attribute "PN" "2"
						( Origin gPackager )
					)
					( objectStatus "R8G5.2" )
				)
			)
			( gate "@baseboard_fab2_lib.baseboard_fab2(sch_1):page159_i229"
				( attribute "BOM_COST" "SM_CONTROLLER"
					( Origin gFrontEnd )
				)
				( attribute "CDS_LIB" "mstr_discrete"
					( Origin gPackager )
				)
				( attribute "CDS_LOCATION" "R8G4"
					( Origin gPackager )
				)
				( attribute "CDS_SEC" "1"
					( Origin gPackager )
				)
				( attribute "LOCATION" "R8G4"
					( Origin gFrontEnd )
				)
				( attribute "MATERIAL" "CHIP"
					( Origin gFrontEnd )
				)
				( attribute "PACK_TYPE" "0402"
					( Origin gFrontEnd )
				)
				( attribute "PART_NUMBER" "G21796-173"
					( Origin gFrontEnd )
				)
				( attribute "PHYS_PAGE" "159"
					( Origin gFrontEnd )
				)
				( attribute "ROOM" "SMBUS"
					( Origin gFrontEnd )
				)
				( attribute "ROT" "0"
					( Origin gFrontEnd )
				)
				( attribute "SEC" "1"
					( Origin gPackager )
				)
				( attribute "TOLERANCE" "1%"
					( Origin gFrontEnd )
				)
				( attribute "VALUE" "20.0"
					( Origin gFrontEnd )
				)
				( attribute "VER" "1"
					( Origin gFrontEnd )
				)
				( attribute "WATTAGE" "1/16W"
					( Origin gFrontEnd )
				)
				( attribute "XY" "(-2875,2350)"
					( Origin gFrontEnd )
				)
				( attribute "CHIPS_PART_NAME" "RES"
					( Origin gPackager )
				)
				( attribute "CDS_PART_NAME" "RES_0402-20.0,1%,1/16W,CHIP,G2A"
					( Origin gPackager )
				)
				( objectStatus "R8G4" )
				( pin "a"
					( attribute "PN" "1"
						( Origin gPackager )
					)
					( objectStatus "R8G4.1" )
				)
				( pin "b"
					( attribute "PN" "2"
						( Origin gPackager )
					)
					( objectStatus "R8G4.2" )
				)
			)
			( gate "@baseboard_fab2_lib.baseboard_fab2(sch_1):page159_i230"
				( attribute "BOM_COST" "SM_CONTROLLER"
					( Origin gFrontEnd )
				)
				( attribute "CDS_LIB" "mstr_discrete"
					( Origin gPackager )
				)
				( attribute "CDS_LOCATION" "R2U34"
					( Origin gPackager )
				)
				( attribute "CDS_SEC" "1"
					( Origin gPackager )
				)
				( attribute "LOCATION" "R2U34"
					( Origin gFrontEnd )
				)
				( attribute "MATERIAL" "CHIP"
					( Origin gFrontEnd )
				)
				( attribute "PACK_TYPE" "0402"
					( Origin gFrontEnd )
				)
				( attribute "PART_NUMBER" "G21796-173"
					( Origin gFrontEnd )
				)
				( attribute "PHYS_PAGE" "159"
					( Origin gFrontEnd )
				)
				( attribute "ROOM" "SMBUS"
					( Origin gFrontEnd )
				)
				( attribute "ROT" "0"
					( Origin gFrontEnd )
				)
				( attribute "SEC" "1"
					( Origin gPackager )
				)
				( attribute "TOLERANCE" "1%"
					( Origin gFrontEnd )
				)
				( attribute "VALUE" "20.0"
					( Origin gFrontEnd )
				)
				( attribute "VER" "1"
					( Origin gFrontEnd )
				)
				( attribute "WATTAGE" "1/16W"
					( Origin gFrontEnd )
				)
				( attribute "XY" "(-3175,3600)"
					( Origin gFrontEnd )
				)
				( attribute "CHIPS_PART_NAME" "RES"
					( Origin gPackager )
				)
				( attribute "CDS_PART_NAME" "RES_0402-20.0,1%,1/16W,CHIP,G2A"
					( Origin gPackager )
				)
				( objectStatus "R2U34" )
				( pin "a"
					( attribute "PN" "1"
						( Origin gPackager )
					)
					( objectStatus "R2U34.1" )
				)
				( pin "b"
					( attribute "PN" "2"
						( Origin gPackager )
					)
					( objectStatus "R2U34.2" )
				)
			)
			( gate "@baseboard_fab2_lib.baseboard_fab2(sch_1):page159_i231"
				( attribute "BOM_COST" "SM_CONTROLLER"
					( Origin gFrontEnd )
				)
				( attribute "CDS_LIB" "mstr_discrete"
					( Origin gPackager )
				)
				( attribute "CDS_LOCATION" "R2U33"
					( Origin gPackager )
				)
				( attribute "CDS_SEC" "1"
					( Origin gPackager )
				)
				( attribute "LOCATION" "R2U33"
					( Origin gFrontEnd )
				)
				( attribute "MATERIAL" "CHIP"
					( Origin gFrontEnd )
				)
				( attribute "PACK_TYPE" "0402"
					( Origin gFrontEnd )
				)
				( attribute "PART_NUMBER" "G21796-173"
					( Origin gFrontEnd )
				)
				( attribute "PHYS_PAGE" "159"
					( Origin gFrontEnd )
				)
				( attribute "ROOM" "SMBUS"
					( Origin gFrontEnd )
				)
				( attribute "ROT" "0"
					( Origin gFrontEnd )
				)
				( attribute "SEC" "1"
					( Origin gPackager )
				)
				( attribute "TOLERANCE" "1%"
					( Origin gFrontEnd )
				)
				( attribute "VALUE" "20.0"
					( Origin gFrontEnd )
				)
				( attribute "VER" "1"
					( Origin gFrontEnd )
				)
				( attribute "WATTAGE" "1/16W"
					( Origin gFrontEnd )
				)
				( attribute "XY" "(-3175,3775)"
					( Origin gFrontEnd )
				)
				( attribute "CHIPS_PART_NAME" "RES"
					( Origin gPackager )
				)
				( attribute "CDS_PART_NAME" "RES_0402-20.0,1%,1/16W,CHIP,G2A"
					( Origin gPackager )
				)
				( objectStatus "R2U33" )
				( pin "a"
					( attribute "PN" "1"
						( Origin gPackager )
					)
					( objectStatus "R2U33.1" )
				)
				( pin "b"
					( attribute "PN" "2"
						( Origin gPackager )
					)
					( objectStatus "R2U33.2" )
				)
			)
			( gate "@baseboard_fab2_lib.baseboard_fab2(sch_1):page159_i232"
				( attribute "BOM_COST" "SM_CONTROLLER"
					( Origin gFrontEnd )
				)
				( attribute "CDS_LIB" "mstr_discrete"
					( Origin gPackager )
				)
				( attribute "CDS_LOCATION" "R1U9"
					( Origin gPackager )
				)
				( attribute "CDS_SEC" "1"
					( Origin gPackager )
				)
				( attribute "LOCATION" "R1U9"
					( Origin gFrontEnd )
				)
				( attribute "MATERIAL" "CHIP"
					( Origin gFrontEnd )
				)
				( attribute "PACK_TYPE" "0402"
					( Origin gFrontEnd )
				)
				( attribute "PART_NUMBER" "G21796-173"
					( Origin gFrontEnd )
				)
				( attribute "PHYS_PAGE" "159"
					( Origin gFrontEnd )
				)
				( attribute "ROOM" "SMBUS"
					( Origin gFrontEnd )
				)
				( attribute "ROT" "0"
					( Origin gFrontEnd )
				)
				( attribute "SEC" "1"
					( Origin gPackager )
				)
				( attribute "TOLERANCE" "1%"
					( Origin gFrontEnd )
				)
				( attribute "VALUE" "20.0"
					( Origin gFrontEnd )
				)
				( attribute "VER" "1"
					( Origin gFrontEnd )
				)
				( attribute "WATTAGE" "1/16W"
					( Origin gFrontEnd )
				)
				( attribute "XY" "(-3175,4200)"
					( Origin gFrontEnd )
				)
				( attribute "CHIPS_PART_NAME" "RES"
					( Origin gPackager )
				)
				( attribute "CDS_PART_NAME" "RES_0402-20.0,1%,1/16W,CHIP,G2A"
					( Origin gPackager )
				)
				( objectStatus "R1U9" )
				( pin "a"
					( attribute "PN" "1"
						( Origin gPackager )
					)
					( objectStatus "R1U9.1" )
				)
				( pin "b"
					( attribute "PN" "2"
						( Origin gPackager )
					)
					( objectStatus "R1U9.2" )
				)
			)
			( gate "@baseboard_fab2_lib.baseboard_fab2(sch_1):page159_i233"
				( attribute "BOM_COST" "SM_CONTROLLER"
					( Origin gFrontEnd )
				)
				( attribute "CDS_LIB" "mstr_discrete"
					( Origin gPackager )
				)
				( attribute "CDS_LOCATION" "R1U10"
					( Origin gPackager )
				)
				( attribute "CDS_SEC" "1"
					( Origin gPackager )
				)
				( attribute "LOCATION" "R1U10"
					( Origin gFrontEnd )
				)
				( attribute "MATERIAL" "CHIP"
					( Origin gFrontEnd )
				)
				( attribute "PACK_TYPE" "0402"
					( Origin gFrontEnd )
				)
				( attribute "PART_NUMBER" "G21796-173"
					( Origin gFrontEnd )
				)
				( attribute "PHYS_PAGE" "159"
					( Origin gFrontEnd )
				)
				( attribute "ROOM" "SMBUS"
					( Origin gFrontEnd )
				)
				( attribute "ROT" "0"
					( Origin gFrontEnd )
				)
				( attribute "SEC" "1"
					( Origin gPackager )
				)
				( attribute "TOLERANCE" "1%"
					( Origin gFrontEnd )
				)
				( attribute "VALUE" "20.0"
					( Origin gFrontEnd )
				)
				( attribute "VER" "1"
					( Origin gFrontEnd )
				)
				( attribute "WATTAGE" "1/16W"
					( Origin gFrontEnd )
				)
				( attribute "XY" "(-3175,4375)"
					( Origin gFrontEnd )
				)
				( attribute "CHIPS_PART_NAME" "RES"
					( Origin gPackager )
				)
				( attribute "CDS_PART_NAME" "RES_0402-20.0,1%,1/16W,CHIP,G2A"
					( Origin gPackager )
				)
				( objectStatus "R1U10" )
				( pin "a"
					( attribute "PN" "1"
						( Origin gPackager )
					)
					( objectStatus "R1U10.1" )
				)
				( pin "b"
					( attribute "PN" "2"
						( Origin gPackager )
					)
					( objectStatus "R1U10.2" )
				)
			)
			( gate "@baseboard_fab2_lib.baseboard_fab2(sch_1):page160_i4"
				( attribute "BOM_COST" "SM_CONTROLLER"
					( Origin gFrontEnd )
				)
				( attribute "CDS_LIB" "mstr_discrete"
					( Origin gPackager )
				)
				( attribute "CDS_LOCATION" "R1T8"
					( Origin gPackager )
				)
				( attribute "CDS_SEC" "1"
					( Origin gPackager )
				)
				( attribute "LOCATION" "R1T8"
					( Origin gFrontEnd )
				)
				( attribute "MATERIAL" "CHIP"
					( Origin gFrontEnd )
				)
				( attribute "PACK_TYPE" "0402"
					( Origin gFrontEnd )
				)
				( attribute "PART_NUMBER" "G21796-173"
					( Origin gFrontEnd )
				)
				( attribute "PHYS_PAGE" "160"
					( Origin gFrontEnd )
				)
				( attribute "ROOM" "SMBUS"
					( Origin gFrontEnd )
				)
				( attribute "ROT" "0"
					( Origin gFrontEnd )
				)
				( attribute "SEC" "1"
					( Origin gPackager )
				)
				( attribute "TOLERANCE" "1%"
					( Origin gFrontEnd )
				)
				( attribute "VALUE" "20.0"
					( Origin gFrontEnd )
				)
				( attribute "VER" "1"
					( Origin gFrontEnd )
				)
				( attribute "WATTAGE" "1/16W"
					( Origin gFrontEnd )
				)
				( attribute "XY" "(-3350,4600)"
					( Origin gFrontEnd )
				)
				( attribute "CHIPS_PART_NAME" "RES"
					( Origin gPackager )
				)
				( attribute "CDS_PART_NAME" "RES_0402-20.0,1%,1/16W,CHIP,G2A"
					( Origin gPackager )
				)
				( objectStatus "R1T8" )
				( pin "a"
					( attribute "PN" "1"
						( Origin gPackager )
					)
					( objectStatus "R1T8.1" )
				)
				( pin "b"
					( attribute "PN" "2"
						( Origin gPackager )
					)
					( objectStatus "R1T8.2" )
				)
			)
			( gate "@baseboard_fab2_lib.baseboard_fab2(sch_1):page160_i46"
				( attribute "BOM_COST" "SM_CONTROLLER"
					( Origin gFrontEnd )
				)
				( attribute "CDS_LIB" "mstr_discrete"
					( Origin gPackager )
				)
				( attribute "CDS_LOCATION" "R1T3"
					( Origin gPackager )
				)
				( attribute "CDS_SEC" "1"
					( Origin gPackager )
				)
				( attribute "LOCATION" "R1T3"
					( Origin gFrontEnd )
				)
				( attribute "MATERIAL" "CHIP"
					( Origin gFrontEnd )
				)
				( attribute "PACK_TYPE" "0402"
					( Origin gFrontEnd )
				)
				( attribute "PART_NUMBER" "G21796-235"
					( Origin gFrontEnd )
				)
				( attribute "PHYS_PAGE" "160"
					( Origin gFrontEnd )
				)
				( attribute "ROOM" "SMBUS"
					( Origin gFrontEnd )
				)
				( attribute "ROT" "0"
					( Origin gFrontEnd )
				)
				( attribute "SEC" "1"
					( Origin gPackager )
				)
				( attribute "SKU" "B"
					( Origin gFrontEnd )
				)
				( attribute "TOLERANCE" "1.0%"
					( Origin gFrontEnd )
				)
				( attribute "VALUE" "665"
					( Origin gFrontEnd )
				)
				( attribute "VER" "2"
					( Origin gFrontEnd )
				)
				( attribute "WATTAGE" "1/16W"
					( Origin gFrontEnd )
				)
				( attribute "XY" "(-4000,4975)"
					( Origin gFrontEnd )
				)
				( attribute "CHIPS_PART_NAME" "RES"
					( Origin gPackager )
				)
				( attribute "CDS_PART_NAME" "RES_0402-665,1.0%,1/16W,CHIP,GA"
					( Origin gPackager )
				)
				( objectStatus "R1T3" )
				( pin "a"
					( attribute "PN" "1"
						( Origin gPackager )
					)
					( objectStatus "R1T3.1" )
				)
				( pin "b"
					( attribute "PN" "2"
						( Origin gPackager )
					)
					( objectStatus "R1T3.2" )
				)
			)
			( gate "@baseboard_fab2_lib.baseboard_fab2(sch_1):page160_i49"
				( attribute "BOM_COST" "SM_CONTROLLER"
					( Origin gFrontEnd )
				)
				( attribute "CDS_LIB" "mstr_discrete"
					( Origin gPackager )
				)
				( attribute "CDS_LOCATION" "R1T2"
					( Origin gPackager )
				)
				( attribute "CDS_SEC" "1"
					( Origin gPackager )
				)
				( attribute "LOCATION" "R1T2"
					( Origin gFrontEnd )
				)
				( attribute "MATERIAL" "CHIP"
					( Origin gFrontEnd )
				)
				( attribute "PACK_TYPE" "0402"
					( Origin gFrontEnd )
				)
				( attribute "PART_NUMBER" "G21796-235"
					( Origin gFrontEnd )
				)
				( attribute "PHYS_PAGE" "160"
					( Origin gFrontEnd )
				)
				( attribute "ROOM" "SMBUS"
					( Origin gFrontEnd )
				)
				( attribute "ROT" "0"
					( Origin gFrontEnd )
				)
				( attribute "SEC" "1"
					( Origin gPackager )
				)
				( attribute "SKU" "B"
					( Origin gFrontEnd )
				)
				( attribute "TOLERANCE" "1.0%"
					( Origin gFrontEnd )
				)
				( attribute "VALUE" "665"
					( Origin gFrontEnd )
				)
				( attribute "VER" "2"
					( Origin gFrontEnd )
				)
				( attribute "WATTAGE" "1/16W"
					( Origin gFrontEnd )
				)
				( attribute "XY" "(-3650,4975)"
					( Origin gFrontEnd )
				)
				( attribute "CHIPS_PART_NAME" "RES"
					( Origin gPackager )
				)
				( attribute "CDS_PART_NAME" "RES_0402-665,1.0%,1/16W,CHIP,GA"
					( Origin gPackager )
				)
				( objectStatus "R1T2" )
				( pin "a"
					( attribute "PN" "1"
						( Origin gPackager )
					)
					( objectStatus "R1T2.1" )
				)
				( pin "b"
					( attribute "PN" "2"
						( Origin gPackager )
					)
					( objectStatus "R1T2.2" )
				)
			)
			( gate "@baseboard_fab2_lib.baseboard_fab2(sch_1):page160_i50"
				( attribute "BOM_COST" "SM_CONTROLLER"
					( Origin gFrontEnd )
				)
				( attribute "CDS_LIB" "mstr_discrete"
					( Origin gPackager )
				)
				( attribute "CDS_LOCATION" "R1T7"
					( Origin gPackager )
				)
				( attribute "CDS_SEC" "1"
					( Origin gPackager )
				)
				( attribute "LOCATION" "R1T7"
					( Origin gFrontEnd )
				)
				( attribute "MATERIAL" "CHIP"
					( Origin gFrontEnd )
				)
				( attribute "PACK_TYPE" "0402"
					( Origin gFrontEnd )
				)
				( attribute "PART_NUMBER" "G21796-173"
					( Origin gFrontEnd )
				)
				( attribute "PHYS_PAGE" "160"
					( Origin gFrontEnd )
				)
				( attribute "ROOM" "SMBUS"
					( Origin gFrontEnd )
				)
				( attribute "ROT" "0"
					( Origin gFrontEnd )
				)
				( attribute "SEC" "1"
					( Origin gPackager )
				)
				( attribute "TOLERANCE" "1%"
					( Origin gFrontEnd )
				)
				( attribute "VALUE" "20.0"
					( Origin gFrontEnd )
				)
				( attribute "VER" "1"
					( Origin gFrontEnd )
				)
				( attribute "WATTAGE" "1/16W"
					( Origin gFrontEnd )
				)
				( attribute "XY" "(-3350,4425)"
					( Origin gFrontEnd )
				)
				( attribute "CHIPS_PART_NAME" "RES"
					( Origin gPackager )
				)
				( attribute "CDS_PART_NAME" "RES_0402-20.0,1%,1/16W,CHIP,G2A"
					( Origin gPackager )
				)
				( objectStatus "R1T7" )
				( pin "a"
					( attribute "PN" "1"
						( Origin gPackager )
					)
					( objectStatus "R1T7.1" )
				)
				( pin "b"
					( attribute "PN" "2"
						( Origin gPackager )
					)
					( objectStatus "R1T7.2" )
				)
			)
			( gate "@baseboard_fab2_lib.baseboard_fab2(sch_1):page160_i51"
				( attribute "BOM_COST" "SM_CONTROLLER"
					( Origin gFrontEnd )
				)
				( attribute "CDS_LIB" "mstr_discrete"
					( Origin gPackager )
				)
				( attribute "CDS_LOCATION" "R9F23"
					( Origin gPackager )
				)
				( attribute "CDS_SEC" "1"
					( Origin gPackager )
				)
				( attribute "LOCATION" "R9F23"
					( Origin gFrontEnd )
				)
				( attribute "MATERIAL" "CHIP"
					( Origin gFrontEnd )
				)
				( attribute "PACK_TYPE" "0402"
					( Origin gFrontEnd )
				)
				( attribute "PART_NUMBER" "G21796-173"
					( Origin gFrontEnd )
				)
				( attribute "PHYS_PAGE" "160"
					( Origin gFrontEnd )
				)
				( attribute "ROOM" "SMBUS"
					( Origin gFrontEnd )
				)
				( attribute "ROT" "0"
					( Origin gFrontEnd )
				)
				( attribute "SEC" "1"
					( Origin gPackager )
				)
				( attribute "TOLERANCE" "1%"
					( Origin gFrontEnd )
				)
				( attribute "VALUE" "20.0"
					( Origin gFrontEnd )
				)
				( attribute "VER" "1"
					( Origin gFrontEnd )
				)
				( attribute "WATTAGE" "1/16W"
					( Origin gFrontEnd )
				)
				( attribute "XY" "(-3350,3700)"
					( Origin gFrontEnd )
				)
				( attribute "CHIPS_PART_NAME" "RES"
					( Origin gPackager )
				)
				( attribute "CDS_PART_NAME" "RES_0402-20.0,1%,1/16W,CHIP,G2A"
					( Origin gPackager )
				)
				( objectStatus "R9F23" )
				( pin "a"
					( attribute "PN" "1"
						( Origin gPackager )
					)
					( objectStatus "R9F23.1" )
				)
				( pin "b"
					( attribute "PN" "2"
						( Origin gPackager )
					)
					( objectStatus "R9F23.2" )
				)
			)
			( gate "@baseboard_fab2_lib.baseboard_fab2(sch_1):page160_i52"
				( attribute "BOM_COST" "SM_CONTROLLER"
					( Origin gFrontEnd )
				)
				( attribute "CDS_LIB" "mstr_discrete"
					( Origin gPackager )
				)
				( attribute "CDS_LOCATION" "R9F22"
					( Origin gPackager )
				)
				( attribute "CDS_SEC" "1"
					( Origin gPackager )
				)
				( attribute "LOCATION" "R9F22"
					( Origin gFrontEnd )
				)
				( attribute "MATERIAL" "CHIP"
					( Origin gFrontEnd )
				)
				( attribute "PACK_TYPE" "0402"
					( Origin gFrontEnd )
				)
				( attribute "PART_NUMBER" "G21796-173"
					( Origin gFrontEnd )
				)
				( attribute "PHYS_PAGE" "160"
					( Origin gFrontEnd )
				)
				( attribute "ROOM" "SMBUS"
					( Origin gFrontEnd )
				)
				( attribute "ROT" "0"
					( Origin gFrontEnd )
				)
				( attribute "SEC" "1"
					( Origin gPackager )
				)
				( attribute "TOLERANCE" "1%"
					( Origin gFrontEnd )
				)
				( attribute "VALUE" "20.0"
					( Origin gFrontEnd )
				)
				( attribute "VER" "1"
					( Origin gFrontEnd )
				)
				( attribute "WATTAGE" "1/16W"
					( Origin gFrontEnd )
				)
				( attribute "XY" "(-3350,3525)"
					( Origin gFrontEnd )
				)
				( attribute "CHIPS_PART_NAME" "RES"
					( Origin gPackager )
				)
				( attribute "CDS_PART_NAME" "RES_0402-20.0,1%,1/16W,CHIP,G2A"
					( Origin gPackager )
				)
				( objectStatus "R9F22" )
				( pin "a"
					( attribute "PN" "1"
						( Origin gPackager )
					)
					( objectStatus "R9F22.1" )
				)
				( pin "b"
					( attribute "PN" "2"
						( Origin gPackager )
					)
					( objectStatus "R9F22.2" )
				)
			)
			( gate "@baseboard_fab2_lib.baseboard_fab2(sch_1):page161_i1"
				( attribute "BOM_COST" "SM_THERM"
					( Origin gFrontEnd )
				)
				( attribute "CDS_LIB" "mstr_conn"
					( Origin gPackager )
				)
				( attribute "CDS_LOCATION" "J1F2"
					( Origin gPackager )
				)
				( attribute "CDS_SEC" "1"
					( Origin gPackager )
				)
				( attribute "LOCATION" "J1F2"
					( Origin gFrontEnd )
				)
				( attribute "MATERIAL" "HDR"
					( Origin gFrontEnd )
				)
				( attribute "PACK_TYPE" "PIP"
					( Origin gFrontEnd )
				)
				( attribute "PART_NUMBER" "C74770-005"
					( Origin gFrontEnd )
				)
				( attribute "PHYS_PAGE" "161"
					( Origin gFrontEnd )
				)
				( attribute "ROOM" "CPU_FANS"
					( Origin gFrontEnd )
				)
				( attribute "ROT" "0"
					( Origin gFrontEnd )
				)
				( attribute "SEC" "1"
					( Origin gFrontEnd )
				)
				( attribute "SEC_TYPE" "PIP"
					( Origin gFrontEnd )
				)
				( attribute "TOLERANCE" "10%"
					( Origin gFrontEnd )
				)
				( attribute "VALUE" "0.22UF"
					( Origin gFrontEnd )
				)
				( attribute "VER" "1"
					( Origin gFrontEnd )
				)
				( attribute "VOLTAGE" "16V"
					( Units "uVoltage" "V" 1.000000)
					( Origin gFrontEnd )
				)
				( attribute "XY" "(-725,3775)"
					( Origin gFrontEnd )
				)
				( attribute "CHIPS_PART_NAME" "CONN6_C74770005"
					( Origin gPackager )
				)
				( attribute "CDS_PART_NAME" "CONN6_C74770005_PIP-HDR,C74770A"
					( Origin gPackager )
				)
				( objectStatus "J1F2" )
				( pin "io1"
					( attribute "PN" "1"
						( Origin gPackager )
					)
					( objectStatus "J1F2.1" )
				)
				( pin "io2"
					( attribute "PN" "2"
						( Origin gPackager )
					)
					( objectStatus "J1F2.2" )
				)
				( pin "io3"
					( attribute "PN" "3"
						( Origin gPackager )
					)
					( objectStatus "J1F2.3" )
				)
				( pin "io4"
					( attribute "PN" "4"
						( Origin gPackager )
					)
					( objectStatus "J1F2.4" )
				)
				( pin "io5"
					( attribute "PN" "5"
						( Origin gPackager )
					)
					( objectStatus "J1F2.5" )
				)
				( pin "io6"
					( attribute "PN" "6"
						( Origin gPackager )
					)
					( objectStatus "J1F2.6" )
				)
			)
			( gate "@baseboard_fab2_lib.baseboard_fab2(sch_1):page161_i3"
				( attribute "BOM_COST" "SM_THERM"
					( Origin gFrontEnd )
				)
				( attribute "CDS_LIB" "mstr_discrete"
					( Origin gPackager )
				)
				( attribute "CDS_LOCATION" "C1E21"
					( Origin gPackager )
				)
				( attribute "CDS_SEC" "1"
					( Origin gPackager )
				)
				( attribute "LOCATION" "C1E21"
					( Origin gFrontEnd )
				)
				( attribute "MATERIAL" "X6S"
					( Origin gFrontEnd )
				)
				( attribute "PACK_TYPE" "0805"
					( Origin gFrontEnd )
				)
				( attribute "PART_NUMBER" "C95333-007"
					( Origin gFrontEnd )
				)
				( attribute "PHYS_PAGE" "161"
					( Origin gFrontEnd )
				)
				( attribute "ROOM" "CPU_FANS"
					( Origin gFrontEnd )
				)
				( attribute "ROT" "0"
					( Origin gFrontEnd )
				)
				( attribute "SEC" "1"
					( Origin gFrontEnd )
				)
				( attribute "SEC_TYPE" "0805"
					( Origin gFrontEnd )
				)
				( attribute "TOLERANCE" "10%"
					( Origin gFrontEnd )
				)
				( attribute "VALUE" "10UF"
					( Origin gFrontEnd )
				)
				( attribute "VER" "1"
					( Origin gFrontEnd )
				)
				( attribute "VOLTAGE" "16V"
					( Units "uVoltage" "V" 1.000000)
					( Origin gFrontEnd )
				)
				( attribute "XY" "(-1400,4350)"
					( Origin gFrontEnd )
				)
				( attribute "CHIPS_PART_NAME" "CAP"
					( Origin gPackager )
				)
				( attribute "CDS_PART_NAME" "CAP_0805-10UF,16V,10%,X6S,C953A"
					( Origin gPackager )
				)
				( objectStatus "C1E21" )
				( pin "a"
					( attribute "PN" "1"
						( Origin gPackager )
					)
					( objectStatus "C1E21.1" )
				)
				( pin "b"
					( attribute "PN" "2"
						( Origin gPackager )
					)
					( objectStatus "C1E21.2" )
				)
			)
			( gate "@baseboard_fab2_lib.baseboard_fab2(sch_1):page161_i4"
				( attribute "BOM_COST" "SM_THERM"
					( Origin gFrontEnd )
				)
				( attribute "CDS_LIB" "dev_discrete"
					( Origin gPackager )
				)
				( attribute "CDS_LOCATION" "C1E20"
					( Origin gPackager )
				)
				( attribute "CDS_SEC" "1"
					( Origin gPackager )
				)
				( attribute "LOCATION" "C1E20"
					( Origin gFrontEnd )
				)
				( attribute "MATERIAL" "X7R"
					( Origin gFrontEnd )
				)
				( attribute "PACK_TYPE" "0402V"
					( Origin gFrontEnd )
				)
				( attribute "PART_NUMBER" "A36096-030"
					( Origin gFrontEnd )
				)
				( attribute "PHYS_PAGE" "161"
					( Origin gFrontEnd )
				)
				( attribute "ROOM" "CPU_FANS"
					( Origin gFrontEnd )
				)
				( attribute "ROT" "0"
					( Origin gFrontEnd )
				)
				( attribute "SEC" "1"
					( Origin gFrontEnd )
				)
				( attribute "SEC_TYPE" "0402V"
					( Origin gFrontEnd )
				)
				( attribute "TOLERANCE" "10%"
					( Origin gFrontEnd )
				)
				( attribute "VALUE" "0.1UF"
					( Origin gFrontEnd )
				)
				( attribute "VER" "1"
					( Origin gFrontEnd )
				)
				( attribute "VOLTAGE" "16V"
					( Units "uVoltage" "V" 1.000000)
					( Origin gFrontEnd )
				)
				( attribute "XY" "(-1125,4325)"
					( Origin gFrontEnd )
				)
				( attribute "CHIPS_PART_NAME" "CAP_A"
					( Origin gPackager )
				)
				( attribute "CDS_PART_NAME" "CAP_A_0402V-0.1UF,16V,10%,X7R,A"
					( Origin gPackager )
				)
				( objectStatus "C1E20" )
				( pin "a"
					( attribute "PN" "1"
						( Origin gPackager )
					)
					( objectStatus "C1E20.1" )
				)
				( pin "b"
					( attribute "PN" "2"
						( Origin gPackager )
					)
					( objectStatus "C1E20.2" )
				)
			)
			( gate "@baseboard_fab2_lib.baseboard_fab2(sch_1):page161_i26"
				( attribute "BOM_COST" "SM_THERM"
					( Origin gFrontEnd )
				)
				( attribute "CDS_LIB" "dev_discrete"
					( Origin gPackager )
				)
				( attribute "CDS_LOCATION" "C9M5"
					( Origin gPackager )
				)
				( attribute "CDS_SEC" "1"
					( Origin gPackager )
				)
				( attribute "LOCATION" "C9M5"
					( Origin gFrontEnd )
				)
				( attribute "MATERIAL" "X7R"
					( Origin gFrontEnd )
				)
				( attribute "PACK_TYPE" "0402V"
					( Origin gFrontEnd )
				)
				( attribute "PART_NUMBER" "A36096-030"
					( Origin gFrontEnd )
				)
				( attribute "PHYS_PAGE" "161"
					( Origin gFrontEnd )
				)
				( attribute "ROOM" "CPU_FANS"
					( Origin gFrontEnd )
				)
				( attribute "ROT" "0"
					( Origin gFrontEnd )
				)
				( attribute "SEC" "1"
					( Origin gFrontEnd )
				)
				( attribute "SEC_TYPE" "0402V"
					( Origin gFrontEnd )
				)
				( attribute "TOLERANCE" "10%"
					( Origin gFrontEnd )
				)
				( attribute "VALUE" "0.1UF"
					( Origin gFrontEnd )
				)
				( attribute "VER" "1"
					( Origin gFrontEnd )
				)
				( attribute "VOLTAGE" "16V"
					( Units "uVoltage" "V" 1.000000)
					( Origin gFrontEnd )
				)
				( attribute "XY" "(-1000,2275)"
					( Origin gFrontEnd )
				)
				( attribute "CHIPS_PART_NAME" "CAP_A"
					( Origin gPackager )
				)
				( attribute "CDS_PART_NAME" "CAP_A_0402V-0.1UF,16V,10%,X7R,A"
					( Origin gPackager )
				)
				( objectStatus "C9M5" )
				( pin "a"
					( attribute "PN" "1"
						( Origin gPackager )
					)
					( objectStatus "C9M5.1" )
				)
				( pin "b"
					( attribute "PN" "2"
						( Origin gPackager )
					)
					( objectStatus "C9M5.2" )
				)
			)
			( gate "@baseboard_fab2_lib.baseboard_fab2(sch_1):page161_i27"
				( attribute "BOM_COST" "SM_THERM"
					( Origin gFrontEnd )
				)
				( attribute "CDS_LIB" "mstr_discrete"
					( Origin gPackager )
				)
				( attribute "CDS_LOCATION" "C9M4"
					( Origin gPackager )
				)
				( attribute "CDS_SEC" "1"
					( Origin gPackager )
				)
				( attribute "LOCATION" "C9M4"
					( Origin gFrontEnd )
				)
				( attribute "MATERIAL" "X6S"
					( Origin gFrontEnd )
				)
				( attribute "PACK_TYPE" "0805"
					( Origin gFrontEnd )
				)
				( attribute "PART_NUMBER" "C95333-007"
					( Origin gFrontEnd )
				)
				( attribute "PHYS_PAGE" "161"
					( Origin gFrontEnd )
				)
				( attribute "ROOM" "CPU_FANS"
					( Origin gFrontEnd )
				)
				( attribute "ROT" "0"
					( Origin gFrontEnd )
				)
				( attribute "SEC" "1"
					( Origin gFrontEnd )
				)
				( attribute "SEC_TYPE" "0805"
					( Origin gFrontEnd )
				)
				( attribute "TOLERANCE" "10%"
					( Origin gFrontEnd )
				)
				( attribute "VALUE" "10UF"
					( Origin gFrontEnd )
				)
				( attribute "VER" "1"
					( Origin gFrontEnd )
				)
				( attribute "VOLTAGE" "16V"
					( Units "uVoltage" "V" 1.000000)
					( Origin gFrontEnd )
				)
				( attribute "XY" "(-1300,2275)"
					( Origin gFrontEnd )
				)
				( attribute "CHIPS_PART_NAME" "CAP"
					( Origin gPackager )
				)
				( attribute "CDS_PART_NAME" "CAP_0805-10UF,16V,10%,X6S,C953A"
					( Origin gPackager )
				)
				( objectStatus "C9M4" )
				( pin "a"
					( attribute "PN" "1"
						( Origin gPackager )
					)
					( objectStatus "C9M4.1" )
				)
				( pin "b"
					( attribute "PN" "2"
						( Origin gPackager )
					)
					( objectStatus "C9M4.2" )
				)
			)
			( gate "@baseboard_fab2_lib.baseboard_fab2(sch_1):page161_i32"
				( attribute "BOM_COST" "SM_THERM"
					( Origin gFrontEnd )
				)
				( attribute "CDS_LIB" "mstr_conn"
					( Origin gPackager )
				)
				( attribute "CDS_LOCATION" "J1B2"
					( Origin gPackager )
				)
				( attribute "CDS_SEC" "1"
					( Origin gPackager )
				)
				( attribute "LOCATION" "J1B2"
					( Origin gFrontEnd )
				)
				( attribute "MATERIAL" "HDR"
					( Origin gFrontEnd )
				)
				( attribute "PACK_TYPE" "PIP"
					( Origin gFrontEnd )
				)
				( attribute "PART_NUMBER" "C74770-005"
					( Origin gFrontEnd )
				)
				( attribute "PHYS_PAGE" "161"
					( Origin gFrontEnd )
				)
				( attribute "ROOM" "CPU_FANS"
					( Origin gFrontEnd )
				)
				( attribute "ROT" "0"
					( Origin gFrontEnd )
				)
				( attribute "SEC" "1"
					( Origin gFrontEnd )
				)
				( attribute "SEC_TYPE" "PIP"
					( Origin gFrontEnd )
				)
				( attribute "VER" "1"
					( Origin gFrontEnd )
				)
				( attribute "XY" "(-775,1700)"
					( Origin gFrontEnd )
				)
				( attribute "CHIPS_PART_NAME" "CONN6_C74770005"
					( Origin gPackager )
				)
				( attribute "CDS_PART_NAME" "CONN6_C74770005_PIP-HDR,C74770A"
					( Origin gPackager )
				)
				( objectStatus "J1B2" )
				( pin "io1"
					( attribute "PN" "1"
						( Origin gPackager )
					)
					( objectStatus "J1B2.1" )
				)
				( pin "io2"
					( attribute "PN" "2"
						( Origin gPackager )
					)
					( objectStatus "J1B2.2" )
				)
				( pin "io3"
					( attribute "PN" "3"
						( Origin gPackager )
					)
					( objectStatus "J1B2.3" )
				)
				( pin "io4"
					( attribute "PN" "4"
						( Origin gPackager )
					)
					( objectStatus "J1B2.4" )
				)
				( pin "io5"
					( attribute "PN" "5"
						( Origin gPackager )
					)
					( objectStatus "J1B2.5" )
				)
				( pin "io6"
					( attribute "PN" "6"
						( Origin gPackager )
					)
					( objectStatus "J1B2.6" )
				)
			)
			( gate "@baseboard_fab2_lib.baseboard_fab2(sch_1):page161_i42"
				( attribute "BOM_COST" "SM_THERM"
					( Origin gFrontEnd )
				)
				( attribute "CDS_LIB" "mstr_discrete"
					( Origin gPackager )
				)
				( attribute "CDS_LOCATION" "CR1F1"
					( Origin gPackager )
				)
				( attribute "CDS_SEC" "1"
					( Origin gPackager )
				)
				( attribute "LOCATION" "CR1F1"
					( Origin gFrontEnd )
				)
				( attribute "MATERIAL" "IC"
					( Origin gFrontEnd )
				)
				( attribute "PACK_TYPE" "SM"
					( Origin gFrontEnd )
				)
				( attribute "PART_NUMBER" "H71799-001"
					( Origin gFrontEnd )
				)
				( attribute "PHYS_PAGE" "161"
					( Origin gFrontEnd )
				)
				( attribute "ROOM" "CPU_FANS"
					( Origin gFrontEnd )
				)
				( attribute "ROT" "0"
					( Origin gFrontEnd )
				)
				( attribute "SEC" "1"
					( Origin gFrontEnd )
				)
				( attribute "SEC_TYPE" "SM"
					( Origin gFrontEnd )
				)
				( attribute "VALUE" "SDMK0340L"
					( Origin gFrontEnd )
				)
				( attribute "VER" "1"
					( Origin gFrontEnd )
				)
				( attribute "XY" "(-1675,3825)"
					( Origin gFrontEnd )
				)
				( attribute "CHIPS_PART_NAME" "DIODE"
					( Origin gPackager )
				)
				( attribute "CDS_PART_NAME" "DIODE_SM-SDMK0340L,IC,H71799-0A"
					( Origin gPackager )
				)
				( objectStatus "CR1F1" )
				( pin "a"
					( attribute "PN" "2"
						( Origin gPackager )
					)
					( objectStatus "CR1F1.2" )
				)
				( pin "c"
					( attribute "PN" "1"
						( Origin gPackager )
					)
					( objectStatus "CR1F1.1" )
				)
			)
			( gate "@baseboard_fab2_lib.baseboard_fab2(sch_1):page161_i43"
				( attribute "BOM_COST" "SM_THERM"
					( Origin gFrontEnd )
				)
				( attribute "CDS_LIB" "mstr_discrete"
					( Origin gPackager )
				)
				( attribute "CDS_LOCATION" "R1F2"
					( Origin gPackager )
				)
				( attribute "CDS_SEC" "1"
					( Origin gPackager )
				)
				( attribute "LOCATION" "R1F2"
					( Origin gFrontEnd )
				)
				( attribute "MATERIAL" "CHIP"
					( Origin gFrontEnd )
				)
				( attribute "NO_XNET_CONNECTION" "1"
					( Origin gFrontEnd )
				)
				( attribute "PACK_TYPE" "0402"
					( Origin gFrontEnd )
				)
				( attribute "PART_NUMBER" "G21796-017"
					( Origin gFrontEnd )
				)
				( attribute "PHYS_PAGE" "161"
					( Origin gFrontEnd )
				)
				( attribute "ROOM" "CPU_FANS"
					( Origin gFrontEnd )
				)
				( attribute "ROT" "0"
					( Origin gFrontEnd )
				)
				( attribute "SEC" "1"
					( Origin gFrontEnd )
				)
				( attribute "SEC_TYPE" "0402"
					( Origin gFrontEnd )
				)
				( attribute "TOLERANCE" "1%"
					( Origin gFrontEnd )
				)
				( attribute "VALUE" "100.0"
					( Origin gFrontEnd )
				)
				( attribute "VER" "1"
					( Origin gFrontEnd )
				)
				( attribute "WATTAGE" "1/16W"
					( Origin gFrontEnd )
				)
				( attribute "XY" "(-2525,3825)"
					( Origin gFrontEnd )
				)
				( attribute "CHIPS_PART_NAME" "RES"
					( Origin gPackager )
				)
				( attribute "CDS_PART_NAME" "RES_0402-100.0,1%,1/16W,CHIP,GA"
					( Origin gPackager )
				)
				( objectStatus "R1F2" )
				( pin "a"
					( attribute "PN" "1"
						( Origin gPackager )
					)
					( objectStatus "R1F2.1" )
				)
				( pin "b"
					( attribute "PN" "2"
						( Origin gPackager )
					)
					( objectStatus "R1F2.2" )
				)
			)
			( gate "@baseboard_fab2_lib.baseboard_fab2(sch_1):page161_i45"
				( attribute "BOM_COST" "SM_THERM"
					( Origin gFrontEnd )
				)
				( attribute "CDS_LIB" "mstr_discrete"
					( Origin gPackager )
				)
				( attribute "CDS_LOCATION" "R1F1"
					( Origin gPackager )
				)
				( attribute "CDS_SEC" "1"
					( Origin gPackager )
				)
				( attribute "LOCATION" "R1F1"
					( Origin gFrontEnd )
				)
				( attribute "MATERIAL" "CHIP"
					( Origin gFrontEnd )
				)
				( attribute "PACK_TYPE" "0402"
					( Origin gFrontEnd )
				)
				( attribute "PART_NUMBER" "G21796-072"
					( Origin gFrontEnd )
				)
				( attribute "PHYS_PAGE" "161"
					( Origin gFrontEnd )
				)
				( attribute "ROOM" "CPU_FANS"
					( Origin gFrontEnd )
				)
				( attribute "ROT" "0"
					( Origin gFrontEnd )
				)
				( attribute "SEC" "1"
					( Origin gFrontEnd )
				)
				( attribute "SEC_TYPE" "0402"
					( Origin gFrontEnd )
				)
				( attribute "TOLERANCE" "1%"
					( Origin gFrontEnd )
				)
				( attribute "VALUE" "4.75K"
					( Origin gFrontEnd )
				)
				( attribute "VER" "2"
					( Origin gFrontEnd )
				)
				( attribute "WATTAGE" "1/16W"
					( Origin gFrontEnd )
				)
				( attribute "XY" "(-2900,4025)"
					( Origin gFrontEnd )
				)
				( attribute "CHIPS_PART_NAME" "RES"
					( Origin gPackager )
				)
				( attribute "CDS_PART_NAME" "RES_0402-4.75K,1%,1/16W,CHIP,GA"
					( Origin gPackager )
				)
				( objectStatus "R1F1" )
				( pin "a"
					( attribute "PN" "1"
						( Origin gPackager )
					)
					( objectStatus "R1F1.1" )
				)
				( pin "b"
					( attribute "PN" "2"
						( Origin gPackager )
					)
					( objectStatus "R1F1.2" )
				)
			)
			( gate "@baseboard_fab2_lib.baseboard_fab2(sch_1):page161_i46"
				( attribute "BOM_COST" "SM_THERM"
					( Origin gFrontEnd )
				)
				( attribute "CDS_LIB" "dev_discrete"
					( Origin gPackager )
				)
				( attribute "CDS_LOCATION" "C1F9"
					( Origin gPackager )
				)
				( attribute "CDS_SEC" "1"
					( Origin gPackager )
				)
				( attribute "LOCATION" "C1F9"
					( Origin gFrontEnd )
				)
				( attribute "MATERIAL" "X7R"
					( Origin gFrontEnd )
				)
				( attribute "PACK_TYPE" "0402V"
					( Origin gFrontEnd )
				)
				( attribute "PART_NUMBER" "A36096-045"
					( Origin gFrontEnd )
				)
				( attribute "PHYS_PAGE" "161"
					( Origin gFrontEnd )
				)
				( attribute "ROOM" "CPU_FANS"
					( Origin gFrontEnd )
				)
				( attribute "ROT" "2"
					( Origin gFrontEnd )
				)
				( attribute "SEC" "1"
					( Origin gFrontEnd )
				)
				( attribute "SEC_TYPE" "0402V"
					( Origin gFrontEnd )
				)
				( attribute "TOLERANCE" "10%"
					( Origin gFrontEnd )
				)
				( attribute "VALUE" "0.01UF"
					( Origin gFrontEnd )
				)
				( attribute "VER" "1"
					( Origin gFrontEnd )
				)
				( attribute "VOLTAGE" "25V"
					( Units "uVoltage" "V" 1.000000)
					( Origin gFrontEnd )
				)
				( attribute "XY" "(-2775,3625)"
					( Origin gFrontEnd )
				)
				( attribute "CHIPS_PART_NAME" "CAP_A"
					( Origin gPackager )
				)
				( attribute "CDS_PART_NAME" "CAP_A_0402V-0.01UF,25V,10%,X7RA"
					( Origin gPackager )
				)
				( objectStatus "C1F9" )
				( pin "a"
					( attribute "PN" "1"
						( Origin gPackager )
					)
					( objectStatus "C1F9.1" )
				)
				( pin "b"
					( attribute "PN" "2"
						( Origin gPackager )
					)
					( objectStatus "C1F9.2" )
				)
			)
			( gate "@baseboard_fab2_lib.baseboard_fab2(sch_1):page161_i50"
				( attribute "BOM_COST" "SM_THERM"
					( Origin gFrontEnd )
				)
				( attribute "CDS_LIB" "mstr_discrete"
					( Origin gPackager )
				)
				( attribute "CDS_LOCATION" "CR1E1"
					( Origin gPackager )
				)
				( attribute "CDS_SEC" "1"
					( Origin gPackager )
				)
				( attribute "LOCATION" "CR1E1"
					( Origin gFrontEnd )
				)
				( attribute "MATERIAL" "EMPTY"
					( Origin gFrontEnd )
				)
				( attribute "PACK_TYPE" "SM"
					( Origin gFrontEnd )
				)
				( attribute "PART_NUMBER" "H71799-001"
					( Origin gFrontEnd )
				)
				( attribute "PHYS_PAGE" "161"
					( Origin gFrontEnd )
				)
				( attribute "ROOM" "CPU_FANS"
					( Origin gFrontEnd )
				)
				( attribute "ROT" "0"
					( Origin gFrontEnd )
				)
				( attribute "SEC" "1"
					( Origin gFrontEnd )
				)
				( attribute "SEC_TYPE" "SM"
					( Origin gFrontEnd )
				)
				( attribute "VALUE" "SDMK0340L"
					( Origin gFrontEnd )
				)
				( attribute "VER" "4"
					( Origin gFrontEnd )
				)
				( attribute "XY" "(-1950,3325)"
					( Origin gFrontEnd )
				)
				( attribute "CHIPS_PART_NAME" "DIODE"
					( Origin gPackager )
				)
				( attribute "CDS_PART_NAME" "DIODE_SM-SDMK0340L,EMPTY,H7179A"
					( Origin gPackager )
				)
				( objectStatus "CR1E1" )
				( pin "a"
					( attribute "PN" "2"
						( Origin gPackager )
					)
					( objectStatus "CR1E1.2" )
				)
				( pin "c"
					( attribute "PN" "1"
						( Origin gPackager )
					)
					( objectStatus "CR1E1.1" )
				)
			)
			( gate "@baseboard_fab2_lib.baseboard_fab2(sch_1):page161_i51"
				( attribute "BOM_COST" "SM_THERM"
					( Origin gFrontEnd )
				)
				( attribute "CDS_LIB" "mstr_discrete"
					( Origin gPackager )
				)
				( attribute "CDS_LOCATION" "R1E12"
					( Origin gPackager )
				)
				( attribute "CDS_SEC" "1"
					( Origin gPackager )
				)
				( attribute "LOCATION" "R1E12"
					( Origin gFrontEnd )
				)
				( attribute "MATERIAL" "CHIP"
					( Origin gFrontEnd )
				)
				( attribute "PACK_TYPE" "0402"
					( Origin gFrontEnd )
				)
				( attribute "PART_NUMBER" "G21796-072"
					( Origin gFrontEnd )
				)
				( attribute "PHYS_PAGE" "161"
					( Origin gFrontEnd )
				)
				( attribute "ROOM" "CPU_FANS"
					( Origin gFrontEnd )
				)
				( attribute "ROT" "2"
					( Origin gFrontEnd )
				)
				( attribute "SEC" "1"
					( Origin gFrontEnd )
				)
				( attribute "SEC_TYPE" "0402"
					( Origin gFrontEnd )
				)
				( attribute "TOLERANCE" "1%"
					( Origin gFrontEnd )
				)
				( attribute "VALUE" "4.75K"
					( Origin gFrontEnd )
				)
				( attribute "VER" "2"
					( Origin gFrontEnd )
				)
				( attribute "WATTAGE" "1/16W"
					( Origin gFrontEnd )
				)
				( attribute "XY" "(-2175,3400)"
					( Origin gFrontEnd )
				)
				( attribute "CHIPS_PART_NAME" "RES"
					( Origin gPackager )
				)
				( attribute "CDS_PART_NAME" "RES_0402-4.75K,1%,1/16W,CHIP,GA"
					( Origin gPackager )
				)
				( objectStatus "R1E12" )
				( pin "a"
					( attribute "PN" "1"
						( Origin gPackager )
					)
					( objectStatus "R1E12.1" )
				)
				( pin "b"
					( attribute "PN" "2"
						( Origin gPackager )
					)
					( objectStatus "R1E12.2" )
				)
			)
			( gate "@baseboard_fab2_lib.baseboard_fab2(sch_1):page161_i62"
				( attribute "BOM_COST" "SM_THERM"
					( Origin gFrontEnd )
				)
				( attribute "CDS_LIB" "mstr_discrete"
					( Origin gPackager )
				)
				( attribute "CDS_LOCATION" "CR1B2"
					( Origin gPackager )
				)
				( attribute "CDS_SEC" "1"
					( Origin gPackager )
				)
				( attribute "LOCATION" "CR1B2"
					( Origin gFrontEnd )
				)
				( attribute "MATERIAL" "IC"
					( Origin gFrontEnd )
				)
				( attribute "PACK_TYPE" "SM"
					( Origin gFrontEnd )
				)
				( attribute "PART_NUMBER" "H71799-001"
					( Origin gFrontEnd )
				)
				( attribute "PHYS_PAGE" "161"
					( Origin gFrontEnd )
				)
				( attribute "ROOM" "CPU_FANS"
					( Origin gFrontEnd )
				)
				( attribute "ROT" "0"
					( Origin gFrontEnd )
				)
				( attribute "SEC" "1"
					( Origin gFrontEnd )
				)
				( attribute "SEC_TYPE" "SM"
					( Origin gFrontEnd )
				)
				( attribute "VALUE" "SDMK0340L"
					( Origin gFrontEnd )
				)
				( attribute "VER" "1"
					( Origin gFrontEnd )
				)
				( attribute "XY" "(-1825,1750)"
					( Origin gFrontEnd )
				)
				( attribute "CHIPS_PART_NAME" "DIODE"
					( Origin gPackager )
				)
				( attribute "CDS_PART_NAME" "DIODE_SM-SDMK0340L,IC,H71799-0A"
					( Origin gPackager )
				)
				( objectStatus "CR1B2" )
				( pin "a"
					( attribute "PN" "2"
						( Origin gPackager )
					)
					( objectStatus "CR1B2.2" )
				)
				( pin "c"
					( attribute "PN" "1"
						( Origin gPackager )
					)
					( objectStatus "CR1B2.1" )
				)
			)
			( gate "@baseboard_fab2_lib.baseboard_fab2(sch_1):page161_i64"
				( attribute "BOM_COST" "SM_THERM"
					( Origin gFrontEnd )
				)
				( attribute "CDS_LIB" "mstr_discrete"
					( Origin gPackager )
				)
				( attribute "CDS_LOCATION" "CR1B1"
					( Origin gPackager )
				)
				( attribute "CDS_SEC" "1"
					( Origin gPackager )
				)
				( attribute "LOCATION" "CR1B1"
					( Origin gFrontEnd )
				)
				( attribute "MATERIAL" "EMPTY"
					( Origin gFrontEnd )
				)
				( attribute "PACK_TYPE" "SM"
					( Origin gFrontEnd )
				)
				( attribute "PART_NUMBER" "H71799-001"
					( Origin gFrontEnd )
				)
				( attribute "PHYS_PAGE" "161"
					( Origin gFrontEnd )
				)
				( attribute "ROOM" "CPU_FANS"
					( Origin gFrontEnd )
				)
				( attribute "ROT" "0"
					( Origin gFrontEnd )
				)
				( attribute "SEC" "1"
					( Origin gFrontEnd )
				)
				( attribute "SEC_TYPE" "SM"
					( Origin gFrontEnd )
				)
				( attribute "VALUE" "SDMK0340L"
					( Origin gFrontEnd )
				)
				( attribute "VER" "4"
					( Origin gFrontEnd )
				)
				( attribute "XY" "(-2100,1250)"
					( Origin gFrontEnd )
				)
				( attribute "CHIPS_PART_NAME" "DIODE"
					( Origin gPackager )
				)
				( attribute "CDS_PART_NAME" "DIODE_SM-SDMK0340L,EMPTY,H7179A"
					( Origin gPackager )
				)
				( objectStatus "CR1B1" )
				( pin "a"
					( attribute "PN" "2"
						( Origin gPackager )
					)
					( objectStatus "CR1B1.2" )
				)
				( pin "c"
					( attribute "PN" "1"
						( Origin gPackager )
					)
					( objectStatus "CR1B1.1" )
				)
			)
			( gate "@baseboard_fab2_lib.baseboard_fab2(sch_1):page161_i65"
				( attribute "BOM_COST" "SM_THERM"
					( Origin gFrontEnd )
				)
				( attribute "CDS_LIB" "mstr_discrete"
					( Origin gPackager )
				)
				( attribute "CDS_LOCATION" "R7F33"
					( Origin gPackager )
				)
				( attribute "CDS_SEC" "1"
					( Origin gPackager )
				)
				( attribute "LOCATION" "R7F33"
					( Origin gFrontEnd )
				)
				( attribute "MATERIAL" "CHIP"
					( Origin gFrontEnd )
				)
				( attribute "PACK_TYPE" "0402"
					( Origin gFrontEnd )
				)
				( attribute "PART_NUMBER" "G21796-072"
					( Origin gFrontEnd )
				)
				( attribute "PHYS_PAGE" "161"
					( Origin gFrontEnd )
				)
				( attribute "ROOM" "CPU_FANS"
					( Origin gFrontEnd )
				)
				( attribute "ROT" "2"
					( Origin gFrontEnd )
				)
				( attribute "SEC" "1"
					( Origin gFrontEnd )
				)
				( attribute "SEC_TYPE" "0402"
					( Origin gFrontEnd )
				)
				( attribute "TOLERANCE" "1%"
					( Origin gFrontEnd )
				)
				( attribute "VALUE" "4.75K"
					( Origin gFrontEnd )
				)
				( attribute "VER" "2"
					( Origin gFrontEnd )
				)
				( attribute "WATTAGE" "1/16W"
					( Origin gFrontEnd )
				)
				( attribute "XY" "(-2325,1300)"
					( Origin gFrontEnd )
				)
				( attribute "CHIPS_PART_NAME" "RES"
					( Origin gPackager )
				)
				( attribute "CDS_PART_NAME" "RES_0402-4.75K,1%,1/16W,CHIP,GA"
					( Origin gPackager )
				)
				( objectStatus "R7F33" )
				( pin "a"
					( attribute "PN" "1"
						( Origin gPackager )
					)
					( objectStatus "R7F33.1" )
				)
				( pin "b"
					( attribute "PN" "2"
						( Origin gPackager )
					)
					( objectStatus "R7F33.2" )
				)
			)
			( gate "@baseboard_fab2_lib.baseboard_fab2(sch_1):page161_i67"
				( attribute "BOM_COST" "SM_THERM"
					( Origin gFrontEnd )
				)
				( attribute "CDS_LIB" "mstr_discrete"
					( Origin gPackager )
				)
				( attribute "CDS_LOCATION" "R1B22"
					( Origin gPackager )
				)
				( attribute "CDS_SEC" "1"
					( Origin gPackager )
				)
				( attribute "LOCATION" "R1B22"
					( Origin gFrontEnd )
				)
				( attribute "MATERIAL" "CHIP"
					( Origin gFrontEnd )
				)
				( attribute "NO_XNET_CONNECTION" "1"
					( Origin gFrontEnd )
				)
				( attribute "PACK_TYPE" "0402"
					( Origin gFrontEnd )
				)
				( attribute "PART_NUMBER" "G21796-017"
					( Origin gFrontEnd )
				)
				( attribute "PHYS_PAGE" "161"
					( Origin gFrontEnd )
				)
				( attribute "ROOM" "CPU_FANS"
					( Origin gFrontEnd )
				)
				( attribute "ROT" "0"
					( Origin gFrontEnd )
				)
				( attribute "SEC" "1"
					( Origin gFrontEnd )
				)
				( attribute "SEC_TYPE" "0402"
					( Origin gFrontEnd )
				)
				( attribute "TOLERANCE" "1%"
					( Origin gFrontEnd )
				)
				( attribute "VALUE" "100.0"
					( Origin gFrontEnd )
				)
				( attribute "VER" "1"
					( Origin gFrontEnd )
				)
				( attribute "WATTAGE" "1/16W"
					( Origin gFrontEnd )
				)
				( attribute "XY" "(-2675,1750)"
					( Origin gFrontEnd )
				)
				( attribute "CHIPS_PART_NAME" "RES"
					( Origin gPackager )
				)
				( attribute "CDS_PART_NAME" "RES_0402-100.0,1%,1/16W,CHIP,GA"
					( Origin gPackager )
				)
				( objectStatus "R1B22" )
				( pin "a"
					( attribute "PN" "1"
						( Origin gPackager )
					)
					( objectStatus "R1B22.1" )
				)
				( pin "b"
					( attribute "PN" "2"
						( Origin gPackager )
					)
					( objectStatus "R1B22.2" )
				)
			)
			( gate "@baseboard_fab2_lib.baseboard_fab2(sch_1):page161_i68"
				( attribute "BOM_COST" "SM_THERM"
					( Origin gFrontEnd )
				)
				( attribute "CDS_LIB" "dev_discrete"
					( Origin gPackager )
				)
				( attribute "CDS_LOCATION" "C1B15"
					( Origin gPackager )
				)
				( attribute "CDS_SEC" "1"
					( Origin gPackager )
				)
				( attribute "LOCATION" "C1B15"
					( Origin gFrontEnd )
				)
				( attribute "MATERIAL" "X7R"
					( Origin gFrontEnd )
				)
				( attribute "PACK_TYPE" "0402V"
					( Origin gFrontEnd )
				)
				( attribute "PART_NUMBER" "A36096-045"
					( Origin gFrontEnd )
				)
				( attribute "PHYS_PAGE" "161"
					( Origin gFrontEnd )
				)
				( attribute "ROOM" "CPU_FANS"
					( Origin gFrontEnd )
				)
				( attribute "ROT" "2"
					( Origin gFrontEnd )
				)
				( attribute "SEC" "1"
					( Origin gFrontEnd )
				)
				( attribute "SEC_TYPE" "0402V"
					( Origin gFrontEnd )
				)
				( attribute "TOLERANCE" "10%"
					( Origin gFrontEnd )
				)
				( attribute "VALUE" "0.01UF"
					( Origin gFrontEnd )
				)
				( attribute "VER" "1"
					( Origin gFrontEnd )
				)
				( attribute "VOLTAGE" "25V"
					( Units "uVoltage" "V" 1.000000)
					( Origin gFrontEnd )
				)
				( attribute "XY" "(-2925,1550)"
					( Origin gFrontEnd )
				)
				( attribute "CHIPS_PART_NAME" "CAP_A"
					( Origin gPackager )
				)
				( attribute "CDS_PART_NAME" "CAP_A_0402V-0.01UF,25V,10%,X7RA"
					( Origin gPackager )
				)
				( objectStatus "C1B15" )
				( pin "a"
					( attribute "PN" "1"
						( Origin gPackager )
					)
					( objectStatus "C1B15.1" )
				)
				( pin "b"
					( attribute "PN" "2"
						( Origin gPackager )
					)
					( objectStatus "C1B15.2" )
				)
			)
			( gate "@baseboard_fab2_lib.baseboard_fab2(sch_1):page161_i70"
				( attribute "BOM_COST" "SM_THERM"
					( Origin gFrontEnd )
				)
				( attribute "CDS_LIB" "mstr_discrete"
					( Origin gPackager )
				)
				( attribute "CDS_LOCATION" "R1B21"
					( Origin gPackager )
				)
				( attribute "CDS_SEC" "1"
					( Origin gPackager )
				)
				( attribute "LOCATION" "R1B21"
					( Origin gFrontEnd )
				)
				( attribute "MATERIAL" "CHIP"
					( Origin gFrontEnd )
				)
				( attribute "PACK_TYPE" "0402"
					( Origin gFrontEnd )
				)
				( attribute "PART_NUMBER" "G21796-072"
					( Origin gFrontEnd )
				)
				( attribute "PHYS_PAGE" "161"
					( Origin gFrontEnd )
				)
				( attribute "ROOM" "CPU_FANS"
					( Origin gFrontEnd )
				)
				( attribute "ROT" "0"
					( Origin gFrontEnd )
				)
				( attribute "SEC" "1"
					( Origin gFrontEnd )
				)
				( attribute "SEC_TYPE" "0402"
					( Origin gFrontEnd )
				)
				( attribute "TOLERANCE" "1%"
					( Origin gFrontEnd )
				)
				( attribute "VALUE" "4.75K"
					( Origin gFrontEnd )
				)
				( attribute "VER" "2"
					( Origin gFrontEnd )
				)
				( attribute "WATTAGE" "1/16W"
					( Origin gFrontEnd )
				)
				( attribute "XY" "(-3050,1950)"
					( Origin gFrontEnd )
				)
				( attribute "CHIPS_PART_NAME" "RES"
					( Origin gPackager )
				)
				( attribute "CDS_PART_NAME" "RES_0402-4.75K,1%,1/16W,CHIP,GA"
					( Origin gPackager )
				)
				( objectStatus "R1B21" )
				( pin "a"
					( attribute "PN" "1"
						( Origin gPackager )
					)
					( objectStatus "R1B21.1" )
				)
				( pin "b"
					( attribute "PN" "2"
						( Origin gPackager )
					)
					( objectStatus "R1B21.2" )
				)
			)
			( gate "@baseboard_fab2_lib.baseboard_fab2(sch_1):page161_i88"
				( attribute "BOM_COST" "SM_THERM"
					( Origin gFrontEnd )
				)
				( attribute "CDS_LIB" "mstr_ttl"
					( Origin gPackager )
				)
				( attribute "CDS_LOCATION" "U8G2"
					( Origin gPackager )
				)
				( attribute "CDS_SEC" "1"
					( Origin gPackager )
				)
				( attribute "LOCATION" "U8G2"
					( Origin gFrontEnd )
				)
				( attribute "MATERIAL" "IC"
					( Origin gFrontEnd )
				)
				( attribute "PACK_TYPE" "SOP"
					( Origin gFrontEnd )
				)
				( attribute "PART_NUMBER" "C88419-001"
					( Origin gFrontEnd )
				)
				( attribute "PHYS_PAGE" "161"
					( Origin gFrontEnd )
				)
				( attribute "ROOM" "CPU_FANS"
					( Origin gFrontEnd )
				)
				( attribute "ROT" "0"
					( Origin gFrontEnd )
				)
				( attribute "SEC" "1"
					( Origin gFrontEnd )
				)
				( attribute "SEC_TYPE" "SOP"
					( Origin gFrontEnd )
				)
				( attribute "VALUE" "74LVC1G07"
					( Origin gFrontEnd )
				)
				( attribute "VER" "1"
					( Origin gFrontEnd )
				)
				( attribute "XY" "(-6350,3850)"
					( Origin gFrontEnd )
				)
				( attribute "CHIPS_PART_NAME" "TTL1G07_A"
					( Origin gPackager )
				)
				( attribute "CDS_PART_NAME" "TTL1G07_A_SOP-74LVC1G07,IC,C88B"
					( Origin gPackager )
				)
				( objectStatus "U8G2" )
				( pin "a"
					( attribute "PN" "2"
						( Origin gPackager )
					)
					( objectStatus "U8G2.2" )
				)
				( pin "y"
					( attribute "PN" "4"
						( Origin gPackager )
					)
					( objectStatus "U8G2.4" )
				)
			)
			( gate "@baseboard_fab2_lib.baseboard_fab2(sch_1):page161_i90"
				( attribute "BOM_COST" "SM_THERM"
					( Origin gFrontEnd )
				)
				( attribute "CDS_LIB" "dev_discrete"
					( Origin gPackager )
				)
				( attribute "CDS_LOCATION" "C2U27"
					( Origin gPackager )
				)
				( attribute "CDS_SEC" "1"
					( Origin gPackager )
				)
				( attribute "LOCATION" "C2U27"
					( Origin gFrontEnd )
				)
				( attribute "MATERIAL" "X7R"
					( Origin gFrontEnd )
				)
				( attribute "PACK_TYPE" "0402V"
					( Origin gFrontEnd )
				)
				( attribute "PART_NUMBER" "A36096-030"
					( Origin gFrontEnd )
				)
				( attribute "PHYS_PAGE" "161"
					( Origin gFrontEnd )
				)
				( attribute "ROOM" "CPU_FANS"
					( Origin gFrontEnd )
				)
				( attribute "ROT" "0"
					( Origin gFrontEnd )
				)
				( attribute "SEC" "1"
					( Origin gFrontEnd )
				)
				( attribute "SEC_TYPE" "0402V"
					( Origin gFrontEnd )
				)
				( attribute "TOLERANCE" "10%"
					( Origin gFrontEnd )
				)
				( attribute "VALUE" "0.1UF"
					( Origin gFrontEnd )
				)
				( attribute "VER" "1"
					( Origin gFrontEnd )
				)
				( attribute "VOLTAGE" "16V"
					( Units "uVoltage" "V" 1.000000)
					( Origin gFrontEnd )
				)
				( attribute "XY" "(-6300,4450)"
					( Origin gFrontEnd )
				)
				( attribute "CHIPS_PART_NAME" "CAP_A"
					( Origin gPackager )
				)
				( attribute "CDS_PART_NAME" "CAP_A_0402V-0.1UF,16V,10%,X7R,A"
					( Origin gPackager )
				)
				( objectStatus "C2U27" )
				( pin "a"
					( attribute "PN" "1"
						( Origin gPackager )
					)
					( objectStatus "C2U27.1" )
				)
				( pin "b"
					( attribute "PN" "2"
						( Origin gPackager )
					)
					( objectStatus "C2U27.2" )
				)
			)
			( gate "@baseboard_fab2_lib.baseboard_fab2(sch_1):page161_i92"
				( attribute "BOM_COST" "SM_THERM"
					( Origin gFrontEnd )
				)
				( attribute "CDS_LIB" "mstr_ttl"
					( Origin gPackager )
				)
				( attribute "CDS_LOCATION" "U8G3"
					( Origin gPackager )
				)
				( attribute "CDS_SEC" "1"
					( Origin gPackager )
				)
				( attribute "LOCATION" "U8G3"
					( Origin gFrontEnd )
				)
				( attribute "MATERIAL" "IC"
					( Origin gFrontEnd )
				)
				( attribute "PACK_TYPE" "SOP"
					( Origin gFrontEnd )
				)
				( attribute "PART_NUMBER" "C88419-001"
					( Origin gFrontEnd )
				)
				( attribute "PHYS_PAGE" "161"
					( Origin gFrontEnd )
				)
				( attribute "ROOM" "CPU_FANS"
					( Origin gFrontEnd )
				)
				( attribute "ROT" "0"
					( Origin gFrontEnd )
				)
				( attribute "SEC" "1"
					( Origin gFrontEnd )
				)
				( attribute "SEC_TYPE" "SOP"
					( Origin gFrontEnd )
				)
				( attribute "VALUE" "74LVC1G07"
					( Origin gFrontEnd )
				)
				( attribute "VER" "1"
					( Origin gFrontEnd )
				)
				( attribute "XY" "(-6425,1100)"
					( Origin gFrontEnd )
				)
				( attribute "CHIPS_PART_NAME" "TTL1G07_A"
					( Origin gPackager )
				)
				( attribute "CDS_PART_NAME" "TTL1G07_A_SOP-74LVC1G07,IC,C88B"
					( Origin gPackager )
				)
				( objectStatus "U8G3" )
				( pin "a"
					( attribute "PN" "2"
						( Origin gPackager )
					)
					( objectStatus "U8G3.2" )
				)
				( pin "y"
					( attribute "PN" "4"
						( Origin gPackager )
					)
					( objectStatus "U8G3.4" )
				)
			)
			( gate "@baseboard_fab2_lib.baseboard_fab2(sch_1):page161_i93"
				( attribute "BOM_COST" "SM_THERM"
					( Origin gFrontEnd )
				)
				( attribute "CDS_LIB" "dev_discrete"
					( Origin gPackager )
				)
				( attribute "CDS_LOCATION" "C2U28"
					( Origin gPackager )
				)
				( attribute "CDS_SEC" "1"
					( Origin gPackager )
				)
				( attribute "LOCATION" "C2U28"
					( Origin gFrontEnd )
				)
				( attribute "MATERIAL" "X7R"
					( Origin gFrontEnd )
				)
				( attribute "PACK_TYPE" "0402V"
					( Origin gFrontEnd )
				)
				( attribute "PART_NUMBER" "A36096-030"
					( Origin gFrontEnd )
				)
				( attribute "PHYS_PAGE" "161"
					( Origin gFrontEnd )
				)
				( attribute "ROOM" "CPU_FANS"
					( Origin gFrontEnd )
				)
				( attribute "ROT" "0"
					( Origin gFrontEnd )
				)
				( attribute "SEC" "1"
					( Origin gFrontEnd )
				)
				( attribute "SEC_TYPE" "0402V"
					( Origin gFrontEnd )
				)
				( attribute "TOLERANCE" "10%"
					( Origin gFrontEnd )
				)
				( attribute "VALUE" "0.1UF"
					( Origin gFrontEnd )
				)
				( attribute "VER" "1"
					( Origin gFrontEnd )
				)
				( attribute "VOLTAGE" "16V"
					( Units "uVoltage" "V" 1.000000)
					( Origin gFrontEnd )
				)
				( attribute "XY" "(-6200,675)"
					( Origin gFrontEnd )
				)
				( attribute "CHIPS_PART_NAME" "CAP_A"
					( Origin gPackager )
				)
				( attribute "CDS_PART_NAME" "CAP_A_0402V-0.1UF,16V,10%,X7R,A"
					( Origin gPackager )
				)
				( objectStatus "C2U28" )
				( pin "a"
					( attribute "PN" "1"
						( Origin gPackager )
					)
					( objectStatus "C2U28.1" )
				)
				( pin "b"
					( attribute "PN" "2"
						( Origin gPackager )
					)
					( objectStatus "C2U28.2" )
				)
			)
			( gate "@baseboard_fab2_lib.baseboard_fab2(sch_1):page161_i99"
				( attribute "BOM_COST" "SM_THERM"
					( Origin gFrontEnd )
				)
				( attribute "CDS_LIB" "mstr_discrete"
					( Origin gPackager )
				)
				( attribute "CDS_LOCATION" "R2U42"
					( Origin gPackager )
				)
				( attribute "CDS_SEC" "1"
					( Origin gPackager )
				)
				( attribute "LOCATION" "R2U42"
					( Origin gFrontEnd )
				)
				( attribute "MATERIAL" "CHIP"
					( Origin gFrontEnd )
				)
				( attribute "PACK_TYPE" "0402"
					( Origin gFrontEnd )
				)
				( attribute "PART_NUMBER" "G21796-271"
					( Origin gFrontEnd )
				)
				( attribute "PHYS_PAGE" "161"
					( Origin gFrontEnd )
				)
				( attribute "ROOM" "CPU_FANS"
					( Origin gFrontEnd )
				)
				( attribute "ROT" "0"
					( Origin gFrontEnd )
				)
				( attribute "SEC" "1"
					( Origin gFrontEnd )
				)
				( attribute "SEC_TYPE" "0402"
					( Origin gFrontEnd )
				)
				( attribute "TOLERANCE" "1.0%"
					( Origin gFrontEnd )
				)
				( attribute "VALUE" "221"
					( Origin gFrontEnd )
				)
				( attribute "VER" "1"
					( Origin gFrontEnd )
				)
				( attribute "WATTAGE" "1/16W"
					( Origin gFrontEnd )
				)
				( attribute "XY" "(-5450,3850)"
					( Origin gFrontEnd )
				)
				( attribute "CHIPS_PART_NAME" "RES"
					( Origin gPackager )
				)
				( attribute "CDS_PART_NAME" "RES_0402-221,1.0%,1/16W,CHIP,GA"
					( Origin gPackager )
				)
				( objectStatus "R2U42" )
				( pin "a"
					( attribute "PN" "1"
						( Origin gPackager )
					)
					( objectStatus "R2U42.1" )
				)
				( pin "b"
					( attribute "PN" "2"
						( Origin gPackager )
					)
					( objectStatus "R2U42.2" )
				)
			)
			( gate "@baseboard_fab2_lib.baseboard_fab2(sch_1):page161_i102"
				( attribute "BOM_COST" "SM_THERM"
					( Origin gFrontEnd )
				)
				( attribute "CDS_LIB" "mstr_discrete"
					( Origin gPackager )
				)
				( attribute "CDS_LOCATION" "R2U44"
					( Origin gPackager )
				)
				( attribute "CDS_SEC" "1"
					( Origin gPackager )
				)
				( attribute "LOCATION" "R2U44"
					( Origin gFrontEnd )
				)
				( attribute "MATERIAL" "CHIP"
					( Origin gFrontEnd )
				)
				( attribute "PACK_TYPE" "0402"
					( Origin gFrontEnd )
				)
				( attribute "PART_NUMBER" "G21796-271"
					( Origin gFrontEnd )
				)
				( attribute "PHYS_PAGE" "161"
					( Origin gFrontEnd )
				)
				( attribute "ROOM" "CPU_FANS"
					( Origin gFrontEnd )
				)
				( attribute "ROT" "0"
					( Origin gFrontEnd )
				)
				( attribute "SEC" "1"
					( Origin gFrontEnd )
				)
				( attribute "SEC_TYPE" "0402"
					( Origin gFrontEnd )
				)
				( attribute "TOLERANCE" "1.0%"
					( Origin gFrontEnd )
				)
				( attribute "VALUE" "221"
					( Origin gFrontEnd )
				)
				( attribute "VER" "1"
					( Origin gFrontEnd )
				)
				( attribute "WATTAGE" "1/16W"
					( Origin gFrontEnd )
				)
				( attribute "XY" "(-5600,1100)"
					( Origin gFrontEnd )
				)
				( attribute "CHIPS_PART_NAME" "RES"
					( Origin gPackager )
				)
				( attribute "CDS_PART_NAME" "RES_0402-221,1.0%,1/16W,CHIP,GA"
					( Origin gPackager )
				)
				( objectStatus "R2U44" )
				( pin "a"
					( attribute "PN" "1"
						( Origin gPackager )
					)
					( objectStatus "R2U44.1" )
				)
				( pin "b"
					( attribute "PN" "2"
						( Origin gPackager )
					)
					( objectStatus "R2U44.2" )
				)
			)
			( gate "@baseboard_fab2_lib.baseboard_fab2(sch_1):page161_i113"
				( attribute "BOM_COST" "SM_THERM"
					( Origin gFrontEnd )
				)
				( attribute "CDS_LIB" "dev_discrete"
					( Origin gPackager )
				)
				( attribute "CDS_LOCATION" "C1E22"
					( Origin gPackager )
				)
				( attribute "CDS_SEC" "1"
					( Origin gPackager )
				)
				( attribute "LOCATION" "C1E22"
					( Origin gFrontEnd )
				)
				( attribute "MATERIAL" "X7R"
					( Origin gFrontEnd )
				)
				( attribute "PACK_TYPE" "0402V"
					( Origin gFrontEnd )
				)
				( attribute "PART_NUMBER" "A36096-030"
					( Origin gFrontEnd )
				)
				( attribute "PHYS_PAGE" "161"
					( Origin gFrontEnd )
				)
				( attribute "ROOM" "CPUFANS"
					( Origin gFrontEnd )
				)
				( attribute "ROT" "0"
					( Origin gFrontEnd )
				)
				( attribute "SEC" "1"
					( Origin gFrontEnd )
				)
				( attribute "SEC_TYPE" "0402V"
					( Origin gFrontEnd )
				)
				( attribute "TOLERANCE" "10%"
					( Origin gFrontEnd )
				)
				( attribute "VALUE" "0.1UF"
					( Origin gFrontEnd )
				)
				( attribute "VER" "1"
					( Origin gFrontEnd )
				)
				( attribute "VOLTAGE" "16V"
					( Units "uVoltage" "V" 1.000000)
					( Origin gFrontEnd )
				)
				( attribute "XY" "(-5775,2150)"
					( Origin gFrontEnd )
				)
				( attribute "CHIPS_PART_NAME" "CAP_A"
					( Origin gPackager )
				)
				( attribute "CDS_PART_NAME" "CAP_A_0402V-0.1UF,16V,10%,X7R,A"
					( Origin gPackager )
				)
				( objectStatus "C1E22" )
				( pin "a"
					( attribute "PN" "1"
						( Origin gPackager )
					)
					( objectStatus "C1E22.1" )
				)
				( pin "b"
					( attribute "PN" "2"
						( Origin gPackager )
					)
					( objectStatus "C1E22.2" )
				)
			)
			( gate "@baseboard_fab2_lib.baseboard_fab2(sch_1):page161_i120"
				( attribute "BOM_COST" "SM_THERM"
					( Origin gFrontEnd )
				)
				( attribute "CDS_LIB" "mstr_discrete"
					( Origin gPackager )
				)
				( attribute "CDS_LOCATION" "R1E11"
					( Origin gPackager )
				)
				( attribute "CDS_SEC" "1"
					( Origin gPackager )
				)
				( attribute "LOCATION" "R1E11"
					( Origin gFrontEnd )
				)
				( attribute "MATERIAL" "EMPTY"
					( Origin gFrontEnd )
				)
				( attribute "PACK_TYPE" "0402"
					( Origin gFrontEnd )
				)
				( attribute "PART_NUMBER" "G21796-016"
					( Origin gFrontEnd )
				)
				( attribute "PHYS_PAGE" "161"
					( Origin gFrontEnd )
				)
				( attribute "ROOM" "CPU_FANS"
					( Origin gFrontEnd )
				)
				( attribute "ROT" "0"
					( Origin gFrontEnd )
				)
				( attribute "SEC" "1"
					( Origin gFrontEnd )
				)
				( attribute "SEC_TYPE" "0402"
					( Origin gFrontEnd )
				)
				( attribute "TOLERANCE" "1%"
					( Origin gFrontEnd )
				)
				( attribute "VALUE" "10.0K"
					( Origin gFrontEnd )
				)
				( attribute "VER" "2"
					( Origin gFrontEnd )
				)
				( attribute "WATTAGE" "1/16W"
					( Origin gFrontEnd )
				)
				( attribute "XY" "(-5950,2800)"
					( Origin gFrontEnd )
				)
				( attribute "CHIPS_PART_NAME" "RES"
					( Origin gPackager )
				)
				( attribute "CDS_PART_NAME" "RES_0402-10.0K,1%,1/16W,EMPTY,A"
					( Origin gPackager )
				)
				( objectStatus "R1E11" )
				( pin "a"
					( attribute "PN" "1"
						( Origin gPackager )
					)
					( objectStatus "R1E11.1" )
				)
				( pin "b"
					( attribute "PN" "2"
						( Origin gPackager )
					)
					( objectStatus "R1E11.2" )
				)
			)
			( gate "@baseboard_fab2_lib.baseboard_fab2(sch_1):page161_i121"
				( attribute "BOM_COST" "SM_THERM"
					( Origin gFrontEnd )
				)
				( attribute "CDS_LIB" "mstr_ttl"
					( Origin gPackager )
				)
				( attribute "CDS_LOCATION" "U1E2"
					( Origin gPackager )
				)
				( attribute "CDS_SEC" "1"
					( Origin gPackager )
				)
				( attribute "LOCATION" "U1E2"
					( Origin gFrontEnd )
				)
				( attribute "MATERIAL" "IC"
					( Origin gFrontEnd )
				)
				( attribute "PACK_TYPE" "SOTLF"
					( Origin gFrontEnd )
				)
				( attribute "PART_NUMBER" "D10321-001"
					( Origin gFrontEnd )
				)
				( attribute "PHYS_PAGE" "161"
					( Origin gFrontEnd )
				)
				( attribute "ROOM" "CPU_FANS"
					( Origin gFrontEnd )
				)
				( attribute "ROT" "0"
					( Origin gFrontEnd )
				)
				( attribute "SEC" "1"
					( Origin gFrontEnd )
				)
				( attribute "SEC_TYPE" "SOTLF"
					( Origin gFrontEnd )
				)
				( attribute "VALUE" "NC7SZ08"
					( Origin gFrontEnd )
				)
				( attribute "VER" "1"
					( Origin gFrontEnd )
				)
				( attribute "XY" "(-6250,2575)"
					( Origin gFrontEnd )
				)
				( attribute "CHIPS_PART_NAME" "TTL1G08"
					( Origin gPackager )
				)
				( attribute "CDS_PART_NAME" "TTL1G08_SOTLF-NC7SZ08,IC,D1032B"
					( Origin gPackager )
				)
				( objectStatus "U1E2" )
				( pin "a(0)"
					( attribute "PN" "1"
						( Origin gPackager )
					)
					( objectStatus "U1E2.1" )
				)
				( pin "b(0)"
					( attribute "PN" "2"
						( Origin gPackager )
					)
					( objectStatus "U1E2.2" )
				)
				( pin "y(0)"
					( attribute "PN" "4"
						( Origin gPackager )
					)
					( objectStatus "U1E2.4" )
				)
			)
			( gate "@baseboard_fab2_lib.baseboard_fab2(sch_1):page161_i123"
				( attribute "BOM_COST" "SM_THERM"
					( Origin gFrontEnd )
				)
				( attribute "CDS_LIB" "mstr_discrete"
					( Origin gPackager )
				)
				( attribute "CDS_LOCATION" "CR1B3"
					( Origin gPackager )
				)
				( attribute "CDS_SEC" "1"
					( Origin gPackager )
				)
				( attribute "LOCATION" "CR1B3"
					( Origin gFrontEnd )
				)
				( attribute "MATERIAL" "IC"
					( Origin gFrontEnd )
				)
				( attribute "PACK_TYPE" "SM"
					( Origin gFrontEnd )
				)
				( attribute "PART_NUMBER" "H71799-001"
					( Origin gFrontEnd )
				)
				( attribute "PHYS_PAGE" "161"
					( Origin gFrontEnd )
				)
				( attribute "ROOM" "CPU_FANS"
					( Origin gFrontEnd )
				)
				( attribute "ROT" "0"
					( Origin gFrontEnd )
				)
				( attribute "SEC" "1"
					( Origin gFrontEnd )
				)
				( attribute "SEC_TYPE" "SM"
					( Origin gFrontEnd )
				)
				( attribute "VALUE" "SDMK0340L"
					( Origin gFrontEnd )
				)
				( attribute "VER" "1"
					( Origin gFrontEnd )
				)
				( attribute "XY" "(-1775,675)"
					( Origin gFrontEnd )
				)
				( attribute "CHIPS_PART_NAME" "DIODE"
					( Origin gPackager )
				)
				( attribute "CDS_PART_NAME" "DIODE_SM-SDMK0340L,IC,H71799-0A"
					( Origin gPackager )
				)
				( objectStatus "CR1B3" )
				( pin "a"
					( attribute "PN" "2"
						( Origin gPackager )
					)
					( objectStatus "CR1B3.2" )
				)
				( pin "c"
					( attribute "PN" "1"
						( Origin gPackager )
					)
					( objectStatus "CR1B3.1" )
				)
			)
			( gate "@baseboard_fab2_lib.baseboard_fab2(sch_1):page161_i124"
				( attribute "BOM_COST" "SM_THERM"
					( Origin gFrontEnd )
				)
				( attribute "CDS_LIB" "mstr_discrete"
					( Origin gPackager )
				)
				( attribute "CDS_LOCATION" "R1B23"
					( Origin gPackager )
				)
				( attribute "CDS_SEC" "1"
					( Origin gPackager )
				)
				( attribute "LOCATION" "R1B23"
					( Origin gFrontEnd )
				)
				( attribute "MATERIAL" "CHIP"
					( Origin gFrontEnd )
				)
				( attribute "PACK_TYPE" "0402"
					( Origin gFrontEnd )
				)
				( attribute "PART_NUMBER" "G21796-017"
					( Origin gFrontEnd )
				)
				( attribute "PHYS_PAGE" "161"
					( Origin gFrontEnd )
				)
				( attribute "ROOM" "CPU_FANS"
					( Origin gFrontEnd )
				)
				( attribute "ROT" "0"
					( Origin gFrontEnd )
				)
				( attribute "SEC" "1"
					( Origin gFrontEnd )
				)
				( attribute "SEC_TYPE" "0402"
					( Origin gFrontEnd )
				)
				( attribute "TOLERANCE" "1%"
					( Origin gFrontEnd )
				)
				( attribute "VALUE" "100.0"
					( Origin gFrontEnd )
				)
				( attribute "VER" "1"
					( Origin gFrontEnd )
				)
				( attribute "WATTAGE" "1/16W"
					( Origin gFrontEnd )
				)
				( attribute "XY" "(-2625,675)"
					( Origin gFrontEnd )
				)
				( attribute "CHIPS_PART_NAME" "RES"
					( Origin gPackager )
				)
				( attribute "CDS_PART_NAME" "RES_0402-100.0,1%,1/16W,CHIP,GA"
					( Origin gPackager )
				)
				( objectStatus "R1B23" )
				( pin "a"
					( attribute "PN" "1"
						( Origin gPackager )
					)
					( objectStatus "R1B23.1" )
				)
				( pin "b"
					( attribute "PN" "2"
						( Origin gPackager )
					)
					( objectStatus "R1B23.2" )
				)
			)
			( gate "@baseboard_fab2_lib.baseboard_fab2(sch_1):page161_i126"
				( attribute "BOM_COST" "SM_THERM"
					( Origin gFrontEnd )
				)
				( attribute "CDS_LIB" "mstr_discrete"
					( Origin gPackager )
				)
				( attribute "CDS_LOCATION" "R1B24"
					( Origin gPackager )
				)
				( attribute "CDS_SEC" "1"
					( Origin gPackager )
				)
				( attribute "LOCATION" "R1B24"
					( Origin gFrontEnd )
				)
				( attribute "MATERIAL" "CHIP"
					( Origin gFrontEnd )
				)
				( attribute "PACK_TYPE" "0402"
					( Origin gFrontEnd )
				)
				( attribute "PART_NUMBER" "G21796-072"
					( Origin gFrontEnd )
				)
				( attribute "PHYS_PAGE" "161"
					( Origin gFrontEnd )
				)
				( attribute "ROOM" "CPU_FANS"
					( Origin gFrontEnd )
				)
				( attribute "ROT" "2"
					( Origin gFrontEnd )
				)
				( attribute "SEC" "1"
					( Origin gFrontEnd )
				)
				( attribute "SEC_TYPE" "0402"
					( Origin gFrontEnd )
				)
				( attribute "TOLERANCE" "1%"
					( Origin gFrontEnd )
				)
				( attribute "VALUE" "4.75K"
					( Origin gFrontEnd )
				)
				( attribute "VER" "2"
					( Origin gFrontEnd )
				)
				( attribute "WATTAGE" "1/16W"
					( Origin gFrontEnd )
				)
				( attribute "XY" "(-2925,825)"
					( Origin gFrontEnd )
				)
				( attribute "CHIPS_PART_NAME" "RES"
					( Origin gPackager )
				)
				( attribute "CDS_PART_NAME" "RES_0402-4.75K,1%,1/16W,CHIP,GA"
					( Origin gPackager )
				)
				( objectStatus "R1B24" )
				( pin "a"
					( attribute "PN" "1"
						( Origin gPackager )
					)
					( objectStatus "R1B24.1" )
				)
				( pin "b"
					( attribute "PN" "2"
						( Origin gPackager )
					)
					( objectStatus "R1B24.2" )
				)
			)
			( gate "@baseboard_fab2_lib.baseboard_fab2(sch_1):page161_i128"
				( attribute "BOM_COST" "SM_THERM"
					( Origin gFrontEnd )
				)
				( attribute "CDS_LIB" "dev_discrete"
					( Origin gPackager )
				)
				( attribute "CDS_LOCATION" "C1B17"
					( Origin gPackager )
				)
				( attribute "CDS_SEC" "1"
					( Origin gPackager )
				)
				( attribute "LOCATION" "C1B17"
					( Origin gFrontEnd )
				)
				( attribute "MATERIAL" "X7R"
					( Origin gFrontEnd )
				)
				( attribute "PACK_TYPE" "0402V"
					( Origin gFrontEnd )
				)
				( attribute "PART_NUMBER" "A36096-045"
					( Origin gFrontEnd )
				)
				( attribute "PHYS_PAGE" "161"
					( Origin gFrontEnd )
				)
				( attribute "ROOM" "CPU_FANS"
					( Origin gFrontEnd )
				)
				( attribute "ROT" "2"
					( Origin gFrontEnd )
				)
				( attribute "SEC" "1"
					( Origin gFrontEnd )
				)
				( attribute "SEC_TYPE" "0402V"
					( Origin gFrontEnd )
				)
				( attribute "TOLERANCE" "10%"
					( Origin gFrontEnd )
				)
				( attribute "VALUE" "0.01UF"
					( Origin gFrontEnd )
				)
				( attribute "VER" "1"
					( Origin gFrontEnd )
				)
				( attribute "VOLTAGE" "25V"
					( Units "uVoltage" "V" 1.000000)
					( Origin gFrontEnd )
				)
				( attribute "XY" "(-3175,550)"
					( Origin gFrontEnd )
				)
				( attribute "CHIPS_PART_NAME" "CAP_A"
					( Origin gPackager )
				)
				( attribute "CDS_PART_NAME" "CAP_A_0402V-0.01UF,25V,10%,X7RA"
					( Origin gPackager )
				)
				( objectStatus "C1B17" )
				( pin "a"
					( attribute "PN" "1"
						( Origin gPackager )
					)
					( objectStatus "C1B17.1" )
				)
				( pin "b"
					( attribute "PN" "2"
						( Origin gPackager )
					)
					( objectStatus "C1B17.2" )
				)
			)
			( gate "@baseboard_fab2_lib.baseboard_fab2(sch_1):page161_i133"
				( attribute "BOM_COST" "SM_THERM"
					( Origin gFrontEnd )
				)
				( attribute "CDS_LIB" "mstr_discrete"
					( Origin gPackager )
				)
				( attribute "CDS_LOCATION" "CR1F2"
					( Origin gPackager )
				)
				( attribute "CDS_SEC" "1"
					( Origin gPackager )
				)
				( attribute "LOCATION" "CR1F2"
					( Origin gFrontEnd )
				)
				( attribute "MATERIAL" "IC"
					( Origin gFrontEnd )
				)
				( attribute "PACK_TYPE" "SM"
					( Origin gFrontEnd )
				)
				( attribute "PART_NUMBER" "H71799-001"
					( Origin gFrontEnd )
				)
				( attribute "PHYS_PAGE" "161"
					( Origin gFrontEnd )
				)
				( attribute "ROOM" "CPU_FANS"
					( Origin gFrontEnd )
				)
				( attribute "ROT" "0"
					( Origin gFrontEnd )
				)
				( attribute "SEC" "1"
					( Origin gFrontEnd )
				)
				( attribute "SEC_TYPE" "SM"
					( Origin gFrontEnd )
				)
				( attribute "VALUE" "SDMK0340L"
					( Origin gFrontEnd )
				)
				( attribute "VER" "1"
					( Origin gFrontEnd )
				)
				( attribute "XY" "(-1975,2775)"
					( Origin gFrontEnd )
				)
				( attribute "CHIPS_PART_NAME" "DIODE"
					( Origin gPackager )
				)
				( attribute "CDS_PART_NAME" "DIODE_SM-SDMK0340L,IC,H71799-0A"
					( Origin gPackager )
				)
				( objectStatus "CR1F2" )
				( pin "a"
					( attribute "PN" "2"
						( Origin gPackager )
					)
					( objectStatus "CR1F2.2" )
				)
				( pin "c"
					( attribute "PN" "1"
						( Origin gPackager )
					)
					( objectStatus "CR1F2.1" )
				)
			)
			( gate "@baseboard_fab2_lib.baseboard_fab2(sch_1):page161_i134"
				( attribute "BOM_COST" "SM_THERM"
					( Origin gFrontEnd )
				)
				( attribute "CDS_LIB" "mstr_discrete"
					( Origin gPackager )
				)
				( attribute "CDS_LOCATION" "R9T7"
					( Origin gPackager )
				)
				( attribute "CDS_SEC" "1"
					( Origin gPackager )
				)
				( attribute "LOCATION" "R9T7"
					( Origin gFrontEnd )
				)
				( attribute "MATERIAL" "CHIP"
					( Origin gFrontEnd )
				)
				( attribute "PACK_TYPE" "0402"
					( Origin gFrontEnd )
				)
				( attribute "PART_NUMBER" "G21796-017"
					( Origin gFrontEnd )
				)
				( attribute "PHYS_PAGE" "161"
					( Origin gFrontEnd )
				)
				( attribute "ROOM" "CPU_FANS"
					( Origin gFrontEnd )
				)
				( attribute "ROT" "0"
					( Origin gFrontEnd )
				)
				( attribute "SEC" "1"
					( Origin gFrontEnd )
				)
				( attribute "SEC_TYPE" "0402"
					( Origin gFrontEnd )
				)
				( attribute "TOLERANCE" "1%"
					( Origin gFrontEnd )
				)
				( attribute "VALUE" "100.0"
					( Origin gFrontEnd )
				)
				( attribute "VER" "1"
					( Origin gFrontEnd )
				)
				( attribute "WATTAGE" "1/16W"
					( Origin gFrontEnd )
				)
				( attribute "XY" "(-2850,2775)"
					( Origin gFrontEnd )
				)
				( attribute "CHIPS_PART_NAME" "RES"
					( Origin gPackager )
				)
				( attribute "CDS_PART_NAME" "RES_0402-100.0,1%,1/16W,CHIP,GA"
					( Origin gPackager )
				)
				( objectStatus "R9T7" )
				( pin "a"
					( attribute "PN" "1"
						( Origin gPackager )
					)
					( objectStatus "R9T7.1" )
				)
				( pin "b"
					( attribute "PN" "2"
						( Origin gPackager )
					)
					( objectStatus "R9T7.2" )
				)
			)
			( gate "@baseboard_fab2_lib.baseboard_fab2(sch_1):page161_i135"
				( attribute "BOM_COST" "SM_THERM"
					( Origin gFrontEnd )
				)
				( attribute "CDS_LIB" "mstr_discrete"
					( Origin gPackager )
				)
				( attribute "CDS_LOCATION" "R9T5"
					( Origin gPackager )
				)
				( attribute "CDS_SEC" "1"
					( Origin gPackager )
				)
				( attribute "LOCATION" "R9T5"
					( Origin gFrontEnd )
				)
				( attribute "MATERIAL" "CHIP"
					( Origin gFrontEnd )
				)
				( attribute "PACK_TYPE" "0402"
					( Origin gFrontEnd )
				)
				( attribute "PART_NUMBER" "G21796-072"
					( Origin gFrontEnd )
				)
				( attribute "PHYS_PAGE" "161"
					( Origin gFrontEnd )
				)
				( attribute "ROOM" "CPU_FANS"
					( Origin gFrontEnd )
				)
				( attribute "ROT" "2"
					( Origin gFrontEnd )
				)
				( attribute "SEC" "1"
					( Origin gFrontEnd )
				)
				( attribute "SEC_TYPE" "0402"
					( Origin gFrontEnd )
				)
				( attribute "TOLERANCE" "1%"
					( Origin gFrontEnd )
				)
				( attribute "VALUE" "4.75K"
					( Origin gFrontEnd )
				)
				( attribute "VER" "2"
					( Origin gFrontEnd )
				)
				( attribute "WATTAGE" "1/16W"
					( Origin gFrontEnd )
				)
				( attribute "XY" "(-3225,2925)"
					( Origin gFrontEnd )
				)
				( attribute "CHIPS_PART_NAME" "RES"
					( Origin gPackager )
				)
				( attribute "CDS_PART_NAME" "RES_0402-4.75K,1%,1/16W,CHIP,GA"
					( Origin gPackager )
				)
				( objectStatus "R9T5" )
				( pin "a"
					( attribute "PN" "1"
						( Origin gPackager )
					)
					( objectStatus "R9T5.1" )
				)
				( pin "b"
					( attribute "PN" "2"
						( Origin gPackager )
					)
					( objectStatus "R9T5.2" )
				)
			)
			( gate "@baseboard_fab2_lib.baseboard_fab2(sch_1):page161_i137"
				( attribute "BOM_COST" "SM_THERM"
					( Origin gFrontEnd )
				)
				( attribute "CDS_LIB" "dev_discrete"
					( Origin gPackager )
				)
				( attribute "CDS_LOCATION" "C9T1"
					( Origin gPackager )
				)
				( attribute "CDS_SEC" "1"
					( Origin gPackager )
				)
				( attribute "LOCATION" "C9T1"
					( Origin gFrontEnd )
				)
				( attribute "MATERIAL" "X7R"
					( Origin gFrontEnd )
				)
				( attribute "PACK_TYPE" "0402V"
					( Origin gFrontEnd )
				)
				( attribute "PART_NUMBER" "A36096-045"
					( Origin gFrontEnd )
				)
				( attribute "PHYS_PAGE" "161"
					( Origin gFrontEnd )
				)
				( attribute "ROOM" "CPU_FANS"
					( Origin gFrontEnd )
				)
				( attribute "ROT" "2"
					( Origin gFrontEnd )
				)
				( attribute "SEC" "1"
					( Origin gFrontEnd )
				)
				( attribute "SEC_TYPE" "0402V"
					( Origin gFrontEnd )
				)
				( attribute "TOLERANCE" "10%"
					( Origin gFrontEnd )
				)
				( attribute "VALUE" "0.01UF"
					( Origin gFrontEnd )
				)
				( attribute "VER" "1"
					( Origin gFrontEnd )
				)
				( attribute "VOLTAGE" "25V"
					( Units "uVoltage" "V" 1.000000)
					( Origin gFrontEnd )
				)
				( attribute "XY" "(-3300,2625)"
					( Origin gFrontEnd )
				)
				( attribute "CHIPS_PART_NAME" "CAP_A"
					( Origin gPackager )
				)
				( attribute "CDS_PART_NAME" "CAP_A_0402V-0.01UF,25V,10%,X7RA"
					( Origin gPackager )
				)
				( objectStatus "C9T1" )
				( pin "a"
					( attribute "PN" "1"
						( Origin gPackager )
					)
					( objectStatus "C9T1.1" )
				)
				( pin "b"
					( attribute "PN" "2"
						( Origin gPackager )
					)
					( objectStatus "C9T1.2" )
				)
			)
			( gate "@baseboard_fab2_lib.baseboard_fab2(sch_1):page162_i8"
				( attribute "BOM_COST" "SM_MEM"
					( Origin gFrontEnd )
				)
				( attribute "CDS_LIB" "mstr_discrete"
					( Origin gPackager )
				)
				( attribute "CDS_LOCATION" "R8F16"
					( Origin gPackager )
				)
				( attribute "CDS_SEC" "1"
					( Origin gPackager )
				)
				( attribute "LOCATION" "R8F16"
					( Origin gFrontEnd )
				)
				( attribute "MATERIAL" "EMPTY"
					( Origin gFrontEnd )
				)
				( attribute "PACK_TYPE" "0402"
					( Origin gFrontEnd )
				)
				( attribute "PART_NUMBER" "G21796-072"
					( Origin gFrontEnd )
				)
				( attribute "PHYS_PAGE" "162"
					( Origin gFrontEnd )
				)
				( attribute "ROOM" "BMC_BOOT_SPI"
					( Origin gFrontEnd )
				)
				( attribute "ROT" "0"
					( Origin gFrontEnd )
				)
				( attribute "SEC" "1"
					( Origin gFrontEnd )
				)
				( attribute "SEC_TYPE" "0402"
					( Origin gFrontEnd )
				)
				( attribute "TOLERANCE" "1%"
					( Origin gFrontEnd )
				)
				( attribute "VALUE" "4.75K"
					( Origin gFrontEnd )
				)
				( attribute "VER" "2"
					( Origin gFrontEnd )
				)
				( attribute "WATTAGE" "1/16W"
					( Origin gFrontEnd )
				)
				( attribute "XY" "(5300,3300)"
					( Origin gFrontEnd )
				)
				( attribute "CHIPS_PART_NAME" "RES"
					( Origin gPackager )
				)
				( attribute "CDS_PART_NAME" "RES_0402-4.75K,1%,1/16W,EMPTY,A"
					( Origin gPackager )
				)
				( objectStatus "R8F16" )
				( pin "a"
					( attribute "PN" "1"
						( Origin gPackager )
					)
					( objectStatus "R8F16.1" )
				)
				( pin "b"
					( attribute "PN" "2"
						( Origin gPackager )
					)
					( objectStatus "R8F16.2" )
				)
			)
			( gate "@baseboard_fab2_lib.baseboard_fab2(sch_1):page162_i9"
				( attribute "BOM_COST" "SM_MEM"
					( Origin gFrontEnd )
				)
				( attribute "CDS_LIB" "mstr_discrete"
					( Origin gPackager )
				)
				( attribute "CDS_LOCATION" "R8F14"
					( Origin gPackager )
				)
				( attribute "CDS_SEC" "1"
					( Origin gPackager )
				)
				( attribute "LOCATION" "R8F14"
					( Origin gFrontEnd )
				)
				( attribute "MATERIAL" "CHIP"
					( Origin gFrontEnd )
				)
				( attribute "PACK_TYPE" "0402"
					( Origin gFrontEnd )
				)
				( attribute "PART_NUMBER" "G21796-072"
					( Origin gFrontEnd )
				)
				( attribute "PHYS_PAGE" "162"
					( Origin gFrontEnd )
				)
				( attribute "ROOM" "BMC_BOOT_SPI"
					( Origin gFrontEnd )
				)
				( attribute "ROT" "2"
					( Origin gFrontEnd )
				)
				( attribute "SEC" "1"
					( Origin gFrontEnd )
				)
				( attribute "SEC_TYPE" "0402"
					( Origin gFrontEnd )
				)
				( attribute "TOLERANCE" "1%"
					( Origin gFrontEnd )
				)
				( attribute "VALUE" "4.75K"
					( Origin gFrontEnd )
				)
				( attribute "VER" "2"
					( Origin gFrontEnd )
				)
				( attribute "WATTAGE" "1/16W"
					( Origin gFrontEnd )
				)
				( attribute "XY" "(5100,3325)"
					( Origin gFrontEnd )
				)
				( attribute "CHIPS_PART_NAME" "RES"
					( Origin gPackager )
				)
				( attribute "CDS_PART_NAME" "RES_0402-4.75K,1%,1/16W,CHIP,GA"
					( Origin gPackager )
				)
				( objectStatus "R8F14" )
				( pin "a"
					( attribute "PN" "1"
						( Origin gPackager )
					)
					( objectStatus "R8F14.1" )
				)
				( pin "b"
					( attribute "PN" "2"
						( Origin gPackager )
					)
					( objectStatus "R8F14.2" )
				)
			)
			( gate "@baseboard_fab2_lib.baseboard_fab2(sch_1):page162_i13"
				( attribute "BOM_COST" "SM_MEM"
					( Origin gFrontEnd )
				)
				( attribute "CDS_LIB" "mstr_discrete"
					( Origin gPackager )
				)
				( attribute "CDS_LOCATION" "R8F12"
					( Origin gPackager )
				)
				( attribute "CDS_SEC" "1"
					( Origin gPackager )
				)
				( attribute "LOCATION" "R8F12"
					( Origin gFrontEnd )
				)
				( attribute "MATERIAL" "CHIP"
					( Origin gFrontEnd )
				)
				( attribute "PACK_TYPE" "0402"
					( Origin gFrontEnd )
				)
				( attribute "PART_NUMBER" "G21796-074"
					( Origin gFrontEnd )
				)
				( attribute "PHYS_PAGE" "162"
					( Origin gFrontEnd )
				)
				( attribute "ROOM" "BMC_BOOT_SPI"
					( Origin gFrontEnd )
				)
				( attribute "ROT" "0"
					( Origin gFrontEnd )
				)
				( attribute "SEC" "1"
					( Origin gFrontEnd )
				)
				( attribute "SEC_TYPE" "0402"
					( Origin gFrontEnd )
				)
				( attribute "TOLERANCE" "1%"
					( Origin gFrontEnd )
				)
				( attribute "VALUE" "33.2"
					( Origin gFrontEnd )
				)
				( attribute "VER" "1"
					( Origin gFrontEnd )
				)
				( attribute "WATTAGE" "1/16W"
					( Origin gFrontEnd )
				)
				( attribute "XY" "(5075,2550)"
					( Origin gFrontEnd )
				)
				( attribute "CHIPS_PART_NAME" "RES"
					( Origin gPackager )
				)
				( attribute "CDS_PART_NAME" "RES_0402-33.2,1%,1/16W,CHIP,G2A"
					( Origin gPackager )
				)
				( objectStatus "R8F12" )
				( pin "a"
					( attribute "PN" "1"
						( Origin gPackager )
					)
					( objectStatus "R8F12.1" )
				)
				( pin "b"
					( attribute "PN" "2"
						( Origin gPackager )
					)
					( objectStatus "R8F12.2" )
				)
			)
			( gate "@baseboard_fab2_lib.baseboard_fab2(sch_1):page162_i22"
				( attribute "BOM_COST" "SM_MEM"
					( Origin gFrontEnd )
				)
				( attribute "CDS_LIB" "mstr_discrete"
					( Origin gPackager )
				)
				( attribute "CDS_LOCATION" "R8F34"
					( Origin gPackager )
				)
				( attribute "CDS_SEC" "1"
					( Origin gPackager )
				)
				( attribute "LOCATION" "R8F34"
					( Origin gFrontEnd )
				)
				( attribute "MATERIAL" "CHIP"
					( Origin gFrontEnd )
				)
				( attribute "PACK_TYPE" "0402"
					( Origin gFrontEnd )
				)
				( attribute "PART_NUMBER" "G21796-072"
					( Origin gFrontEnd )
				)
				( attribute "PHYS_PAGE" "162"
					( Origin gFrontEnd )
				)
				( attribute "ROOM" "BMC_BOOT_SPI"
					( Origin gFrontEnd )
				)
				( attribute "ROT" "2"
					( Origin gFrontEnd )
				)
				( attribute "SEC" "1"
					( Origin gPackager )
				)
				( attribute "TOLERANCE" "1%"
					( Origin gFrontEnd )
				)
				( attribute "VALUE" "4.75K"
					( Origin gFrontEnd )
				)
				( attribute "VER" "2"
					( Origin gFrontEnd )
				)
				( attribute "WATTAGE" "1/16W"
					( Origin gFrontEnd )
				)
				( attribute "XY" "(4825,3325)"
					( Origin gFrontEnd )
				)
				( attribute "CHIPS_PART_NAME" "RES"
					( Origin gPackager )
				)
				( attribute "CDS_PART_NAME" "RES_0402-4.75K,1%,1/16W,CHIP,GA"
					( Origin gPackager )
				)
				( objectStatus "R8F34" )
				( pin "a"
					( attribute "PN" "1"
						( Origin gPackager )
					)
					( objectStatus "R8F34.1" )
				)
				( pin "b"
					( attribute "PN" "2"
						( Origin gPackager )
					)
					( objectStatus "R8F34.2" )
				)
			)
			( gate "@baseboard_fab2_lib.baseboard_fab2(sch_1):page162_i23"
				( attribute "BOM_COST" "SM_MEM"
					( Origin gFrontEnd )
				)
				( attribute "CDS_LIB" "mstr_discrete"
					( Origin gPackager )
				)
				( attribute "CDS_LOCATION" "R8F13"
					( Origin gPackager )
				)
				( attribute "CDS_SEC" "1"
					( Origin gPackager )
				)
				( attribute "LOCATION" "R8F13"
					( Origin gFrontEnd )
				)
				( attribute "MATERIAL" "CHIP"
					( Origin gFrontEnd )
				)
				( attribute "PACK_TYPE" "0402"
					( Origin gFrontEnd )
				)
				( attribute "PART_NUMBER" "G21796-072"
					( Origin gFrontEnd )
				)
				( attribute "PHYS_PAGE" "162"
					( Origin gFrontEnd )
				)
				( attribute "ROOM" "BMC_BOOT_SPI"
					( Origin gFrontEnd )
				)
				( attribute "ROT" "2"
					( Origin gFrontEnd )
				)
				( attribute "SEC" "1"
					( Origin gPackager )
				)
				( attribute "TOLERANCE" "1%"
					( Origin gFrontEnd )
				)
				( attribute "VALUE" "4.75K"
					( Origin gFrontEnd )
				)
				( attribute "VER" "2"
					( Origin gFrontEnd )
				)
				( attribute "WATTAGE" "1/16W"
					( Origin gFrontEnd )
				)
				( attribute "XY" "(4550,3325)"
					( Origin gFrontEnd )
				)
				( attribute "CHIPS_PART_NAME" "RES"
					( Origin gPackager )
				)
				( attribute "CDS_PART_NAME" "RES_0402-4.75K,1%,1/16W,CHIP,GA"
					( Origin gPackager )
				)
				( objectStatus "R8F13" )
				( pin "a"
					( attribute "PN" "1"
						( Origin gPackager )
					)
					( objectStatus "R8F13.1" )
				)
				( pin "b"
					( attribute "PN" "2"
						( Origin gPackager )
					)
					( objectStatus "R8F13.2" )
				)
			)
			( gate "@baseboard_fab2_lib.baseboard_fab2(sch_1):page162_i24"
				( attribute "BOM_COST" "SM_MEM"
					( Origin gFrontEnd )
				)
				( attribute "CDS_LIB" "mstr_discrete"
					( Origin gPackager )
				)
				( attribute "CDS_LOCATION" "R8F35"
					( Origin gPackager )
				)
				( attribute "CDS_SEC" "1"
					( Origin gPackager )
				)
				( attribute "LOCATION" "R8F35"
					( Origin gFrontEnd )
				)
				( attribute "MATERIAL" "EMPTY"
					( Origin gFrontEnd )
				)
				( attribute "PACK_TYPE" "0402"
					( Origin gFrontEnd )
				)
				( attribute "PART_NUMBER" "G21796-026"
					( Origin gFrontEnd )
				)
				( attribute "PHYS_PAGE" "162"
					( Origin gFrontEnd )
				)
				( attribute "ROOM" "BMC_BOOT_SPI"
					( Origin gFrontEnd )
				)
				( attribute "ROT" "0"
					( Origin gFrontEnd )
				)
				( attribute "SEC" "1"
					( Origin gPackager )
				)
				( attribute "TOLERANCE" "1%"
					( Origin gFrontEnd )
				)
				( attribute "VALUE" "1.00K"
					( Origin gFrontEnd )
				)
				( attribute "VER" "2"
					( Origin gFrontEnd )
				)
				( attribute "WATTAGE" "1/16W"
					( Origin gFrontEnd )
				)
				( attribute "XY" "(4875,2050)"
					( Origin gFrontEnd )
				)
				( attribute "CHIPS_PART_NAME" "RES"
					( Origin gPackager )
				)
				( attribute "CDS_PART_NAME" "RES_0402-1.00K,1%,1/16W,EMPTY,A"
					( Origin gPackager )
				)
				( objectStatus "R8F35" )
				( pin "a"
					( attribute "PN" "1"
						( Origin gPackager )
					)
					( objectStatus "R8F35.1" )
				)
				( pin "b"
					( attribute "PN" "2"
						( Origin gPackager )
					)
					( objectStatus "R8F35.2" )
				)
			)
			( gate "@baseboard_fab2_lib.baseboard_fab2(sch_1):page162_i28"
				( attribute "BOM_COST" "SM_MEM"
					( Origin gFrontEnd )
				)
				( attribute "CDS_LIB" "dev_discrete"
					( Origin gPackager )
				)
				( attribute "CDS_LOCATION" "C8F5"
					( Origin gPackager )
				)
				( attribute "CDS_SEC" "1"
					( Origin gPackager )
				)
				( attribute "LOCATION" "C8F5"
					( Origin gFrontEnd )
				)
				( attribute "MATERIAL" "X7R"
					( Origin gFrontEnd )
				)
				( attribute "PACK_TYPE" "0402V"
					( Origin gFrontEnd )
				)
				( attribute "PART_NUMBER" "A36096-045"
					( Origin gFrontEnd )
				)
				( attribute "PHYS_PAGE" "162"
					( Origin gFrontEnd )
				)
				( attribute "ROOM" "BMC_BOOT_SPI"
					( Origin gFrontEnd )
				)
				( attribute "ROT" "0"
					( Origin gFrontEnd )
				)
				( attribute "SEC" "1"
					( Origin gPackager )
				)
				( attribute "TOLERANCE" "10%"
					( Origin gFrontEnd )
				)
				( attribute "VALUE" "0.01UF"
					( Origin gFrontEnd )
				)
				( attribute "VER" "1"
					( Origin gFrontEnd )
				)
				( attribute "VOLTAGE" "25V"
					( Units "uVoltage" "V" 1.000000)
					( Origin gFrontEnd )
				)
				( attribute "XY" "(7650,3400)"
					( Origin gFrontEnd )
				)
				( attribute "CHIPS_PART_NAME" "CAP_A"
					( Origin gPackager )
				)
				( attribute "CDS_PART_NAME" "CAP_A_0402V-0.01UF,25V,10%,X7RA"
					( Origin gPackager )
				)
				( objectStatus "C8F5" )
				( pin "a"
					( attribute "PN" "1"
						( Origin gPackager )
					)
					( objectStatus "C8F5.1" )
				)
				( pin "b"
					( attribute "PN" "2"
						( Origin gPackager )
					)
					( objectStatus "C8F5.2" )
				)
			)
			( gate "@baseboard_fab2_lib.baseboard_fab2(sch_1):page162_i30"
				( attribute "BOM_COST" "SM_MEM"
					( Origin gFrontEnd )
				)
				( attribute "CDS_LIB" "dev_discrete"
					( Origin gPackager )
				)
				( attribute "CDS_LOCATION" "C8F4"
					( Origin gPackager )
				)
				( attribute "CDS_SEC" "1"
					( Origin gPackager )
				)
				( attribute "LOCATION" "C8F4"
					( Origin gFrontEnd )
				)
				( attribute "MATERIAL" "X6S"
					( Origin gFrontEnd )
				)
				( attribute "PACK_TYPE" "0402V"
					( Origin gFrontEnd )
				)
				( attribute "PART_NUMBER" "D97712-004"
					( Origin gFrontEnd )
				)
				( attribute "PHYS_PAGE" "162"
					( Origin gFrontEnd )
				)
				( attribute "ROOM" "BMC_BOOT_SPI"
					( Origin gFrontEnd )
				)
				( attribute "ROT" "0"
					( Origin gFrontEnd )
				)
				( attribute "SEC" "1"
					( Origin gPackager )
				)
				( attribute "TOLERANCE" "10%"
					( Origin gFrontEnd )
				)
				( attribute "VALUE" "1.0UF"
					( Origin gFrontEnd )
				)
				( attribute "VER" "1"
					( Origin gFrontEnd )
				)
				( attribute "VOLTAGE" "6.3V"
					( Units "uVoltage" "V" 1.000000)
					( Origin gFrontEnd )
				)
				( attribute "XY" "(7350,3400)"
					( Origin gFrontEnd )
				)
				( attribute "CHIPS_PART_NAME" "CAP_A"
					( Origin gPackager )
				)
				( attribute "CDS_PART_NAME" "CAP_A_0402V-1.0UF,6.3V,10%,X6SA"
					( Origin gPackager )
				)
				( objectStatus "C8F4" )
				( pin "a"
					( attribute "PN" "1"
						( Origin gPackager )
					)
					( objectStatus "C8F4.1" )
				)
				( pin "b"
					( attribute "PN" "2"
						( Origin gPackager )
					)
					( objectStatus "C8F4.2" )
				)
			)
			( gate "@baseboard_fab2_lib.baseboard_fab2(sch_1):page162_i32"
				( attribute "BOM_COST" "SM_MEM"
					( Origin gFrontEnd )
				)
				( attribute "CDS_LIB" "mstr_memory"
					( Origin gPackager )
				)
				( attribute "CDS_LMAN_SYM_OUTLINE" "-500,325,500,-325"
					( Origin gPackager )
				)
				( attribute "CDS_LOCATION" "U8F2"
					( Origin gPackager )
				)
				( attribute "CDS_SEC" "1"
					( Origin gPackager )
				)
				( attribute "LOCATION" "U8F2"
					( Origin gFrontEnd )
				)
				( attribute "MATERIAL" "IC"
					( Origin gFrontEnd )
				)
				( attribute "PACK_TYPE" "SKT16"
					( Origin gFrontEnd )
				)
				( attribute "PART_NUMBER" "H12709-001"
					( Origin gFrontEnd )
				)
				( attribute "PHYS_PAGE" "162"
					( Origin gFrontEnd )
				)
				( attribute "ROOM" "BMC_BOOT_SPI"
					( Origin gFrontEnd )
				)
				( attribute "ROT" "0"
					( Origin gFrontEnd )
				)
				( attribute "SEC" "1"
					( Origin gFrontEnd )
				)
				( attribute "SEC_TYPE" "SKT16"
					( Origin gFrontEnd )
				)
				( attribute "VER" "3"
					( Origin gFrontEnd )
				)
				( attribute "XY" "(6450,2800)"
					( Origin gFrontEnd )
				)
				( attribute "CHIPS_PART_NAME" "W25Q128"
					( Origin gPackager )
				)
				( attribute "CDS_PART_NAME" "W25Q128_SKT16-IC,H12709-001"
					( Origin gPackager )
				)
				( objectStatus "U8F2" )
				( pin "clk"
					( attribute "PN" "16"
						( Origin gPackager )
					)
					( objectStatus "U8F2.16" )
				)
				( pin "cs_n"
					( attribute "PN" "7"
						( Origin gPackager )
					)
					( objectStatus "U8F2.7" )
				)
				( pin "di_io(0)"
					( attribute "PN" "15"
						( Origin gPackager )
					)
					( objectStatus "U8F2.15" )
				)
				( pin "do_io(1)"
					( attribute "PN" "8"
						( Origin gPackager )
					)
					( objectStatus "U8F2.8" )
				)
				( pin "gnd"
					( attribute "PN" "10"
						( Origin gPackager )
					)
					( objectStatus "U8F2.10" )
				)
				( pin "hold_n_io(3)"
					( attribute "PN" "1"
						( Origin gPackager )
					)
					( objectStatus "U8F2.1" )
				)
				( pin "nc(0)"
					( attribute "PN" "4"
						( Origin gPackager )
					)
					( objectStatus "U8F2.4" )
				)
				( pin "nc(1)"
					( attribute "PN" "5"
						( Origin gPackager )
					)
					( objectStatus "U8F2.5" )
				)
				( pin "nc(2)"
					( attribute "PN" "6"
						( Origin gPackager )
					)
					( objectStatus "U8F2.6" )
				)
				( pin "nc(3)"
					( attribute "PN" "11"
						( Origin gPackager )
					)
					( objectStatus "U8F2.11" )
				)
				( pin "nc(4)"
					( attribute "PN" "12"
						( Origin gPackager )
					)
					( objectStatus "U8F2.12" )
				)
				( pin "nc(5)"
					( attribute "PN" "13"
						( Origin gPackager )
					)
					( objectStatus "U8F2.13" )
				)
				( pin "nc(6)"
					( attribute "PN" "14"
						( Origin gPackager )
					)
					( objectStatus "U8F2.14" )
				)
				( pin "reset_n"
					( attribute "PN" "3"
						( Origin gPackager )
					)
					( objectStatus "U8F2.3" )
				)
				( pin "vcc"
					( attribute "PN" "2"
						( Origin gPackager )
					)
					( objectStatus "U8F2.2" )
				)
				( pin "wp_n_io(2)"
					( attribute "PN" "9"
						( Origin gPackager )
					)
					( objectStatus "U8F2.9" )
				)
			)
			( gate "@baseboard_fab2_lib.baseboard_fab2(sch_1):page163_i1"
				( attribute "CDS_LIB" "mstr_digital"
					( Origin gPackager )
				)
				( attribute "CDS_LOCATION" "U1B2"
					( Origin gPackager )
				)
				( attribute "CDS_SEC" "1"
					( Origin gPackager )
				)
				( attribute "LOCATION" "U1B2"
					( Origin gFrontEnd )
				)
				( attribute "MATERIAL" "IC"
					( Origin gFrontEnd )
				)
				( attribute "PACK_TYPE" "SM"
					( Origin gFrontEnd )
				)
				( attribute "PART_NUMBER" "G77073-001"
					( Origin gFrontEnd )
				)
				( attribute "PHYS_PAGE" "163"
					( Origin gFrontEnd )
				)
				( attribute "ROOM" "SMB_PE_HP_CPU1"
					( Origin gFrontEnd )
				)
				( attribute "ROT" "0"
					( Origin gFrontEnd )
				)
				( attribute "SEC" "1"
					( Origin gFrontEnd )
				)
				( attribute "SEC_TYPE" "SM"
					( Origin gFrontEnd )
				)
				( attribute "VER" "1"
					( Origin gFrontEnd )
				)
				( attribute "XY" "(-1600,3250)"
					( Origin gFrontEnd )
				)
				( attribute "CHIPS_PART_NAME" "PCA9517"
					( Origin gPackager )
				)
				( attribute "CDS_PART_NAME" "PCA9517_SM-IC,G77073-001"
					( Origin gPackager )
				)
				( objectStatus "U1B2" )
				( pin "en"
					( attribute "PN" "5"
						( Origin gPackager )
					)
					( objectStatus "U1B2.5" )
				)
				( pin "scla"
					( attribute "PN" "2"
						( Origin gPackager )
					)
					( objectStatus "U1B2.2" )
				)
				( pin "sclb"
					( attribute "PN" "7"
						( Origin gPackager )
					)
					( objectStatus "U1B2.7" )
				)
				( pin "sdaa"
					( attribute "PN" "3"
						( Origin gPackager )
					)
					( objectStatus "U1B2.3" )
				)
				( pin "sdab"
					( attribute "PN" "6"
						( Origin gPackager )
					)
					( objectStatus "U1B2.6" )
				)
				( pin "vcca"
					( attribute "PN" "1"
						( Origin gPackager )
					)
					( objectStatus "U1B2.1" )
				)
				( pin "vccb"
					( attribute "PN" "8"
						( Origin gPackager )
					)
					( objectStatus "U1B2.8" )
				)
			)
			( gate "@baseboard_fab2_lib.baseboard_fab2(sch_1):page163_i2"
				( attribute "CDS_LIB" "mstr_discrete"
					( Origin gPackager )
				)
				( attribute "CDS_LOCATION" "R6N8"
					( Origin gPackager )
				)
				( attribute "CDS_SEC" "1"
					( Origin gPackager )
				)
				( attribute "LOCATION" "R6N8"
					( Origin gFrontEnd )
				)
				( attribute "MATERIAL" "CHIP"
					( Origin gFrontEnd )
				)
				( attribute "PACK_TYPE" "0402"
					( Origin gFrontEnd )
				)
				( attribute "PART_NUMBER" "G21796-066"
					( Origin gFrontEnd )
				)
				( attribute "PHYS_PAGE" "163"
					( Origin gFrontEnd )
				)
				( attribute "ROOM" "CPU1"
					( Origin gFrontEnd )
				)
				( attribute "ROT" "0"
					( Origin gFrontEnd )
				)
				( attribute "SEC" "1"
					( Origin gFrontEnd )
				)
				( attribute "SEC_TYPE" "0402"
					( Origin gFrontEnd )
				)
				( attribute "TOLERANCE" "1%"
					( Origin gFrontEnd )
				)
				( attribute "VALUE" "10.0"
					( Origin gFrontEnd )
				)
				( attribute "VER" "1"
					( Origin gFrontEnd )
				)
				( attribute "WATTAGE" "1/16W"
					( Origin gFrontEnd )
				)
				( attribute "XY" "(-3950,3300)"
					( Origin gFrontEnd )
				)
				( attribute "CHIPS_PART_NAME" "RES"
					( Origin gPackager )
				)
				( attribute "CDS_PART_NAME" "RES_0402-10.0,1%,1/16W,CHIP,G2A"
					( Origin gPackager )
				)
				( objectStatus "R6N8" )
				( pin "a"
					( attribute "PN" "1"
						( Origin gPackager )
					)
					( objectStatus "R6N8.1" )
				)
				( pin "b"
					( attribute "PN" "2"
						( Origin gPackager )
					)
					( objectStatus "R6N8.2" )
				)
			)
			( gate "@baseboard_fab2_lib.baseboard_fab2(sch_1):page163_i3"
				( attribute "CDS_LIB" "mstr_discrete"
					( Origin gPackager )
				)
				( attribute "CDS_LOCATION" "R6N9"
					( Origin gPackager )
				)
				( attribute "CDS_SEC" "1"
					( Origin gPackager )
				)
				( attribute "LOCATION" "R6N9"
					( Origin gFrontEnd )
				)
				( attribute "MATERIAL" "CHIP"
					( Origin gFrontEnd )
				)
				( attribute "PACK_TYPE" "0402"
					( Origin gFrontEnd )
				)
				( attribute "PART_NUMBER" "G21796-066"
					( Origin gFrontEnd )
				)
				( attribute "PHYS_PAGE" "163"
					( Origin gFrontEnd )
				)
				( attribute "ROOM" "CPU1"
					( Origin gFrontEnd )
				)
				( attribute "ROT" "0"
					( Origin gFrontEnd )
				)
				( attribute "SEC" "1"
					( Origin gFrontEnd )
				)
				( attribute "SEC_TYPE" "0402"
					( Origin gFrontEnd )
				)
				( attribute "TOLERANCE" "1%"
					( Origin gFrontEnd )
				)
				( attribute "VALUE" "10.0"
					( Origin gFrontEnd )
				)
				( attribute "VER" "1"
					( Origin gFrontEnd )
				)
				( attribute "WATTAGE" "1/16W"
					( Origin gFrontEnd )
				)
				( attribute "XY" "(-3425,3250)"
					( Origin gFrontEnd )
				)
				( attribute "CHIPS_PART_NAME" "RES"
					( Origin gPackager )
				)
				( attribute "CDS_PART_NAME" "RES_0402-10.0,1%,1/16W,CHIP,G2A"
					( Origin gPackager )
				)
				( objectStatus "R6N9" )
				( pin "a"
					( attribute "PN" "1"
						( Origin gPackager )
					)
					( objectStatus "R6N9.1" )
				)
				( pin "b"
					( attribute "PN" "2"
						( Origin gPackager )
					)
					( objectStatus "R6N9.2" )
				)
			)
			( gate "@baseboard_fab2_lib.baseboard_fab2(sch_1):page163_i6"
				( attribute "CDS_LIB" "mstr_discrete"
					( Origin gPackager )
				)
				( attribute "CDS_LOCATION" "R9M18"
					( Origin gPackager )
				)
				( attribute "CDS_SEC" "1"
					( Origin gPackager )
				)
				( attribute "LOCATION" "R9M18"
					( Origin gFrontEnd )
				)
				( attribute "MATERIAL" "CHIP"
					( Origin gFrontEnd )
				)
				( attribute "PACK_TYPE" "0402"
					( Origin gFrontEnd )
				)
				( attribute "PART_NUMBER" "G21796-294"
					( Origin gFrontEnd )
				)
				( attribute "PHYS_PAGE" "163"
					( Origin gFrontEnd )
				)
				( attribute "ROOM" "SMB_PE_HP_CPU1"
					( Origin gFrontEnd )
				)
				( attribute "ROT" "0"
					( Origin gFrontEnd )
				)
				( attribute "SEC" "1"
					( Origin gFrontEnd )
				)
				( attribute "SEC_TYPE" "0402"
					( Origin gFrontEnd )
				)
				( attribute "TOLERANCE" "1.0%"
					( Origin gFrontEnd )
				)
				( attribute "VALUE" "240"
					( Origin gFrontEnd )
				)
				( attribute "VER" "2"
					( Origin gFrontEnd )
				)
				( attribute "WATTAGE" "1/16W"
					( Origin gFrontEnd )
				)
				( attribute "XY" "(-2350,3650)"
					( Origin gFrontEnd )
				)
				( attribute "CHIPS_PART_NAME" "RES"
					( Origin gPackager )
				)
				( attribute "CDS_PART_NAME" "RES_0402-240,1.0%,1/16W,CHIP,GA"
					( Origin gPackager )
				)
				( objectStatus "R9M18" )
				( pin "a"
					( attribute "PN" "1"
						( Origin gPackager )
					)
					( objectStatus "R9M18.1" )
				)
				( pin "b"
					( attribute "PN" "2"
						( Origin gPackager )
					)
					( objectStatus "R9M18.2" )
				)
			)
			( gate "@baseboard_fab2_lib.baseboard_fab2(sch_1):page163_i7"
				( attribute "CDS_LIB" "mstr_discrete"
					( Origin gPackager )
				)
				( attribute "CDS_LOCATION" "R9M19"
					( Origin gPackager )
				)
				( attribute "CDS_SEC" "1"
					( Origin gPackager )
				)
				( attribute "LOCATION" "R9M19"
					( Origin gFrontEnd )
				)
				( attribute "MATERIAL" "CHIP"
					( Origin gFrontEnd )
				)
				( attribute "PACK_TYPE" "0402"
					( Origin gFrontEnd )
				)
				( attribute "PART_NUMBER" "G21796-294"
					( Origin gFrontEnd )
				)
				( attribute "PHYS_PAGE" "163"
					( Origin gFrontEnd )
				)
				( attribute "ROOM" "SMB_PE_HP_CPU1"
					( Origin gFrontEnd )
				)
				( attribute "ROT" "2"
					( Origin gFrontEnd )
				)
				( attribute "SEC" "1"
					( Origin gFrontEnd )
				)
				( attribute "SEC_TYPE" "0402"
					( Origin gFrontEnd )
				)
				( attribute "TOLERANCE" "1.0%"
					( Origin gFrontEnd )
				)
				( attribute "VALUE" "240"
					( Origin gFrontEnd )
				)
				( attribute "VER" "2"
					( Origin gFrontEnd )
				)
				( attribute "WATTAGE" "1/16W"
					( Origin gFrontEnd )
				)
				( attribute "XY" "(-2475,3650)"
					( Origin gFrontEnd )
				)
				( attribute "CHIPS_PART_NAME" "RES"
					( Origin gPackager )
				)
				( attribute "CDS_PART_NAME" "RES_0402-240,1.0%,1/16W,CHIP,GA"
					( Origin gPackager )
				)
				( objectStatus "R9M19" )
				( pin "a"
					( attribute "PN" "1"
						( Origin gPackager )
					)
					( objectStatus "R9M19.1" )
				)
				( pin "b"
					( attribute "PN" "2"
						( Origin gPackager )
					)
					( objectStatus "R9M19.2" )
				)
			)
			( gate "@baseboard_fab2_lib.baseboard_fab2(sch_1):page163_i10"
				( attribute "CDS_LIB" "dev_discrete"
					( Origin gPackager )
				)
				( attribute "CDS_LOCATION" "C9M8"
					( Origin gPackager )
				)
				( attribute "CDS_SEC" "1"
					( Origin gPackager )
				)
				( attribute "LOCATION" "C9M8"
					( Origin gFrontEnd )
				)
				( attribute "MATERIAL" "X7R"
					( Origin gFrontEnd )
				)
				( attribute "PACK_TYPE" "0402V"
					( Origin gFrontEnd )
				)
				( attribute "PART_NUMBER" "A36096-030"
					( Origin gFrontEnd )
				)
				( attribute "PHYS_PAGE" "163"
					( Origin gFrontEnd )
				)
				( attribute "ROOM" "SMB_PE_HP_CPU1"
					( Origin gFrontEnd )
				)
				( attribute "ROT" "0"
					( Origin gFrontEnd )
				)
				( attribute "SEC" "1"
					( Origin gFrontEnd )
				)
				( attribute "SEC_TYPE" "0402V"
					( Origin gFrontEnd )
				)
				( attribute "TOLERANCE" "10%"
					( Origin gFrontEnd )
				)
				( attribute "VALUE" "0.1UF"
					( Origin gFrontEnd )
				)
				( attribute "VER" "1"
					( Origin gFrontEnd )
				)
				( attribute "VOLTAGE" "16V"
					( Units "uVoltage" "V" 1.000000)
					( Origin gFrontEnd )
				)
				( attribute "XY" "(-1950,3825)"
					( Origin gFrontEnd )
				)
				( attribute "CHIPS_PART_NAME" "CAP_A"
					( Origin gPackager )
				)
				( attribute "CDS_PART_NAME" "CAP_A_0402V-0.1UF,16V,10%,X7R,A"
					( Origin gPackager )
				)
				( objectStatus "C9M8" )
				( pin "a"
					( attribute "PN" "1"
						( Origin gPackager )
					)
					( objectStatus "C9M8.1" )
				)
				( pin "b"
					( attribute "PN" "2"
						( Origin gPackager )
					)
					( objectStatus "C9M8.2" )
				)
			)
			( gate "@baseboard_fab2_lib.baseboard_fab2(sch_1):page163_i12"
				( attribute "CDS_LIB" "dev_discrete"
					( Origin gPackager )
				)
				( attribute "CDS_LOCATION" "C9M7"
					( Origin gPackager )
				)
				( attribute "CDS_SEC" "1"
					( Origin gPackager )
				)
				( attribute "LOCATION" "C9M7"
					( Origin gFrontEnd )
				)
				( attribute "MATERIAL" "X7R"
					( Origin gFrontEnd )
				)
				( attribute "PACK_TYPE" "0402V"
					( Origin gFrontEnd )
				)
				( attribute "PART_NUMBER" "A36096-030"
					( Origin gFrontEnd )
				)
				( attribute "PHYS_PAGE" "163"
					( Origin gFrontEnd )
				)
				( attribute "ROOM" "SMB_PE_HP_CPU1"
					( Origin gFrontEnd )
				)
				( attribute "ROT" "2"
					( Origin gFrontEnd )
				)
				( attribute "SEC" "1"
					( Origin gFrontEnd )
				)
				( attribute "SEC_TYPE" "0402V"
					( Origin gFrontEnd )
				)
				( attribute "TOLERANCE" "10%"
					( Origin gFrontEnd )
				)
				( attribute "VALUE" "0.1UF"
					( Origin gFrontEnd )
				)
				( attribute "VER" "1"
					( Origin gFrontEnd )
				)
				( attribute "VOLTAGE" "16V"
					( Units "uVoltage" "V" 1.000000)
					( Origin gFrontEnd )
				)
				( attribute "XY" "(-1275,3825)"
					( Origin gFrontEnd )
				)
				( attribute "CHIPS_PART_NAME" "CAP_A"
					( Origin gPackager )
				)
				( attribute "CDS_PART_NAME" "CAP_A_0402V-0.1UF,16V,10%,X7R,A"
					( Origin gPackager )
				)
				( objectStatus "C9M7" )
				( pin "a"
					( attribute "PN" "1"
						( Origin gPackager )
					)
					( objectStatus "C9M7.1" )
				)
				( pin "b"
					( attribute "PN" "2"
						( Origin gPackager )
					)
					( objectStatus "C9M7.2" )
				)
			)
			( gate "@baseboard_fab2_lib.baseboard_fab2(sch_1):page163_i15"
				( attribute "CDS_LIB" "mstr_discrete"
					( Origin gPackager )
				)
				( attribute "CDS_LOCATION" "R9M17"
					( Origin gPackager )
				)
				( attribute "CDS_SEC" "1"
					( Origin gPackager )
				)
				( attribute "LOCATION" "R9M17"
					( Origin gFrontEnd )
				)
				( attribute "MATERIAL" "CHIP"
					( Origin gFrontEnd )
				)
				( attribute "PACK_TYPE" "0402"
					( Origin gFrontEnd )
				)
				( attribute "PART_NUMBER" "G21796-001"
					( Origin gFrontEnd )
				)
				( attribute "PHYS_PAGE" "163"
					( Origin gFrontEnd )
				)
				( attribute "ROOM" "SMB_PE_HP_CPU1"
					( Origin gFrontEnd )
				)
				( attribute "ROT" "2"
					( Origin gFrontEnd )
				)
				( attribute "SEC" "1"
					( Origin gFrontEnd )
				)
				( attribute "SEC_TYPE" "0402"
					( Origin gFrontEnd )
				)
				( attribute "TOLERANCE" "1%"
					( Origin gFrontEnd )
				)
				( attribute "VALUE" "2.0K"
					( Origin gFrontEnd )
				)
				( attribute "VER" "2"
					( Origin gFrontEnd )
				)
				( attribute "WATTAGE" "1/16W"
					( Origin gFrontEnd )
				)
				( attribute "XY" "(-750,3650)"
					( Origin gFrontEnd )
				)
				( attribute "CHIPS_PART_NAME" "RES"
					( Origin gPackager )
				)
				( attribute "CDS_PART_NAME" "RES_0402-2.0K,1%,1/16W,CHIP,G2A"
					( Origin gPackager )
				)
				( objectStatus "R9M17" )
				( pin "a"
					( attribute "PN" "1"
						( Origin gPackager )
					)
					( objectStatus "R9M17.1" )
				)
				( pin "b"
					( attribute "PN" "2"
						( Origin gPackager )
					)
					( objectStatus "R9M17.2" )
				)
			)
			( gate "@baseboard_fab2_lib.baseboard_fab2(sch_1):page163_i16"
				( attribute "CDS_LIB" "mstr_discrete"
					( Origin gPackager )
				)
				( attribute "CDS_LOCATION" "R9M16"
					( Origin gPackager )
				)
				( attribute "CDS_SEC" "1"
					( Origin gPackager )
				)
				( attribute "LOCATION" "R9M16"
					( Origin gFrontEnd )
				)
				( attribute "MATERIAL" "CHIP"
					( Origin gFrontEnd )
				)
				( attribute "PACK_TYPE" "0402"
					( Origin gFrontEnd )
				)
				( attribute "PART_NUMBER" "G21796-001"
					( Origin gFrontEnd )
				)
				( attribute "PHYS_PAGE" "163"
					( Origin gFrontEnd )
				)
				( attribute "ROOM" "SMB_PE_HP_CPU1"
					( Origin gFrontEnd )
				)
				( attribute "ROT" "0"
					( Origin gFrontEnd )
				)
				( attribute "SEC" "1"
					( Origin gFrontEnd )
				)
				( attribute "SEC_TYPE" "0402"
					( Origin gFrontEnd )
				)
				( attribute "TOLERANCE" "1%"
					( Origin gFrontEnd )
				)
				( attribute "VALUE" "2.0K"
					( Origin gFrontEnd )
				)
				( attribute "VER" "2"
					( Origin gFrontEnd )
				)
				( attribute "WATTAGE" "1/16W"
					( Origin gFrontEnd )
				)
				( attribute "XY" "(-600,3650)"
					( Origin gFrontEnd )
				)
				( attribute "CHIPS_PART_NAME" "RES"
					( Origin gPackager )
				)
				( attribute "CDS_PART_NAME" "RES_0402-2.0K,1%,1/16W,CHIP,G2A"
					( Origin gPackager )
				)
				( objectStatus "R9M16" )
				( pin "a"
					( attribute "PN" "1"
						( Origin gPackager )
					)
					( objectStatus "R9M16.1" )
				)
				( pin "b"
					( attribute "PN" "2"
						( Origin gPackager )
					)
					( objectStatus "R9M16.2" )
				)
			)
			( gate "@baseboard_fab2_lib.baseboard_fab2(sch_1):page163_i20"
				( attribute "CDS_LIB" "mstr_discrete"
					( Origin gPackager )
				)
				( attribute "CDS_LOCATION" "R9M14"
					( Origin gPackager )
				)
				( attribute "CDS_SEC" "1"
					( Origin gPackager )
				)
				( attribute "LOCATION" "R9M14"
					( Origin gFrontEnd )
				)
				( attribute "MATERIAL" "CHIP"
					( Origin gFrontEnd )
				)
				( attribute "PACK_TYPE" "0402"
					( Origin gFrontEnd )
				)
				( attribute "PART_NUMBER" "G21796-173"
					( Origin gFrontEnd )
				)
				( attribute "PHYS_PAGE" "163"
					( Origin gFrontEnd )
				)
				( attribute "ROOM" "SMB_PE_HP_CPU1"
					( Origin gFrontEnd )
				)
				( attribute "ROT" "0"
					( Origin gFrontEnd )
				)
				( attribute "SEC" "1"
					( Origin gPackager )
				)
				( attribute "TOLERANCE" "1%"
					( Origin gFrontEnd )
				)
				( attribute "VALUE" "20.0"
					( Origin gFrontEnd )
				)
				( attribute "VER" "1"
					( Origin gFrontEnd )
				)
				( attribute "WATTAGE" "1/16W"
					( Origin gFrontEnd )
				)
				( attribute "XY" "(-200,3300)"
					( Origin gFrontEnd )
				)
				( attribute "CHIPS_PART_NAME" "RES"
					( Origin gPackager )
				)
				( attribute "CDS_PART_NAME" "RES_0402-20.0,1%,1/16W,CHIP,G2A"
					( Origin gPackager )
				)
				( objectStatus "R9M14" )
				( pin "a"
					( attribute "PN" "1"
						( Origin gPackager )
					)
					( objectStatus "R9M14.1" )
				)
				( pin "b"
					( attribute "PN" "2"
						( Origin gPackager )
					)
					( objectStatus "R9M14.2" )
				)
			)
			( gate "@baseboard_fab2_lib.baseboard_fab2(sch_1):page163_i21"
				( attribute "CDS_LIB" "mstr_discrete"
					( Origin gPackager )
				)
				( attribute "CDS_LOCATION" "R9M13"
					( Origin gPackager )
				)
				( attribute "CDS_SEC" "1"
					( Origin gPackager )
				)
				( attribute "LOCATION" "R9M13"
					( Origin gFrontEnd )
				)
				( attribute "MATERIAL" "CHIP"
					( Origin gFrontEnd )
				)
				( attribute "PACK_TYPE" "0402"
					( Origin gFrontEnd )
				)
				( attribute "PART_NUMBER" "G21796-173"
					( Origin gFrontEnd )
				)
				( attribute "PHYS_PAGE" "163"
					( Origin gFrontEnd )
				)
				( attribute "ROOM" "SMB_PE_HP_CPU1"
					( Origin gFrontEnd )
				)
				( attribute "ROT" "0"
					( Origin gFrontEnd )
				)
				( attribute "SEC" "1"
					( Origin gPackager )
				)
				( attribute "TOLERANCE" "1%"
					( Origin gFrontEnd )
				)
				( attribute "VALUE" "20.0"
					( Origin gFrontEnd )
				)
				( attribute "VER" "1"
					( Origin gFrontEnd )
				)
				( attribute "WATTAGE" "1/16W"
					( Origin gFrontEnd )
				)
				( attribute "XY" "(50,3250)"
					( Origin gFrontEnd )
				)
				( attribute "CHIPS_PART_NAME" "RES"
					( Origin gPackager )
				)
				( attribute "CDS_PART_NAME" "RES_0402-20.0,1%,1/16W,CHIP,G2A"
					( Origin gPackager )
				)
				( objectStatus "R9M13" )
				( pin "a"
					( attribute "PN" "1"
						( Origin gPackager )
					)
					( objectStatus "R9M13.1" )
				)
				( pin "b"
					( attribute "PN" "2"
						( Origin gPackager )
					)
					( objectStatus "R9M13.2" )
				)
			)
			( gate "@baseboard_fab2_lib.baseboard_fab2(sch_1):page163_i24"
				( attribute "CDS_LIB" "mstr_discrete"
					( Origin gPackager )
				)
				( attribute "CDS_LOCATION" "R9M12"
					( Origin gPackager )
				)
				( attribute "CDS_SEC" "1"
					( Origin gPackager )
				)
				( attribute "LOCATION" "R9M12"
					( Origin gFrontEnd )
				)
				( attribute "MATERIAL" "CHIP"
					( Origin gFrontEnd )
				)
				( attribute "PACK_TYPE" "0402"
					( Origin gFrontEnd )
				)
				( attribute "PART_NUMBER" "G21796-173"
					( Origin gFrontEnd )
				)
				( attribute "PHYS_PAGE" "163"
					( Origin gFrontEnd )
				)
				( attribute "ROOM" "SMB_PE_HP_CPU1"
					( Origin gFrontEnd )
				)
				( attribute "ROT" "0"
					( Origin gFrontEnd )
				)
				( attribute "SEC" "1"
					( Origin gPackager )
				)
				( attribute "TOLERANCE" "1%"
					( Origin gFrontEnd )
				)
				( attribute "VALUE" "20.0"
					( Origin gFrontEnd )
				)
				( attribute "VER" "1"
					( Origin gFrontEnd )
				)
				( attribute "WATTAGE" "1/16W"
					( Origin gFrontEnd )
				)
				( attribute "XY" "(100,2825)"
					( Origin gFrontEnd )
				)
				( attribute "CHIPS_PART_NAME" "RES"
					( Origin gPackager )
				)
				( attribute "CDS_PART_NAME" "RES_0402-20.0,1%,1/16W,CHIP,G2A"
					( Origin gPackager )
				)
				( objectStatus "R9M12" )
				( pin "a"
					( attribute "PN" "1"
						( Origin gPackager )
					)
					( objectStatus "R9M12.1" )
				)
				( pin "b"
					( attribute "PN" "2"
						( Origin gPackager )
					)
					( objectStatus "R9M12.2" )
				)
			)
			( gate "@baseboard_fab2_lib.baseboard_fab2(sch_1):page163_i25"
				( attribute "CDS_LIB" "mstr_discrete"
					( Origin gPackager )
				)
				( attribute "CDS_LOCATION" "R9M15"
					( Origin gPackager )
				)
				( attribute "CDS_SEC" "1"
					( Origin gPackager )
				)
				( attribute "LOCATION" "R9M15"
					( Origin gFrontEnd )
				)
				( attribute "MATERIAL" "CHIP"
					( Origin gFrontEnd )
				)
				( attribute "PACK_TYPE" "0402"
					( Origin gFrontEnd )
				)
				( attribute "PART_NUMBER" "G21796-173"
					( Origin gFrontEnd )
				)
				( attribute "PHYS_PAGE" "163"
					( Origin gFrontEnd )
				)
				( attribute "ROOM" "SMB_PE_HP_CPU1"
					( Origin gFrontEnd )
				)
				( attribute "ROT" "0"
					( Origin gFrontEnd )
				)
				( attribute "SEC" "1"
					( Origin gPackager )
				)
				( attribute "TOLERANCE" "1%"
					( Origin gFrontEnd )
				)
				( attribute "VALUE" "20.0"
					( Origin gFrontEnd )
				)
				( attribute "VER" "1"
					( Origin gFrontEnd )
				)
				( attribute "WATTAGE" "1/16W"
					( Origin gFrontEnd )
				)
				( attribute "XY" "(-150,2875)"
					( Origin gFrontEnd )
				)
				( attribute "CHIPS_PART_NAME" "RES"
					( Origin gPackager )
				)
				( attribute "CDS_PART_NAME" "RES_0402-20.0,1%,1/16W,CHIP,G2A"
					( Origin gPackager )
				)
				( objectStatus "R9M15" )
				( pin "a"
					( attribute "PN" "1"
						( Origin gPackager )
					)
					( objectStatus "R9M15.1" )
				)
				( pin "b"
					( attribute "PN" "2"
						( Origin gPackager )
					)
					( objectStatus "R9M15.2" )
				)
			)
			( gate "@baseboard_fab2_lib.baseboard_fab2(sch_1):page164_i5"
				( attribute "BOM_COST" "SM_CONTROLLER"
					( Origin gFrontEnd )
				)
				( attribute "CDS_LIB" "mstr_discrete"
					( Origin gPackager )
				)
				( attribute "CDS_LOCATION" "R1T10"
					( Origin gPackager )
				)
				( attribute "CDS_SEC" "1"
					( Origin gPackager )
				)
				( attribute "LOCATION" "R1T10"
					( Origin gFrontEnd )
				)
				( attribute "MATERIAL" "EMPTY"
					( Origin gFrontEnd )
				)
				( attribute "PACK_TYPE" "0402"
					( Origin gFrontEnd )
				)
				( attribute "PART_NUMBER" "G21796-026"
					( Origin gFrontEnd )
				)
				( attribute "PHYS_PAGE" "164"
					( Origin gFrontEnd )
				)
				( attribute "ROOM" "BMC_MISC"
					( Origin gFrontEnd )
				)
				( attribute "ROT" "0"
					( Origin gFrontEnd )
				)
				( attribute "SEC" "1"
					( Origin gFrontEnd )
				)
				( attribute "SEC_TYPE" "0402"
					( Origin gFrontEnd )
				)
				( attribute "TOLERANCE" "1%"
					( Origin gFrontEnd )
				)
				( attribute "VALUE" "1.00K"
					( Origin gFrontEnd )
				)
				( attribute "VER" "2"
					( Origin gFrontEnd )
				)
				( attribute "WATTAGE" "1/16W"
					( Origin gFrontEnd )
				)
				( attribute "XY" "(-5975,775)"
					( Origin gFrontEnd )
				)
				( attribute "CHIPS_PART_NAME" "RES"
					( Origin gPackager )
				)
				( attribute "CDS_PART_NAME" "RES_0402-1.00K,1%,1/16W,EMPTY,A"
					( Origin gPackager )
				)
				( objectStatus "R1T10" )
				( pin "a"
					( attribute "PN" "1"
						( Origin gPackager )
					)
					( objectStatus "R1T10.1" )
				)
				( pin "b"
					( attribute "PN" "2"
						( Origin gPackager )
					)
					( objectStatus "R1T10.2" )
				)
			)
			( gate "@baseboard_fab2_lib.baseboard_fab2(sch_1):page164_i6"
				( attribute "BOM_COST" "SM_CONTROLLER"
					( Origin gFrontEnd )
				)
				( attribute "CDS_LIB" "mstr_discrete"
					( Origin gPackager )
				)
				( attribute "CDS_LOCATION" "R1T12"
					( Origin gPackager )
				)
				( attribute "CDS_SEC" "1"
					( Origin gPackager )
				)
				( attribute "LOCATION" "R1T12"
					( Origin gFrontEnd )
				)
				( attribute "MATERIAL" "CHIP"
					( Origin gFrontEnd )
				)
				( attribute "PACK_TYPE" "0402"
					( Origin gFrontEnd )
				)
				( attribute "PART_NUMBER" "G21796-026"
					( Origin gFrontEnd )
				)
				( attribute "PHYS_PAGE" "164"
					( Origin gFrontEnd )
				)
				( attribute "ROOM" "BMC_MISC"
					( Origin gFrontEnd )
				)
				( attribute "ROT" "0"
					( Origin gFrontEnd )
				)
				( attribute "SEC" "1"
					( Origin gFrontEnd )
				)
				( attribute "SEC_TYPE" "0402"
					( Origin gFrontEnd )
				)
				( attribute "TOLERANCE" "1%"
					( Origin gFrontEnd )
				)
				( attribute "VALUE" "1.00K"
					( Origin gFrontEnd )
				)
				( attribute "VER" "2"
					( Origin gFrontEnd )
				)
				( attribute "WATTAGE" "1/16W"
					( Origin gFrontEnd )
				)
				( attribute "XY" "(-6225,775)"
					( Origin gFrontEnd )
				)
				( attribute "CHIPS_PART_NAME" "RES"
					( Origin gPackager )
				)
				( attribute "CDS_PART_NAME" "RES_0402-1.00K,1%,1/16W,CHIP,GA"
					( Origin gPackager )
				)
				( objectStatus "R1T12" )
				( pin "a"
					( attribute "PN" "1"
						( Origin gPackager )
					)
					( objectStatus "R1T12.1" )
				)
				( pin "b"
					( attribute "PN" "2"
						( Origin gPackager )
					)
					( objectStatus "R1T12.2" )
				)
			)
			( gate "@baseboard_fab2_lib.baseboard_fab2(sch_1):page164_i7"
				( attribute "BOM_COST" "SM_CONTROLLER"
					( Origin gFrontEnd )
				)
				( attribute "CDS_LIB" "mstr_discrete"
					( Origin gPackager )
				)
				( attribute "CDS_LOCATION" "R1T11"
					( Origin gPackager )
				)
				( attribute "CDS_SEC" "1"
					( Origin gPackager )
				)
				( attribute "LOCATION" "R1T11"
					( Origin gFrontEnd )
				)
				( attribute "MATERIAL" "CHIP"
					( Origin gFrontEnd )
				)
				( attribute "PACK_TYPE" "0402"
					( Origin gFrontEnd )
				)
				( attribute "PART_NUMBER" "G21796-026"
					( Origin gFrontEnd )
				)
				( attribute "PHYS_PAGE" "164"
					( Origin gFrontEnd )
				)
				( attribute "ROOM" "BMC_MISC"
					( Origin gFrontEnd )
				)
				( attribute "ROT" "0"
					( Origin gFrontEnd )
				)
				( attribute "SEC" "1"
					( Origin gFrontEnd )
				)
				( attribute "SEC_TYPE" "0402"
					( Origin gFrontEnd )
				)
				( attribute "TOLERANCE" "1%"
					( Origin gFrontEnd )
				)
				( attribute "VALUE" "1.00K"
					( Origin gFrontEnd )
				)
				( attribute "VER" "2"
					( Origin gFrontEnd )
				)
				( attribute "WATTAGE" "1/16W"
					( Origin gFrontEnd )
				)
				( attribute "XY" "(-6475,775)"
					( Origin gFrontEnd )
				)
				( attribute "CHIPS_PART_NAME" "RES"
					( Origin gPackager )
				)
				( attribute "CDS_PART_NAME" "RES_0402-1.00K,1%,1/16W,CHIP,GA"
					( Origin gPackager )
				)
				( objectStatus "R1T11" )
				( pin "a"
					( attribute "PN" "1"
						( Origin gPackager )
					)
					( objectStatus "R1T11.1" )
				)
				( pin "b"
					( attribute "PN" "2"
						( Origin gPackager )
					)
					( objectStatus "R1T11.2" )
				)
			)
			( gate "@baseboard_fab2_lib.baseboard_fab2(sch_1):page164_i11"
				( attribute "BOM_COST" "SM_CONTROLLER"
					( Origin gFrontEnd )
				)
				( attribute "CDS_LIB" "mstr_discrete"
					( Origin gPackager )
				)
				( attribute "CDS_LOCATION" "R1T5"
					( Origin gPackager )
				)
				( attribute "CDS_SEC" "1"
					( Origin gPackager )
				)
				( attribute "LOCATION" "R1T5"
					( Origin gFrontEnd )
				)
				( attribute "MATERIAL" "EMPTY"
					( Origin gFrontEnd )
				)
				( attribute "PACK_TYPE" "0402"
					( Origin gFrontEnd )
				)
				( attribute "PART_NUMBER" "G21796-344"
					( Origin gFrontEnd )
				)
				( attribute "PHYS_PAGE" "164"
					( Origin gFrontEnd )
				)
				( attribute "ROOM" "BMC_MISC"
					( Origin gFrontEnd )
				)
				( attribute "ROT" "0"
					( Origin gFrontEnd )
				)
				( attribute "SEC" "1"
					( Origin gFrontEnd )
				)
				( attribute "SEC_TYPE" "0402"
					( Origin gFrontEnd )
				)
				( attribute "TOLERANCE" "1%"
					( Origin gFrontEnd )
				)
				( attribute "VALUE" "2.7K"
					( Origin gFrontEnd )
				)
				( attribute "VER" "1"
					( Origin gFrontEnd )
				)
				( attribute "WATTAGE" "1/16W"
					( Origin gFrontEnd )
				)
				( attribute "XY" "(-7025,1450)"
					( Origin gFrontEnd )
				)
				( attribute "CHIPS_PART_NAME" "RES"
					( Origin gPackager )
				)
				( attribute "CDS_PART_NAME" "RES_0402-2.7K,1%,1/16W,EMPTY,GA"
					( Origin gPackager )
				)
				( objectStatus "R1T5" )
				( pin "a"
					( attribute "PN" "1"
						( Origin gPackager )
					)
					( objectStatus "R1T5.1" )
				)
				( pin "b"
					( attribute "PN" "2"
						( Origin gPackager )
					)
					( objectStatus "R1T5.2" )
				)
			)
			( gate "@baseboard_fab2_lib.baseboard_fab2(sch_1):page164_i13"
				( attribute "BOM_COST" "SM_CONTROLLER"
					( Origin gFrontEnd )
				)
				( attribute "CDS_LIB" "mstr_discrete"
					( Origin gPackager )
				)
				( attribute "CDS_LOCATION" "R1T6"
					( Origin gPackager )
				)
				( attribute "CDS_SEC" "1"
					( Origin gPackager )
				)
				( attribute "LOCATION" "R1T6"
					( Origin gFrontEnd )
				)
				( attribute "MATERIAL" "EMPTY"
					( Origin gFrontEnd )
				)
				( attribute "PACK_TYPE" "0402"
					( Origin gFrontEnd )
				)
				( attribute "PART_NUMBER" "G21796-344"
					( Origin gFrontEnd )
				)
				( attribute "PHYS_PAGE" "164"
					( Origin gFrontEnd )
				)
				( attribute "ROOM" "BMC_MISC"
					( Origin gFrontEnd )
				)
				( attribute "ROT" "0"
					( Origin gFrontEnd )
				)
				( attribute "SEC" "1"
					( Origin gFrontEnd )
				)
				( attribute "SEC_TYPE" "0402"
					( Origin gFrontEnd )
				)
				( attribute "TOLERANCE" "1%"
					( Origin gFrontEnd )
				)
				( attribute "VALUE" "2.7K"
					( Origin gFrontEnd )
				)
				( attribute "VER" "1"
					( Origin gFrontEnd )
				)
				( attribute "WATTAGE" "1/16W"
					( Origin gFrontEnd )
				)
				( attribute "XY" "(-7025,1250)"
					( Origin gFrontEnd )
				)
				( attribute "CHIPS_PART_NAME" "RES"
					( Origin gPackager )
				)
				( attribute "CDS_PART_NAME" "RES_0402-2.7K,1%,1/16W,EMPTY,GA"
					( Origin gPackager )
				)
				( objectStatus "R1T6" )
				( pin "a"
					( attribute "PN" "1"
						( Origin gPackager )
					)
					( objectStatus "R1T6.1" )
				)
				( pin "b"
					( attribute "PN" "2"
						( Origin gPackager )
					)
					( objectStatus "R1T6.2" )
				)
			)
			( gate "@baseboard_fab2_lib.baseboard_fab2(sch_1):page164_i14"
				( attribute "BOM_COST" "SM_CONTROLLER"
					( Origin gFrontEnd )
				)
				( attribute "CDS_LIB" "mstr_discrete"
					( Origin gPackager )
				)
				( attribute "CDS_LOCATION" "R1T4"
					( Origin gPackager )
				)
				( attribute "CDS_SEC" "1"
					( Origin gPackager )
				)
				( attribute "LOCATION" "R1T4"
					( Origin gFrontEnd )
				)
				( attribute "MATERIAL" "CHIP"
					( Origin gFrontEnd )
				)
				( attribute "PACK_TYPE" "0402"
					( Origin gFrontEnd )
				)
				( attribute "PART_NUMBER" "G21796-344"
					( Origin gFrontEnd )
				)
				( attribute "PHYS_PAGE" "164"
					( Origin gFrontEnd )
				)
				( attribute "ROOM" "BMC_MISC"
					( Origin gFrontEnd )
				)
				( attribute "ROT" "0"
					( Origin gFrontEnd )
				)
				( attribute "SEC" "1"
					( Origin gFrontEnd )
				)
				( attribute "SEC_TYPE" "0402"
					( Origin gFrontEnd )
				)
				( attribute "TOLERANCE" "1%"
					( Origin gFrontEnd )
				)
				( attribute "VALUE" "2.7K"
					( Origin gFrontEnd )
				)
				( attribute "VER" "1"
					( Origin gFrontEnd )
				)
				( attribute "WATTAGE" "1/16W"
					( Origin gFrontEnd )
				)
				( attribute "XY" "(-7025,1050)"
					( Origin gFrontEnd )
				)
				( attribute "CHIPS_PART_NAME" "RES"
					( Origin gPackager )
				)
				( attribute "CDS_PART_NAME" "RES_0402-2.7K,1%,1/16W,CHIP,G2A"
					( Origin gPackager )
				)
				( objectStatus "R1T4" )
				( pin "a"
					( attribute "PN" "1"
						( Origin gPackager )
					)
					( objectStatus "R1T4.1" )
				)
				( pin "b"
					( attribute "PN" "2"
						( Origin gPackager )
					)
					( objectStatus "R1T4.2" )
				)
			)
			( gate "@baseboard_fab2_lib.baseboard_fab2(sch_1):page164_i19"
				( attribute "BOM_COST" "SM_CONTROLLER"
					( Origin gFrontEnd )
				)
				( attribute "CDS_LIB" "mstr_discrete"
					( Origin gPackager )
				)
				( attribute "CDS_LOCATION" "R1U18"
					( Origin gPackager )
				)
				( attribute "CDS_SEC" "1"
					( Origin gPackager )
				)
				( attribute "LOCATION" "R1U18"
					( Origin gFrontEnd )
				)
				( attribute "MATERIAL" "CHIP"
					( Origin gFrontEnd )
				)
				( attribute "PACK_TYPE" "0402"
					( Origin gFrontEnd )
				)
				( attribute "PART_NUMBER" "G21796-026"
					( Origin gFrontEnd )
				)
				( attribute "PHYS_PAGE" "164"
					( Origin gFrontEnd )
				)
				( attribute "ROOM" "BMC_MISC"
					( Origin gFrontEnd )
				)
				( attribute "ROT" "0"
					( Origin gFrontEnd )
				)
				( attribute "SEC" "1"
					( Origin gFrontEnd )
				)
				( attribute "SEC_TYPE" "0402"
					( Origin gFrontEnd )
				)
				( attribute "TOLERANCE" "1%"
					( Origin gFrontEnd )
				)
				( attribute "VALUE" "1.00K"
					( Origin gFrontEnd )
				)
				( attribute "VER" "2"
					( Origin gFrontEnd )
				)
				( attribute "WATTAGE" "1/16W"
					( Origin gFrontEnd )
				)
				( attribute "XY" "(-5475,2150)"
					( Origin gFrontEnd )
				)
				( attribute "CHIPS_PART_NAME" "RES"
					( Origin gPackager )
				)
				( attribute "CDS_PART_NAME" "RES_0402-1.00K,1%,1/16W,CHIP,GA"
					( Origin gPackager )
				)
				( objectStatus "R1U18" )
				( pin "a"
					( attribute "PN" "1"
						( Origin gPackager )
					)
					( objectStatus "R1U18.1" )
				)
				( pin "b"
					( attribute "PN" "2"
						( Origin gPackager )
					)
					( objectStatus "R1U18.2" )
				)
			)
			( gate "@baseboard_fab2_lib.baseboard_fab2(sch_1):page164_i20"
				( attribute "BOM_COST" "SM_CONTROLLER"
					( Origin gFrontEnd )
				)
				( attribute "CDS_LIB" "mstr_discrete"
					( Origin gPackager )
				)
				( attribute "CDS_LOCATION" "R1U16"
					( Origin gPackager )
				)
				( attribute "CDS_SEC" "1"
					( Origin gPackager )
				)
				( attribute "LOCATION" "R1U16"
					( Origin gFrontEnd )
				)
				( attribute "MATERIAL" "EMPTY"
					( Origin gFrontEnd )
				)
				( attribute "PACK_TYPE" "0402"
					( Origin gFrontEnd )
				)
				( attribute "PART_NUMBER" "G21796-026"
					( Origin gFrontEnd )
				)
				( attribute "PHYS_PAGE" "164"
					( Origin gFrontEnd )
				)
				( attribute "ROOM" "BMC_MISC"
					( Origin gFrontEnd )
				)
				( attribute "ROT" "0"
					( Origin gFrontEnd )
				)
				( attribute "SEC" "1"
					( Origin gFrontEnd )
				)
				( attribute "SEC_TYPE" "0402"
					( Origin gFrontEnd )
				)
				( attribute "TOLERANCE" "1%"
					( Origin gFrontEnd )
				)
				( attribute "VALUE" "1.00K"
					( Origin gFrontEnd )
				)
				( attribute "VER" "2"
					( Origin gFrontEnd )
				)
				( attribute "WATTAGE" "1/16W"
					( Origin gFrontEnd )
				)
				( attribute "XY" "(-5725,2150)"
					( Origin gFrontEnd )
				)
				( attribute "CHIPS_PART_NAME" "RES"
					( Origin gPackager )
				)
				( attribute "CDS_PART_NAME" "RES_0402-1.00K,1%,1/16W,EMPTY,A"
					( Origin gPackager )
				)
				( objectStatus "R1U16" )
				( pin "a"
					( attribute "PN" "1"
						( Origin gPackager )
					)
					( objectStatus "R1U16.1" )
				)
				( pin "b"
					( attribute "PN" "2"
						( Origin gPackager )
					)
					( objectStatus "R1U16.2" )
				)
			)
			( gate "@baseboard_fab2_lib.baseboard_fab2(sch_1):page164_i21"
				( attribute "BOM_COST" "SM_CONTROLLER"
					( Origin gFrontEnd )
				)
				( attribute "CDS_LIB" "mstr_discrete"
					( Origin gPackager )
				)
				( attribute "CDS_LOCATION" "R1U17"
					( Origin gPackager )
				)
				( attribute "CDS_SEC" "1"
					( Origin gPackager )
				)
				( attribute "LOCATION" "R1U17"
					( Origin gFrontEnd )
				)
				( attribute "MATERIAL" "CHIP"
					( Origin gFrontEnd )
				)
				( attribute "PACK_TYPE" "0402"
					( Origin gFrontEnd )
				)
				( attribute "PART_NUMBER" "G21796-026"
					( Origin gFrontEnd )
				)
				( attribute "PHYS_PAGE" "164"
					( Origin gFrontEnd )
				)
				( attribute "ROOM" "BMC_MISC"
					( Origin gFrontEnd )
				)
				( attribute "ROT" "0"
					( Origin gFrontEnd )
				)
				( attribute "SEC" "1"
					( Origin gFrontEnd )
				)
				( attribute "SEC_TYPE" "0402"
					( Origin gFrontEnd )
				)
				( attribute "TOLERANCE" "1%"
					( Origin gFrontEnd )
				)
				( attribute "VALUE" "1.00K"
					( Origin gFrontEnd )
				)
				( attribute "VER" "2"
					( Origin gFrontEnd )
				)
				( attribute "WATTAGE" "1/16W"
					( Origin gFrontEnd )
				)
				( attribute "XY" "(-5975,2150)"
					( Origin gFrontEnd )
				)
				( attribute "CHIPS_PART_NAME" "RES"
					( Origin gPackager )
				)
				( attribute "CDS_PART_NAME" "RES_0402-1.00K,1%,1/16W,CHIP,GA"
					( Origin gPackager )
				)
				( objectStatus "R1U17" )
				( pin "a"
					( attribute "PN" "1"
						( Origin gPackager )
					)
					( objectStatus "R1U17.1" )
				)
				( pin "b"
					( attribute "PN" "2"
						( Origin gPackager )
					)
					( objectStatus "R1U17.2" )
				)
			)
			( gate "@baseboard_fab2_lib.baseboard_fab2(sch_1):page164_i22"
				( attribute "BOM_COST" "SM_CONTROLLER"
					( Origin gFrontEnd )
				)
				( attribute "CDS_LIB" "mstr_discrete"
					( Origin gPackager )
				)
				( attribute "CDS_LOCATION" "R1U15"
					( Origin gPackager )
				)
				( attribute "CDS_SEC" "1"
					( Origin gPackager )
				)
				( attribute "LOCATION" "R1U15"
					( Origin gFrontEnd )
				)
				( attribute "MATERIAL" "EMPTY"
					( Origin gFrontEnd )
				)
				( attribute "PACK_TYPE" "0402"
					( Origin gFrontEnd )
				)
				( attribute "PART_NUMBER" "G21796-026"
					( Origin gFrontEnd )
				)
				( attribute "PHYS_PAGE" "164"
					( Origin gFrontEnd )
				)
				( attribute "ROOM" "BMC_MISC"
					( Origin gFrontEnd )
				)
				( attribute "ROT" "0"
					( Origin gFrontEnd )
				)
				( attribute "SEC" "1"
					( Origin gFrontEnd )
				)
				( attribute "SEC_TYPE" "0402"
					( Origin gFrontEnd )
				)
				( attribute "TOLERANCE" "1%"
					( Origin gFrontEnd )
				)
				( attribute "VALUE" "1.00K"
					( Origin gFrontEnd )
				)
				( attribute "VER" "2"
					( Origin gFrontEnd )
				)
				( attribute "WATTAGE" "1/16W"
					( Origin gFrontEnd )
				)
				( attribute "XY" "(-6225,2150)"
					( Origin gFrontEnd )
				)
				( attribute "CHIPS_PART_NAME" "RES"
					( Origin gPackager )
				)
				( attribute "CDS_PART_NAME" "RES_0402-1.00K,1%,1/16W,EMPTY,A"
					( Origin gPackager )
				)
				( objectStatus "R1U15" )
				( pin "a"
					( attribute "PN" "1"
						( Origin gPackager )
					)
					( objectStatus "R1U15.1" )
				)
				( pin "b"
					( attribute "PN" "2"
						( Origin gPackager )
					)
					( objectStatus "R1U15.2" )
				)
			)
			( gate "@baseboard_fab2_lib.baseboard_fab2(sch_1):page164_i24"
				( attribute "BOM_COST" "SM_CONTROLLER"
					( Origin gFrontEnd )
				)
				( attribute "CDS_LIB" "mstr_discrete"
					( Origin gPackager )
				)
				( attribute "CDS_LOCATION" "R1U21"
					( Origin gPackager )
				)
				( attribute "CDS_SEC" "1"
					( Origin gPackager )
				)
				( attribute "LOCATION" "R1U21"
					( Origin gFrontEnd )
				)
				( attribute "MATERIAL" "CHIP"
					( Origin gFrontEnd )
				)
				( attribute "PACK_TYPE" "0402"
					( Origin gFrontEnd )
				)
				( attribute "PART_NUMBER" "G21796-344"
					( Origin gFrontEnd )
				)
				( attribute "PHYS_PAGE" "164"
					( Origin gFrontEnd )
				)
				( attribute "ROOM" "BMC_MISC"
					( Origin gFrontEnd )
				)
				( attribute "ROT" "0"
					( Origin gFrontEnd )
				)
				( attribute "SEC" "1"
					( Origin gFrontEnd )
				)
				( attribute "SEC_TYPE" "0402"
					( Origin gFrontEnd )
				)
				( attribute "TOLERANCE" "1%"
					( Origin gFrontEnd )
				)
				( attribute "VALUE" "2.7K"
					( Origin gFrontEnd )
				)
				( attribute "VER" "1"
					( Origin gFrontEnd )
				)
				( attribute "WATTAGE" "1/16W"
					( Origin gFrontEnd )
				)
				( attribute "XY" "(-7025,3075)"
					( Origin gFrontEnd )
				)
				( attribute "CHIPS_PART_NAME" "RES"
					( Origin gPackager )
				)
				( attribute "CDS_PART_NAME" "RES_0402-2.7K,1%,1/16W,CHIP,G2A"
					( Origin gPackager )
				)
				( objectStatus "R1U21" )
				( pin "a"
					( attribute "PN" "1"
						( Origin gPackager )
					)
					( objectStatus "R1U21.1" )
				)
				( pin "b"
					( attribute "PN" "2"
						( Origin gPackager )
					)
					( objectStatus "R1U21.2" )
				)
			)
			( gate "@baseboard_fab2_lib.baseboard_fab2(sch_1):page164_i25"
				( attribute "BOM_COST" "SM_CONTROLLER"
					( Origin gFrontEnd )
				)
				( attribute "CDS_LIB" "mstr_discrete"
					( Origin gPackager )
				)
				( attribute "CDS_LOCATION" "R1U24"
					( Origin gPackager )
				)
				( attribute "CDS_SEC" "1"
					( Origin gPackager )
				)
				( attribute "LOCATION" "R1U24"
					( Origin gFrontEnd )
				)
				( attribute "MATERIAL" "EMPTY"
					( Origin gFrontEnd )
				)
				( attribute "PACK_TYPE" "0402"
					( Origin gFrontEnd )
				)
				( attribute "PART_NUMBER" "G21796-344"
					( Origin gFrontEnd )
				)
				( attribute "PHYS_PAGE" "164"
					( Origin gFrontEnd )
				)
				( attribute "ROOM" "BMC_MISC"
					( Origin gFrontEnd )
				)
				( attribute "ROT" "0"
					( Origin gFrontEnd )
				)
				( attribute "SEC" "1"
					( Origin gFrontEnd )
				)
				( attribute "SEC_TYPE" "0402"
					( Origin gFrontEnd )
				)
				( attribute "TOLERANCE" "1%"
					( Origin gFrontEnd )
				)
				( attribute "VALUE" "2.7K"
					( Origin gFrontEnd )
				)
				( attribute "VER" "1"
					( Origin gFrontEnd )
				)
				( attribute "WATTAGE" "1/16W"
					( Origin gFrontEnd )
				)
				( attribute "XY" "(-7025,2875)"
					( Origin gFrontEnd )
				)
				( attribute "CHIPS_PART_NAME" "RES"
					( Origin gPackager )
				)
				( attribute "CDS_PART_NAME" "RES_0402-2.7K,1%,1/16W,EMPTY,GA"
					( Origin gPackager )
				)
				( objectStatus "R1U24" )
				( pin "a"
					( attribute "PN" "1"
						( Origin gPackager )
					)
					( objectStatus "R1U24.1" )
				)
				( pin "b"
					( attribute "PN" "2"
						( Origin gPackager )
					)
					( objectStatus "R1U24.2" )
				)
			)
			( gate "@baseboard_fab2_lib.baseboard_fab2(sch_1):page164_i27"
				( attribute "BOM_COST" "SM_CONTROLLER"
					( Origin gFrontEnd )
				)
				( attribute "CDS_LIB" "mstr_discrete"
					( Origin gPackager )
				)
				( attribute "CDS_LOCATION" "R1U22"
					( Origin gPackager )
				)
				( attribute "CDS_SEC" "1"
					( Origin gPackager )
				)
				( attribute "LOCATION" "R1U22"
					( Origin gFrontEnd )
				)
				( attribute "MATERIAL" "CHIP"
					( Origin gFrontEnd )
				)
				( attribute "PACK_TYPE" "0402"
					( Origin gFrontEnd )
				)
				( attribute "PART_NUMBER" "G21796-344"
					( Origin gFrontEnd )
				)
				( attribute "PHYS_PAGE" "164"
					( Origin gFrontEnd )
				)
				( attribute "ROOM" "BMC_MISC"
					( Origin gFrontEnd )
				)
				( attribute "ROT" "0"
					( Origin gFrontEnd )
				)
				( attribute "SEC" "1"
					( Origin gFrontEnd )
				)
				( attribute "SEC_TYPE" "0402"
					( Origin gFrontEnd )
				)
				( attribute "TOLERANCE" "1%"
					( Origin gFrontEnd )
				)
				( attribute "VALUE" "2.7K"
					( Origin gFrontEnd )
				)
				( attribute "VER" "1"
					( Origin gFrontEnd )
				)
				( attribute "WATTAGE" "1/16W"
					( Origin gFrontEnd )
				)
				( attribute "XY" "(-7025,2675)"
					( Origin gFrontEnd )
				)
				( attribute "CHIPS_PART_NAME" "RES"
					( Origin gPackager )
				)
				( attribute "CDS_PART_NAME" "RES_0402-2.7K,1%,1/16W,CHIP,G2A"
					( Origin gPackager )
				)
				( objectStatus "R1U22" )
				( pin "a"
					( attribute "PN" "1"
						( Origin gPackager )
					)
					( objectStatus "R1U22.1" )
				)
				( pin "b"
					( attribute "PN" "2"
						( Origin gPackager )
					)
					( objectStatus "R1U22.2" )
				)
			)
			( gate "@baseboard_fab2_lib.baseboard_fab2(sch_1):page164_i28"
				( attribute "BOM_COST" "SM_CONTROLLER"
					( Origin gFrontEnd )
				)
				( attribute "CDS_LIB" "mstr_discrete"
					( Origin gPackager )
				)
				( attribute "CDS_LOCATION" "R1U23"
					( Origin gPackager )
				)
				( attribute "CDS_SEC" "1"
					( Origin gPackager )
				)
				( attribute "LOCATION" "R1U23"
					( Origin gFrontEnd )
				)
				( attribute "MATERIAL" "EMPTY"
					( Origin gFrontEnd )
				)
				( attribute "PACK_TYPE" "0402"
					( Origin gFrontEnd )
				)
				( attribute "PART_NUMBER" "G21796-344"
					( Origin gFrontEnd )
				)
				( attribute "PHYS_PAGE" "164"
					( Origin gFrontEnd )
				)
				( attribute "ROOM" "BMC_MISC"
					( Origin gFrontEnd )
				)
				( attribute "ROT" "0"
					( Origin gFrontEnd )
				)
				( attribute "SEC" "1"
					( Origin gFrontEnd )
				)
				( attribute "SEC_TYPE" "0402"
					( Origin gFrontEnd )
				)
				( attribute "TOLERANCE" "1%"
					( Origin gFrontEnd )
				)
				( attribute "VALUE" "2.7K"
					( Origin gFrontEnd )
				)
				( attribute "VER" "1"
					( Origin gFrontEnd )
				)
				( attribute "WATTAGE" "1/16W"
					( Origin gFrontEnd )
				)
				( attribute "XY" "(-7025,2475)"
					( Origin gFrontEnd )
				)
				( attribute "CHIPS_PART_NAME" "RES"
					( Origin gPackager )
				)
				( attribute "CDS_PART_NAME" "RES_0402-2.7K,1%,1/16W,EMPTY,GA"
					( Origin gPackager )
				)
				( objectStatus "R1U23" )
				( pin "a"
					( attribute "PN" "1"
						( Origin gPackager )
					)
					( objectStatus "R1U23.1" )
				)
				( pin "b"
					( attribute "PN" "2"
						( Origin gPackager )
					)
					( objectStatus "R1U23.2" )
				)
			)
			( gate "@baseboard_fab2_lib.baseboard_fab2(sch_1):page164_i29"
				( attribute "BOM_COST" "SM_CONTROLLER"
					( Origin gFrontEnd )
				)
				( attribute "CDS_LIB" "mstr_discrete"
					( Origin gPackager )
				)
				( attribute "CDS_LOCATION" "R2N17"
					( Origin gPackager )
				)
				( attribute "CDS_SEC" "1"
					( Origin gPackager )
				)
				( attribute "LOCATION" "R2N17"
					( Origin gFrontEnd )
				)
				( attribute "MATERIAL" "EMPTY"
					( Origin gFrontEnd )
				)
				( attribute "PACK_TYPE" "0402"
					( Origin gFrontEnd )
				)
				( attribute "PART_NUMBER" "G21796-344"
					( Origin gFrontEnd )
				)
				( attribute "PHYS_PAGE" "164"
					( Origin gFrontEnd )
				)
				( attribute "ROOM" "BMC_MISC"
					( Origin gFrontEnd )
				)
				( attribute "ROT" "0"
					( Origin gFrontEnd )
				)
				( attribute "SEC" "1"
					( Origin gPackager )
				)
				( attribute "TOLERANCE" "1%"
					( Origin gFrontEnd )
				)
				( attribute "VALUE" "2.7K"
					( Origin gFrontEnd )
				)
				( attribute "VER" "1"
					( Origin gFrontEnd )
				)
				( attribute "WATTAGE" "1/16W"
					( Origin gFrontEnd )
				)
				( attribute "XY" "(-7025,3275)"
					( Origin gFrontEnd )
				)
				( attribute "CHIPS_PART_NAME" "RES"
					( Origin gPackager )
				)
				( attribute "CDS_PART_NAME" "RES_0402-2.7K,1%,1/16W,EMPTY,GA"
					( Origin gPackager )
				)
				( objectStatus "R2N17" )
				( pin "a"
					( attribute "PN" "1"
						( Origin gPackager )
					)
					( objectStatus "R2N17.1" )
				)
				( pin "b"
					( attribute "PN" "2"
						( Origin gPackager )
					)
					( objectStatus "R2N17.2" )
				)
			)
			( gate "@baseboard_fab2_lib.baseboard_fab2(sch_1):page164_i32"
				( attribute "BOM_COST" "SM_CONTROLLER"
					( Origin gFrontEnd )
				)
				( attribute "CDS_LIB" "mstr_discrete"
					( Origin gPackager )
				)
				( attribute "CDS_LOCATION" "R2N18"
					( Origin gPackager )
				)
				( attribute "CDS_SEC" "1"
					( Origin gPackager )
				)
				( attribute "LOCATION" "R2N18"
					( Origin gFrontEnd )
				)
				( attribute "MATERIAL" "CHIP"
					( Origin gFrontEnd )
				)
				( attribute "PACK_TYPE" "0402"
					( Origin gFrontEnd )
				)
				( attribute "PART_NUMBER" "G21796-026"
					( Origin gFrontEnd )
				)
				( attribute "PHYS_PAGE" "164"
					( Origin gFrontEnd )
				)
				( attribute "ROOM" "BMC_MISC"
					( Origin gFrontEnd )
				)
				( attribute "ROT" "0"
					( Origin gFrontEnd )
				)
				( attribute "SEC" "1"
					( Origin gPackager )
				)
				( attribute "TOLERANCE" "1%"
					( Origin gFrontEnd )
				)
				( attribute "VALUE" "1.00K"
					( Origin gFrontEnd )
				)
				( attribute "VER" "2"
					( Origin gFrontEnd )
				)
				( attribute "WATTAGE" "1/16W"
					( Origin gFrontEnd )
				)
				( attribute "XY" "(-6475,2150)"
					( Origin gFrontEnd )
				)
				( attribute "CHIPS_PART_NAME" "RES"
					( Origin gPackager )
				)
				( attribute "CDS_PART_NAME" "RES_0402-1.00K,1%,1/16W,CHIP,GA"
					( Origin gPackager )
				)
				( objectStatus "R2N18" )
				( pin "a"
					( attribute "PN" "1"
						( Origin gPackager )
					)
					( objectStatus "R2N18.1" )
				)
				( pin "b"
					( attribute "PN" "2"
						( Origin gPackager )
					)
					( objectStatus "R2N18.2" )
				)
			)
			( gate "@baseboard_fab2_lib.baseboard_fab2(sch_1):page165_i52"
				( attribute "BOM_COST" "SM_HM"
					( Origin gFrontEnd )
				)
				( attribute "CDS_LIB" "mstr_digital"
					( Origin gPackager )
				)
				( attribute "CDS_LOCATION" "EU9G1"
					( Origin gPackager )
				)
				( attribute "CDS_SEC" "1"
					( Origin gPackager )
				)
				( attribute "LOCATION" "EU9G1"
					( Origin gFrontEnd )
				)
				( attribute "MATERIAL" "IC"
					( Origin gFrontEnd )
				)
				( attribute "PACK_TYPE" "SM"
					( Origin gFrontEnd )
				)
				( attribute "PART_NUMBER" "H63642-001"
					( Origin gFrontEnd )
				)
				( attribute "PHYS_PAGE" "165"
					( Origin gFrontEnd )
				)
				( attribute "ROOM" "HEC_VOLT_MONITOR"
					( Origin gFrontEnd )
				)
				( attribute "ROT" "0"
					( Origin gFrontEnd )
				)
				( attribute "SEC" "1"
					( Origin gFrontEnd )
				)
				( attribute "SEC_TYPE" "SM"
					( Origin gFrontEnd )
				)
				( attribute "VER" "1"
					( Origin gFrontEnd )
				)
				( attribute "XY" "(-4325,2625)"
					( Origin gFrontEnd )
				)
				( attribute "CHIPS_PART_NAME" "ADC128D818"
					( Origin gPackager )
				)
				( attribute "CDS_PART_NAME" "ADC128D818_SM-IC,H63642-001"
					( Origin gPackager )
				)
				( objectStatus "EU9G1" )
				( pin "a0"
					( attribute "PN" "7"
						( Origin gPackager )
					)
					( objectStatus "EU9G1.7" )
				)
				( pin "a1"
					( attribute "PN" "8"
						( Origin gPackager )
					)
					( objectStatus "EU9G1.8" )
				)
				( pin "gnd"
					( attribute "PN" "4"
						( Origin gPackager )
					)
					( objectStatus "EU9G1.4" )
				)
				( pin "in0"
					( attribute "PN" "16"
						( Origin gPackager )
					)
					( objectStatus "EU9G1.16" )
				)
				( pin "in1"
					( attribute "PN" "15"
						( Origin gPackager )
					)
					( objectStatus "EU9G1.15" )
				)
				( pin "in2"
					( attribute "PN" "14"
						( Origin gPackager )
					)
					( objectStatus "EU9G1.14" )
				)
				( pin "in3"
					( attribute "PN" "13"
						( Origin gPackager )
					)
					( objectStatus "EU9G1.13" )
				)
				( pin "in4"
					( attribute "PN" "12"
						( Origin gPackager )
					)
					( objectStatus "EU9G1.12" )
				)
				( pin "in5"
					( attribute "PN" "11"
						( Origin gPackager )
					)
					( objectStatus "EU9G1.11" )
				)
				( pin "in6"
					( attribute "PN" "10"
						( Origin gPackager )
					)
					( objectStatus "EU9G1.10" )
				)
				( pin "in7"
					( attribute "PN" "9"
						( Origin gPackager )
					)
					( objectStatus "EU9G1.9" )
				)
				( pin "int_n"
					( attribute "PN" "6"
						( Origin gPackager )
					)
					( objectStatus "EU9G1.6" )
				)
				( pin "scl"
					( attribute "PN" "3"
						( Origin gPackager )
					)
					( objectStatus "EU9G1.3" )
				)
				( pin "sda"
					( attribute "PN" "2"
						( Origin gPackager )
					)
					( objectStatus "EU9G1.2" )
				)
				( pin "vp"
					( attribute "PN" "5"
						( Origin gPackager )
					)
					( objectStatus "EU9G1.5" )
				)
				( pin "vref"
					( attribute "PN" "1"
						( Origin gPackager )
					)
					( objectStatus "EU9G1.1" )
				)
			)
			( gate "@baseboard_fab2_lib.baseboard_fab2(sch_1):page165_i55"
				( attribute "BOM_COST" "SM_HM"
					( Origin gFrontEnd )
				)
				( attribute "CDS_LIB" "mstr_discrete"
					( Origin gPackager )
				)
				( attribute "CDS_LOCATION" "R1U45"
					( Origin gPackager )
				)
				( attribute "CDS_SEC" "1"
					( Origin gPackager )
				)
				( attribute "LOCATION" "R1U45"
					( Origin gFrontEnd )
				)
				( attribute "MATERIAL" "CHIP"
					( Origin gFrontEnd )
				)
				( attribute "PACK_TYPE" "0402"
					( Origin gFrontEnd )
				)
				( attribute "PART_NUMBER" "G21796-072"
					( Origin gFrontEnd )
				)
				( attribute "PHYS_PAGE" "165"
					( Origin gFrontEnd )
				)
				( attribute "ROOM" "HEC_VOLT_MONITOR"
					( Origin gFrontEnd )
				)
				( attribute "ROT" "2"
					( Origin gFrontEnd )
				)
				( attribute "SEC" "1"
					( Origin gPackager )
				)
				( attribute "TOLERANCE" "1%"
					( Origin gFrontEnd )
				)
				( attribute "VALUE" "4.75K"
					( Origin gFrontEnd )
				)
				( attribute "VER" "2"
					( Origin gFrontEnd )
				)
				( attribute "WATTAGE" "1/16W"
					( Origin gFrontEnd )
				)
				( attribute "XY" "(-6275,2350)"
					( Origin gFrontEnd )
				)
				( attribute "CHIPS_PART_NAME" "RES"
					( Origin gPackager )
				)
				( attribute "CDS_PART_NAME" "RES_0402-4.75K,1%,1/16W,CHIP,GA"
					( Origin gPackager )
				)
				( objectStatus "R1U45" )
				( pin "a"
					( attribute "PN" "1"
						( Origin gPackager )
					)
					( objectStatus "R1U45.1" )
				)
				( pin "b"
					( attribute "PN" "2"
						( Origin gPackager )
					)
					( objectStatus "R1U45.2" )
				)
			)
			( gate "@baseboard_fab2_lib.baseboard_fab2(sch_1):page165_i56"
				( attribute "BOM_COST" "SM_HM"
					( Origin gFrontEnd )
				)
				( attribute "CDS_LIB" "mstr_discrete"
					( Origin gPackager )
				)
				( attribute "CDS_LOCATION" "R1U48"
					( Origin gPackager )
				)
				( attribute "CDS_SEC" "1"
					( Origin gPackager )
				)
				( attribute "LOCATION" "R1U48"
					( Origin gFrontEnd )
				)
				( attribute "MATERIAL" "CHIP"
					( Origin gFrontEnd )
				)
				( attribute "PACK_TYPE" "0402"
					( Origin gFrontEnd )
				)
				( attribute "PART_NUMBER" "G21796-072"
					( Origin gFrontEnd )
				)
				( attribute "PHYS_PAGE" "165"
					( Origin gFrontEnd )
				)
				( attribute "ROOM" "HEC_VOLT_MONITOR"
					( Origin gFrontEnd )
				)
				( attribute "ROT" "2"
					( Origin gFrontEnd )
				)
				( attribute "SEC" "1"
					( Origin gPackager )
				)
				( attribute "TOLERANCE" "1%"
					( Origin gFrontEnd )
				)
				( attribute "VALUE" "4.75K"
					( Origin gFrontEnd )
				)
				( attribute "VER" "2"
					( Origin gFrontEnd )
				)
				( attribute "WATTAGE" "1/16W"
					( Origin gFrontEnd )
				)
				( attribute "XY" "(-6650,2350)"
					( Origin gFrontEnd )
				)
				( attribute "CHIPS_PART_NAME" "RES"
					( Origin gPackager )
				)
				( attribute "CDS_PART_NAME" "RES_0402-4.75K,1%,1/16W,CHIP,GA"
					( Origin gPackager )
				)
				( objectStatus "R1U48" )
				( pin "a"
					( attribute "PN" "1"
						( Origin gPackager )
					)
					( objectStatus "R1U48.1" )
				)
				( pin "b"
					( attribute "PN" "2"
						( Origin gPackager )
					)
					( objectStatus "R1U48.2" )
				)
			)
			( gate "@baseboard_fab2_lib.baseboard_fab2(sch_1):page165_i57"
				( attribute "BOM_COST" "SM_HM"
					( Origin gFrontEnd )
				)
				( attribute "CDS_LIB" "mstr_discrete"
					( Origin gPackager )
				)
				( attribute "CDS_LOCATION" "R9G23"
					( Origin gPackager )
				)
				( attribute "CDS_SEC" "1"
					( Origin gPackager )
				)
				( attribute "LOCATION" "R9G23"
					( Origin gFrontEnd )
				)
				( attribute "MATERIAL" "EMPTY"
					( Origin gFrontEnd )
				)
				( attribute "PACK_TYPE" "0402"
					( Origin gFrontEnd )
				)
				( attribute "PART_NUMBER" "G21796-072"
					( Origin gFrontEnd )
				)
				( attribute "PHYS_PAGE" "165"
					( Origin gFrontEnd )
				)
				( attribute "ROOM" "HEC_VOLT_MONITOR"
					( Origin gFrontEnd )
				)
				( attribute "ROT" "0"
					( Origin gFrontEnd )
				)
				( attribute "SEC" "1"
					( Origin gPackager )
				)
				( attribute "TOLERANCE" "1%"
					( Origin gFrontEnd )
				)
				( attribute "VALUE" "4.75K"
					( Origin gFrontEnd )
				)
				( attribute "VER" "2"
					( Origin gFrontEnd )
				)
				( attribute "WATTAGE" "1/16W"
					( Origin gFrontEnd )
				)
				( attribute "XY" "(-6275,2850)"
					( Origin gFrontEnd )
				)
				( attribute "CHIPS_PART_NAME" "RES"
					( Origin gPackager )
				)
				( attribute "CDS_PART_NAME" "RES_0402-4.75K,1%,1/16W,EMPTY,A"
					( Origin gPackager )
				)
				( objectStatus "R9G23" )
				( pin "a"
					( attribute "PN" "1"
						( Origin gPackager )
					)
					( objectStatus "R9G23.1" )
				)
				( pin "b"
					( attribute "PN" "2"
						( Origin gPackager )
					)
					( objectStatus "R9G23.2" )
				)
			)
			( gate "@baseboard_fab2_lib.baseboard_fab2(sch_1):page165_i58"
				( attribute "BOM_COST" "SM_HM"
					( Origin gFrontEnd )
				)
				( attribute "CDS_LIB" "mstr_discrete"
					( Origin gPackager )
				)
				( attribute "CDS_LOCATION" "R9G25"
					( Origin gPackager )
				)
				( attribute "CDS_SEC" "1"
					( Origin gPackager )
				)
				( attribute "LOCATION" "R9G25"
					( Origin gFrontEnd )
				)
				( attribute "MATERIAL" "EMPTY"
					( Origin gFrontEnd )
				)
				( attribute "PACK_TYPE" "0402"
					( Origin gFrontEnd )
				)
				( attribute "PART_NUMBER" "G21796-072"
					( Origin gFrontEnd )
				)
				( attribute "PHYS_PAGE" "165"
					( Origin gFrontEnd )
				)
				( attribute "ROOM" "HEC_VOLT_MONITOR"
					( Origin gFrontEnd )
				)
				( attribute "ROT" "0"
					( Origin gFrontEnd )
				)
				( attribute "SEC" "1"
					( Origin gPackager )
				)
				( attribute "TOLERANCE" "1%"
					( Origin gFrontEnd )
				)
				( attribute "VALUE" "4.75K"
					( Origin gFrontEnd )
				)
				( attribute "VER" "2"
					( Origin gFrontEnd )
				)
				( attribute "WATTAGE" "1/16W"
					( Origin gFrontEnd )
				)
				( attribute "XY" "(-6650,2850)"
					( Origin gFrontEnd )
				)
				( attribute "CHIPS_PART_NAME" "RES"
					( Origin gPackager )
				)
				( attribute "CDS_PART_NAME" "RES_0402-4.75K,1%,1/16W,EMPTY,A"
					( Origin gPackager )
				)
				( objectStatus "R9G25" )
				( pin "a"
					( attribute "PN" "1"
						( Origin gPackager )
					)
					( objectStatus "R9G25.1" )
				)
				( pin "b"
					( attribute "PN" "2"
						( Origin gPackager )
					)
					( objectStatus "R9G25.2" )
				)
			)
			( gate "@baseboard_fab2_lib.baseboard_fab2(sch_1):page165_i61"
				( attribute "BOM_COST" "SM_HM"
					( Origin gFrontEnd )
				)
				( attribute "CDS_LIB" "dev_discrete"
					( Origin gPackager )
				)
				( attribute "CDS_LOCATION" "C9G19"
					( Origin gPackager )
				)
				( attribute "CDS_SEC" "1"
					( Origin gPackager )
				)
				( attribute "LOCATION" "C9G19"
					( Origin gFrontEnd )
				)
				( attribute "MATERIAL" "X7R"
					( Origin gFrontEnd )
				)
				( attribute "PACK_TYPE" "0402V"
					( Origin gFrontEnd )
				)
				( attribute "PART_NUMBER" "A36096-030"
					( Origin gFrontEnd )
				)
				( attribute "PHYS_PAGE" "165"
					( Origin gFrontEnd )
				)
				( attribute "ROOM" "HEC_VOLT_MONITOR"
					( Origin gFrontEnd )
				)
				( attribute "ROT" "0"
					( Origin gFrontEnd )
				)
				( attribute "SEC" "1"
					( Origin gPackager )
				)
				( attribute "TOLERANCE" "10%"
					( Origin gFrontEnd )
				)
				( attribute "VALUE" "0.1UF"
					( Origin gFrontEnd )
				)
				( attribute "VER" "1"
					( Origin gFrontEnd )
				)
				( attribute "VOLTAGE" "16V"
					( Units "uVoltage" "V" 1.000000)
					( Origin gFrontEnd )
				)
				( attribute "XY" "(-5050,3525)"
					( Origin gFrontEnd )
				)
				( attribute "CHIPS_PART_NAME" "CAP_A"
					( Origin gPackager )
				)
				( attribute "CDS_PART_NAME" "CAP_A_0402V-0.1UF,16V,10%,X7R,A"
					( Origin gPackager )
				)
				( objectStatus "C9G19" )
				( pin "a"
					( attribute "PN" "1"
						( Origin gPackager )
					)
					( objectStatus "C9G19.1" )
				)
				( pin "b"
					( attribute "PN" "2"
						( Origin gPackager )
					)
					( objectStatus "C9G19.2" )
				)
			)
			( gate "@baseboard_fab2_lib.baseboard_fab2(sch_1):page165_i67"
				( attribute "BOM_COST" "SM_HM"
					( Origin gFrontEnd )
				)
				( attribute "CDS_LIB" "mstr_discrete"
					( Origin gPackager )
				)
				( attribute "CDS_LOCATION" "C1U20"
					( Origin gPackager )
				)
				( attribute "CDS_SEC" "1"
					( Origin gPackager )
				)
				( attribute "LOCATION" "C1U20"
					( Origin gFrontEnd )
				)
				( attribute "MATERIAL" "X7R"
					( Origin gFrontEnd )
				)
				( attribute "PACK_TYPE" "0805"
					( Origin gFrontEnd )
				)
				( attribute "PART_NUMBER" "G10601-001"
					( Origin gFrontEnd )
				)
				( attribute "PHYS_PAGE" "165"
					( Origin gFrontEnd )
				)
				( attribute "ROOM" "HEC_VOLT_MONITOR"
					( Origin gFrontEnd )
				)
				( attribute "ROT" "0"
					( Origin gFrontEnd )
				)
				( attribute "SEC" "1"
					( Origin gPackager )
				)
				( attribute "TOLERANCE" "10%"
					( Origin gFrontEnd )
				)
				( attribute "VALUE" "10UF"
					( Origin gFrontEnd )
				)
				( attribute "VER" "1"
					( Origin gFrontEnd )
				)
				( attribute "VOLTAGE" "16V"
					( Units "uVoltage" "V" 1.000000)
					( Origin gFrontEnd )
				)
				( attribute "XY" "(-5325,3525)"
					( Origin gFrontEnd )
				)
				( attribute "CHIPS_PART_NAME" "CAP"
					( Origin gPackager )
				)
				( attribute "CDS_PART_NAME" "CAP_0805-10UF,16V,10%,X7R,G106A"
					( Origin gPackager )
				)
				( objectStatus "C1U20" )
				( pin "a"
					( attribute "PN" "1"
						( Origin gPackager )
					)
					( objectStatus "C1U20.1" )
				)
				( pin "b"
					( attribute "PN" "2"
						( Origin gPackager )
					)
					( objectStatus "C1U20.2" )
				)
			)
			( gate "@baseboard_fab2_lib.baseboard_fab2(sch_1):page165_i69"
				( attribute "BOM_COST" "SM_HM"
					( Origin gFrontEnd )
				)
				( attribute "CDS_LIB" "mstr_discrete"
					( Origin gPackager )
				)
				( attribute "CDS_LOCATION" "R9G21"
					( Origin gPackager )
				)
				( attribute "CDS_SEC" "1"
					( Origin gPackager )
				)
				( attribute "LOCATION" "R9G21"
					( Origin gFrontEnd )
				)
				( attribute "MATERIAL" "CHIP"
					( Origin gFrontEnd )
				)
				( attribute "PACK_TYPE" "0402"
					( Origin gFrontEnd )
				)
				( attribute "PART_NUMBER" "G21796-072"
					( Origin gFrontEnd )
				)
				( attribute "PHYS_PAGE" "165"
					( Origin gFrontEnd )
				)
				( attribute "ROOM" "HEC_VOLT_MONITOR"
					( Origin gFrontEnd )
				)
				( attribute "ROT" "0"
					( Origin gFrontEnd )
				)
				( attribute "SEC" "1"
					( Origin gFrontEnd )
				)
				( attribute "SEC_TYPE" "0402"
					( Origin gFrontEnd )
				)
				( attribute "TOLERANCE" "1%"
					( Origin gFrontEnd )
				)
				( attribute "VALUE" "4.75K"
					( Origin gFrontEnd )
				)
				( attribute "VER" "2"
					( Origin gFrontEnd )
				)
				( attribute "WATTAGE" "1/16W"
					( Origin gFrontEnd )
				)
				( attribute "XY" "(-3650,3375)"
					( Origin gFrontEnd )
				)
				( attribute "CHIPS_PART_NAME" "RES"
					( Origin gPackager )
				)
				( attribute "CDS_PART_NAME" "RES_0402-4.75K,1%,1/16W,CHIP,GA"
					( Origin gPackager )
				)
				( objectStatus "R9G21" )
				( pin "a"
					( attribute "PN" "1"
						( Origin gPackager )
					)
					( objectStatus "R9G21.1" )
				)
				( pin "b"
					( attribute "PN" "2"
						( Origin gPackager )
					)
					( objectStatus "R9G21.2" )
				)
			)
			( gate "@baseboard_fab2_lib.baseboard_fab2(sch_1):page165_i79"
				( attribute "BOM_COST" "SM_HM"
					( Origin gFrontEnd )
				)
				( attribute "CDS_LIB" "mstr_discrete"
					( Origin gPackager )
				)
				( attribute "CDS_LOCATION" "FB1U2"
					( Origin gPackager )
				)
				( attribute "CDS_SEC" "1"
					( Origin gPackager )
				)
				( attribute "LOCATION" "FB1U2"
					( Origin gFrontEnd )
				)
				( attribute "MATERIAL" "FB"
					( Origin gFrontEnd )
				)
				( attribute "PACK_TYPE" "SMLF"
					( Origin gFrontEnd )
				)
				( attribute "PART_NUMBER" "693286-001"
					( Origin gFrontEnd )
				)
				( attribute "PHYS_PAGE" "165"
					( Origin gFrontEnd )
				)
				( attribute "ROOM" "HEC_VOLT_MONITOR"
					( Origin gFrontEnd )
				)
				( attribute "ROT" "0"
					( Origin gFrontEnd )
				)
				( attribute "SEC" "1"
					( Origin gFrontEnd )
				)
				( attribute "SEC_TYPE" "SMLF"
					( Origin gFrontEnd )
				)
				( attribute "VALUE" "60"
					( Origin gFrontEnd )
				)
				( attribute "VER" "1"
					( Origin gFrontEnd )
				)
				( attribute "XY" "(-5525,3750)"
					( Origin gFrontEnd )
				)
				( attribute "CHIPS_PART_NAME" "FERRITE"
					( Origin gPackager )
				)
				( attribute "CDS_PART_NAME" "FERRITE_SMLF-60,FB,693286-001"
					( Origin gPackager )
				)
				( objectStatus "FB1U2" )
				( pin "a"
					( attribute "PN" "1"
						( Origin gPackager )
					)
					( objectStatus "FB1U2.1" )
				)
				( pin "b"
					( attribute "PN" "2"
						( Origin gPackager )
					)
					( objectStatus "FB1U2.2" )
				)
			)
			( gate "@baseboard_fab2_lib.baseboard_fab2(sch_1):page165_i81"
				( attribute "CDS_LIB" "mstr_discrete"
					( Origin gPackager )
				)
				( attribute "CDS_LOCATION" "R1U40"
					( Origin gPackager )
				)
				( attribute "CDS_SEC" "1"
					( Origin gPackager )
				)
				( attribute "LOCATION" "R1U40"
					( Origin gFrontEnd )
				)
				( attribute "MATERIAL" "CHIP"
					( Origin gFrontEnd )
				)
				( attribute "PACK_TYPE" "0402"
					( Origin gFrontEnd )
				)
				( attribute "PART_NUMBER" "G21796-074"
					( Origin gFrontEnd )
				)
				( attribute "PHYS_PAGE" "165"
					( Origin gFrontEnd )
				)
				( attribute "ROT" "0"
					( Origin gFrontEnd )
				)
				( attribute "SEC" "1"
					( Origin gFrontEnd )
				)
				( attribute "SEC_TYPE" "0402"
					( Origin gFrontEnd )
				)
				( attribute "TOLERANCE" "1%"
					( Origin gFrontEnd )
				)
				( attribute "VALUE" "33.2"
					( Origin gFrontEnd )
				)
				( attribute "VER" "1"
					( Origin gFrontEnd )
				)
				( attribute "WATTAGE" "1/16W"
					( Origin gFrontEnd )
				)
				( attribute "XY" "(-3075,3025)"
					( Origin gFrontEnd )
				)
				( attribute "CHIPS_PART_NAME" "RES"
					( Origin gPackager )
				)
				( attribute "CDS_PART_NAME" "RES_0402-33.2,1%,1/16W,CHIP,G2A"
					( Origin gPackager )
				)
				( objectStatus "R1U40" )
				( pin "a"
					( attribute "PN" "1"
						( Origin gPackager )
					)
					( objectStatus "R1U40.1" )
				)
				( pin "b"
					( attribute "PN" "2"
						( Origin gPackager )
					)
					( objectStatus "R1U40.2" )
				)
			)
			( gate "@baseboard_fab2_lib.baseboard_fab2(sch_1):page166_i11"
				( attribute "BOM_COST" "DEBUG"
					( Origin gFrontEnd )
				)
				( attribute "CDS_LIB" "mstr_discrete"
					( Origin gPackager )
				)
				( attribute "CDS_LOCATION" "R7C18"
					( Origin gPackager )
				)
				( attribute "CDS_SEC" "1"
					( Origin gPackager )
				)
				( attribute "LOCATION" "R7C18"
					( Origin gFrontEnd )
				)
				( attribute "MATERIAL" "EMPTY"
					( Origin gFrontEnd )
				)
				( attribute "PACK_TYPE" "0402"
					( Origin gFrontEnd )
				)
				( attribute "PART_NUMBER" "G21497-005"
					( Origin gFrontEnd )
				)
				( attribute "PHYS_PAGE" "166"
					( Origin gFrontEnd )
				)
				( attribute "ROOM" "PECI"
					( Origin gFrontEnd )
				)
				( attribute "ROT" "0"
					( Origin gFrontEnd )
				)
				( attribute "SEC" "1"
					( Origin gFrontEnd )
				)
				( attribute "SEC_TYPE" "0402"
					( Origin gFrontEnd )
				)
				( attribute "TOLERANCE" "5%"
					( Origin gFrontEnd )
				)
				( attribute "VALUE" "0.0"
					( Origin gFrontEnd )
				)
				( attribute "VER" "1"
					( Origin gFrontEnd )
				)
				( attribute "WATTAGE" "1/16W"
					( Origin gFrontEnd )
				)
				( attribute "XY" "(-4550,3125)"
					( Origin gFrontEnd )
				)
				( attribute "CHIPS_PART_NAME" "RES"
					( Origin gPackager )
				)
				( attribute "CDS_PART_NAME" "RES_0402-0.0,5%,1/16W,EMPTY,G2A"
					( Origin gPackager )
				)
				( objectStatus "R7C18" )
				( pin "a"
					( attribute "PN" "1"
						( Origin gPackager )
					)
					( objectStatus "R7C18.1" )
				)
				( pin "b"
					( attribute "PN" "2"
						( Origin gPackager )
					)
					( objectStatus "R7C18.2" )
				)
			)
			( gate "@baseboard_fab2_lib.baseboard_fab2(sch_1):page166_i14"
				( attribute "BOM_COST" "DEBUG"
					( Origin gFrontEnd )
				)
				( attribute "CDS_LIB" "mstr_discrete"
					( Origin gPackager )
				)
				( attribute "CDS_LOCATION" "R7C22"
					( Origin gPackager )
				)
				( attribute "CDS_SEC" "1"
					( Origin gPackager )
				)
				( attribute "LOCATION" "R7C22"
					( Origin gFrontEnd )
				)
				( attribute "MATERIAL" "EMPTY"
					( Origin gFrontEnd )
				)
				( attribute "PACK_TYPE" "0402"
					( Origin gFrontEnd )
				)
				( attribute "PART_NUMBER" "G21796-072"
					( Origin gFrontEnd )
				)
				( attribute "PHYS_PAGE" "166"
					( Origin gFrontEnd )
				)
				( attribute "ROOM" "PECI"
					( Origin gFrontEnd )
				)
				( attribute "ROT" "0"
					( Origin gFrontEnd )
				)
				( attribute "SEC" "1"
					( Origin gFrontEnd )
				)
				( attribute "SEC_TYPE" "0402"
					( Origin gFrontEnd )
				)
				( attribute "TOLERANCE" "1%"
					( Origin gFrontEnd )
				)
				( attribute "VALUE" "4.75K"
					( Origin gFrontEnd )
				)
				( attribute "VER" "2"
					( Origin gFrontEnd )
				)
				( attribute "WATTAGE" "1/16W"
					( Origin gFrontEnd )
				)
				( attribute "XY" "(-4850,3500)"
					( Origin gFrontEnd )
				)
				( attribute "CHIPS_PART_NAME" "RES"
					( Origin gPackager )
				)
				( attribute "CDS_PART_NAME" "RES_0402-4.75K,1%,1/16W,EMPTY,A"
					( Origin gPackager )
				)
				( objectStatus "R7C22" )
				( pin "a"
					( attribute "PN" "1"
						( Origin gPackager )
					)
					( objectStatus "R7C22.1" )
				)
				( pin "b"
					( attribute "PN" "2"
						( Origin gPackager )
					)
					( objectStatus "R7C22.2" )
				)
			)
			( gate "@baseboard_fab2_lib.baseboard_fab2(sch_1):page166_i15"
				( attribute "BOM_COST" "DEBUG"
					( Origin gFrontEnd )
				)
				( attribute "CDS_LIB" "mstr_discrete"
					( Origin gPackager )
				)
				( attribute "CDS_LOCATION" "R7C19"
					( Origin gPackager )
				)
				( attribute "CDS_SEC" "1"
					( Origin gPackager )
				)
				( attribute "LOCATION" "R7C19"
					( Origin gFrontEnd )
				)
				( attribute "MATERIAL" "CHIP"
					( Origin gFrontEnd )
				)
				( attribute "PACK_TYPE" "0402"
					( Origin gFrontEnd )
				)
				( attribute "PART_NUMBER" "G21497-005"
					( Origin gFrontEnd )
				)
				( attribute "PHYS_PAGE" "166"
					( Origin gFrontEnd )
				)
				( attribute "ROOM" "PECI"
					( Origin gFrontEnd )
				)
				( attribute "ROT" "0"
					( Origin gFrontEnd )
				)
				( attribute "SEC" "1"
					( Origin gFrontEnd )
				)
				( attribute "SEC_TYPE" "0402"
					( Origin gFrontEnd )
				)
				( attribute "TOLERANCE" "5%"
					( Origin gFrontEnd )
				)
				( attribute "VALUE" "0.0"
					( Origin gFrontEnd )
				)
				( attribute "VER" "1"
					( Origin gFrontEnd )
				)
				( attribute "WATTAGE" "1/16W"
					( Origin gFrontEnd )
				)
				( attribute "XY" "(-4675,2525)"
					( Origin gFrontEnd )
				)
				( attribute "CHIPS_PART_NAME" "RES"
					( Origin gPackager )
				)
				( attribute "CDS_PART_NAME" "RES_0402-0.0,5%,1/16W,CHIP,G21A"
					( Origin gPackager )
				)
				( objectStatus "R7C19" )
				( pin "a"
					( attribute "PN" "1"
						( Origin gPackager )
					)
					( objectStatus "R7C19.1" )
				)
				( pin "b"
					( attribute "PN" "2"
						( Origin gPackager )
					)
					( objectStatus "R7C19.2" )
				)
			)
			( gate "@baseboard_fab2_lib.baseboard_fab2(sch_1):page166_i28"
				( attribute "BOM_COST" "DEBUG"
					( Origin gFrontEnd )
				)
				( attribute "CDS_LIB" "mstr_discrete"
					( Origin gPackager )
				)
				( attribute "CDS_LOCATION" "R7C17"
					( Origin gPackager )
				)
				( attribute "CDS_SEC" "1"
					( Origin gPackager )
				)
				( attribute "LOCATION" "R7C17"
					( Origin gFrontEnd )
				)
				( attribute "MATERIAL" "CHIP"
					( Origin gFrontEnd )
				)
				( attribute "PACK_TYPE" "0402"
					( Origin gFrontEnd )
				)
				( attribute "PART_NUMBER" "G21796-072"
					( Origin gFrontEnd )
				)
				( attribute "PHYS_PAGE" "166"
					( Origin gFrontEnd )
				)
				( attribute "ROOM" "PECI"
					( Origin gFrontEnd )
				)
				( attribute "ROT" "2"
					( Origin gFrontEnd )
				)
				( attribute "SEC" "1"
					( Origin gFrontEnd )
				)
				( attribute "SEC_TYPE" "0402"
					( Origin gFrontEnd )
				)
				( attribute "TOLERANCE" "1%"
					( Origin gFrontEnd )
				)
				( attribute "VALUE" "4.75K"
					( Origin gFrontEnd )
				)
				( attribute "VER" "2"
					( Origin gFrontEnd )
				)
				( attribute "WATTAGE" "1/16W"
					( Origin gFrontEnd )
				)
				( attribute "XY" "(-5050,3500)"
					( Origin gFrontEnd )
				)
				( attribute "CHIPS_PART_NAME" "RES"
					( Origin gPackager )
				)
				( attribute "CDS_PART_NAME" "RES_0402-4.75K,1%,1/16W,CHIP,GA"
					( Origin gPackager )
				)
				( objectStatus "R7C17" )
				( pin "a"
					( attribute "PN" "1"
						( Origin gPackager )
					)
					( objectStatus "R7C17.1" )
				)
				( pin "b"
					( attribute "PN" "2"
						( Origin gPackager )
					)
					( objectStatus "R7C17.2" )
				)
			)
			( gate "@baseboard_fab2_lib.baseboard_fab2(sch_1):page166_i32"
				( attribute "BOM_COST" "DEBUG"
					( Origin gFrontEnd )
				)
				( attribute "CDS_LIB" "mstr_discrete"
					( Origin gPackager )
				)
				( attribute "CDS_LOCATION" "R7D15"
					( Origin gPackager )
				)
				( attribute "CDS_SEC" "1"
					( Origin gPackager )
				)
				( attribute "LOCATION" "R7D15"
					( Origin gFrontEnd )
				)
				( attribute "MATERIAL" "CHIP"
					( Origin gFrontEnd )
				)
				( attribute "PACK_TYPE" "0402"
					( Origin gFrontEnd )
				)
				( attribute "PART_NUMBER" "G21796-340"
					( Origin gFrontEnd )
				)
				( attribute "PHYS_PAGE" "166"
					( Origin gFrontEnd )
				)
				( attribute "ROOM" "PECI"
					( Origin gFrontEnd )
				)
				( attribute "ROT" "0"
					( Origin gFrontEnd )
				)
				( attribute "SEC" "1"
					( Origin gFrontEnd )
				)
				( attribute "SEC_TYPE" "0402"
					( Origin gFrontEnd )
				)
				( attribute "TOLERANCE" "1%"
					( Origin gFrontEnd )
				)
				( attribute "VALUE" "348"
					( Origin gFrontEnd )
				)
				( attribute "VER" "2"
					( Origin gFrontEnd )
				)
				( attribute "WATTAGE" "1/16W"
					( Origin gFrontEnd )
				)
				( attribute "XY" "(-4475,2200)"
					( Origin gFrontEnd )
				)
				( attribute "CHIPS_PART_NAME" "RES"
					( Origin gPackager )
				)
				( attribute "CDS_PART_NAME" "RES_0402-348,1%,1/16W,CHIP,G21A"
					( Origin gPackager )
				)
				( objectStatus "R7D15" )
				( pin "a"
					( attribute "PN" "1"
						( Origin gPackager )
					)
					( objectStatus "R7D15.1" )
				)
				( pin "b"
					( attribute "PN" "2"
						( Origin gPackager )
					)
					( objectStatus "R7D15.2" )
				)
			)
			( gate "@baseboard_fab2_lib.baseboard_fab2(sch_1):page167_i1"
				( attribute "BOM_COST" "SM_THERM"
					( Origin gFrontEnd )
				)
				( attribute "CDS_LIB" "mstr_analog"
					( Origin gPackager )
				)
				( attribute "CDS_LOCATION" "U9B4"
					( Origin gPackager )
				)
				( attribute "CDS_SEC" "1"
					( Origin gPackager )
				)
				( attribute "LOCATION" "U9B4"
					( Origin gFrontEnd )
				)
				( attribute "MATERIAL" "IC"
					( Origin gFrontEnd )
				)
				( attribute "PACK_TYPE" "TSSOP"
					( Origin gFrontEnd )
				)
				( attribute "PART_NUMBER" "G62962-001"
					( Origin gFrontEnd )
				)
				( attribute "PHYS_PAGE" "167"
					( Origin gFrontEnd )
				)
				( attribute "ROOM" "TEMP_SENSORS"
					( Origin gFrontEnd )
				)
				( attribute "ROT" "0"
					( Origin gFrontEnd )
				)
				( attribute "SEC" "1"
					( Origin gFrontEnd )
				)
				( attribute "SEC_TYPE" "TSSOP"
					( Origin gFrontEnd )
				)
				( attribute "VER" "1"
					( Origin gFrontEnd )
				)
				( attribute "XY" "(-4000,4450)"
					( Origin gFrontEnd )
				)
				( attribute "CHIPS_PART_NAME" "TMP421"
					( Origin gPackager )
				)
				( attribute "CDS_PART_NAME" "TMP421_TSSOP-IC,G62962-001"
					( Origin gPackager )
				)
				( objectStatus "U9B4" )
				( pin "a(0)"
					( attribute "PN" "4"
						( Origin gPackager )
					)
					( objectStatus "U9B4.4" )
				)
				( pin "a(1)"
					( attribute "PN" "3"
						( Origin gPackager )
					)
					( objectStatus "U9B4.3" )
				)
				( pin "dxn"
					( attribute "PN" "2"
						( Origin gPackager )
					)
					( objectStatus "U9B4.2" )
				)
				( pin "dxp"
					( attribute "PN" "1"
						( Origin gPackager )
					)
					( objectStatus "U9B4.1" )
				)
				( pin "gnd"
					( attribute "PN" "5"
						( Origin gPackager )
					)
					( objectStatus "U9B4.5" )
				)
				( pin "scl"
					( attribute "PN" "7"
						( Origin gPackager )
					)
					( objectStatus "U9B4.7" )
				)
				( pin "sda"
					( attribute "PN" "6"
						( Origin gPackager )
					)
					( objectStatus "U9B4.6" )
				)
				( pin "vp"
					( attribute "PN" "8"
						( Origin gPackager )
					)
					( objectStatus "U9B4.8" )
				)
			)
			( gate "@baseboard_fab2_lib.baseboard_fab2(sch_1):page167_i3"
				( attribute "BOM_COST" "SM_THERM"
					( Origin gFrontEnd )
				)
				( attribute "CDS_LIB" "mstr_discrete"
					( Origin gPackager )
				)
				( attribute "CDS_LOCATION" "Q9B1"
					( Origin gPackager )
				)
				( attribute "CDS_SEC" "1"
					( Origin gPackager )
				)
				( attribute "LOCATION" "Q9B1"
					( Origin gFrontEnd )
				)
				( attribute "MATERIAL" "IC"
					( Origin gFrontEnd )
				)
				( attribute "PACK_TYPE" "TO92"
					( Origin gFrontEnd )
				)
				( attribute "PART_NUMBER" "G73554-001"
					( Origin gFrontEnd )
				)
				( attribute "PHYS_PAGE" "167"
					( Origin gFrontEnd )
				)
				( attribute "ROOM" "TEMP_SENSORS"
					( Origin gFrontEnd )
				)
				( attribute "ROT" "0"
					( Origin gFrontEnd )
				)
				( attribute "SEC" "1"
					( Origin gFrontEnd )
				)
				( attribute "SEC_TYPE" "TO92"
					( Origin gFrontEnd )
				)
				( attribute "VALUE" "MPS2907"
					( Origin gFrontEnd )
				)
				( attribute "VER" "3"
					( Origin gFrontEnd )
				)
				( attribute "XY" "(-5775,4600)"
					( Origin gFrontEnd )
				)
				( attribute "CHIPS_PART_NAME" "PNP"
					( Origin gPackager )
				)
				( attribute "CDS_PART_NAME" "PNP_TO92-MPS2907,IC,G73554-001"
					( Origin gPackager )
				)
				( objectStatus "Q9B1" )
				( pin "b"
					( attribute "PN" "1"
						( Origin gPackager )
					)
					( objectStatus "Q9B1.1" )
				)
				( pin "c"
					( attribute "PN" "3"
						( Origin gPackager )
					)
					( objectStatus "Q9B1.3" )
				)
				( pin "e"
					( attribute "PN" "2"
						( Origin gPackager )
					)
					( objectStatus "Q9B1.2" )
				)
			)
			( gate "@baseboard_fab2_lib.baseboard_fab2(sch_1):page167_i5"
				( attribute "BOM_COST" "SM_THERM"
					( Origin gFrontEnd )
				)
				( attribute "CDS_LIB" "mstr_discrete"
					( Origin gPackager )
				)
				( attribute "CDS_LOCATION" "R9B5"
					( Origin gPackager )
				)
				( attribute "CDS_SEC" "1"
					( Origin gPackager )
				)
				( attribute "LOCATION" "R9B5"
					( Origin gFrontEnd )
				)
				( attribute "MATERIAL" "CHIP"
					( Origin gFrontEnd )
				)
				( attribute "PACK_TYPE" "0402"
					( Origin gFrontEnd )
				)
				( attribute "PART_NUMBER" "G21796-047"
					( Origin gFrontEnd )
				)
				( attribute "PHYS_PAGE" "167"
					( Origin gFrontEnd )
				)
				( attribute "ROOM" "TEMP_SENSORS"
					( Origin gFrontEnd )
				)
				( attribute "ROT" "0"
					( Origin gFrontEnd )
				)
				( attribute "SEC" "1"
					( Origin gFrontEnd )
				)
				( attribute "SEC_TYPE" "0402"
					( Origin gFrontEnd )
				)
				( attribute "TOLERANCE" "1%"
					( Origin gFrontEnd )
				)
				( attribute "VALUE" "49.9"
					( Origin gFrontEnd )
				)
				( attribute "VER" "1"
					( Origin gFrontEnd )
				)
				( attribute "WATTAGE" "1/16W"
					( Origin gFrontEnd )
				)
				( attribute "XY" "(-5150,4450)"
					( Origin gFrontEnd )
				)
				( attribute "CHIPS_PART_NAME" "RES"
					( Origin gPackager )
				)
				( attribute "CDS_PART_NAME" "RES_0402-49.9,1%,1/16W,CHIP,G2A"
					( Origin gPackager )
				)
				( objectStatus "R9B5" )
				( pin "a"
					( attribute "PN" "1"
						( Origin gPackager )
					)
					( objectStatus "R9B5.1" )
				)
				( pin "b"
					( attribute "PN" "2"
						( Origin gPackager )
					)
					( objectStatus "R9B5.2" )
				)
			)
			( gate "@baseboard_fab2_lib.baseboard_fab2(sch_1):page167_i6"
				( attribute "BOM_COST" "SM_THERM"
					( Origin gFrontEnd )
				)
				( attribute "CDS_LIB" "mstr_discrete"
					( Origin gPackager )
				)
				( attribute "CDS_LOCATION" "R9B4"
					( Origin gPackager )
				)
				( attribute "CDS_SEC" "1"
					( Origin gPackager )
				)
				( attribute "LOCATION" "R9B4"
					( Origin gFrontEnd )
				)
				( attribute "MATERIAL" "CHIP"
					( Origin gFrontEnd )
				)
				( attribute "PACK_TYPE" "0402"
					( Origin gFrontEnd )
				)
				( attribute "PART_NUMBER" "G21796-047"
					( Origin gFrontEnd )
				)
				( attribute "PHYS_PAGE" "167"
					( Origin gFrontEnd )
				)
				( attribute "ROOM" "TEMP_SENSORS"
					( Origin gFrontEnd )
				)
				( attribute "ROT" "0"
					( Origin gFrontEnd )
				)
				( attribute "SEC" "1"
					( Origin gFrontEnd )
				)
				( attribute "SEC_TYPE" "0402"
					( Origin gFrontEnd )
				)
				( attribute "TOLERANCE" "1%"
					( Origin gFrontEnd )
				)
				( attribute "VALUE" "49.9"
					( Origin gFrontEnd )
				)
				( attribute "VER" "1"
					( Origin gFrontEnd )
				)
				( attribute "WATTAGE" "1/16W"
					( Origin gFrontEnd )
				)
				( attribute "XY" "(-5150,4775)"
					( Origin gFrontEnd )
				)
				( attribute "CHIPS_PART_NAME" "RES"
					( Origin gPackager )
				)
				( attribute "CDS_PART_NAME" "RES_0402-49.9,1%,1/16W,CHIP,G2A"
					( Origin gPackager )
				)
				( objectStatus "R9B4" )
				( pin "a"
					( attribute "PN" "1"
						( Origin gPackager )
					)
					( objectStatus "R9B4.1" )
				)
				( pin "b"
					( attribute "PN" "2"
						( Origin gPackager )
					)
					( objectStatus "R9B4.2" )
				)
			)
			( gate "@baseboard_fab2_lib.baseboard_fab2(sch_1):page167_i7"
				( attribute "BOM_COST" "SM_THERM"
					( Origin gFrontEnd )
				)
				( attribute "CDS_LIB" "mstr_discrete"
					( Origin gPackager )
				)
				( attribute "CDS_LOCATION" "C1M4"
					( Origin gPackager )
				)
				( attribute "CDS_SEC" "1"
					( Origin gPackager )
				)
				( attribute "LOCATION" "C1M4"
					( Origin gFrontEnd )
				)
				( attribute "MATERIAL" "EMPTY"
					( Origin gFrontEnd )
				)
				( attribute "PACK_TYPE" "0402LF"
					( Origin gFrontEnd )
				)
				( attribute "PART_NUMBER" "A36095-025"
					( Origin gFrontEnd )
				)
				( attribute "PHYS_PAGE" "167"
					( Origin gFrontEnd )
				)
				( attribute "ROOM" "TEMP_SENSORS"
					( Origin gFrontEnd )
				)
				( attribute "ROT" "0"
					( Origin gFrontEnd )
				)
				( attribute "SEC" "1"
					( Origin gFrontEnd )
				)
				( attribute "SEC_TYPE" "0402LF"
					( Origin gFrontEnd )
				)
				( attribute "TOLERANCE" "5%"
					( Origin gFrontEnd )
				)
				( attribute "VALUE" "47.0PF"
					( Origin gFrontEnd )
				)
				( attribute "VER" "1"
					( Origin gFrontEnd )
				)
				( attribute "VOLTAGE" "50V"
					( Units "uVoltage" "V" 1.000000)
					( Origin gFrontEnd )
				)
				( attribute "XY" "(-4850,4625)"
					( Origin gFrontEnd )
				)
				( attribute "CHIPS_PART_NAME" "CAP"
					( Origin gPackager )
				)
				( attribute "CDS_PART_NAME" "CAP_0402LF-47.0PF,50V,5%,EMPTYA"
					( Origin gPackager )
				)
				( objectStatus "C1M4" )
				( pin "a"
					( attribute "PN" "1"
						( Origin gPackager )
					)
					( objectStatus "C1M4.1" )
				)
				( pin "b"
					( attribute "PN" "2"
						( Origin gPackager )
					)
					( objectStatus "C1M4.2" )
				)
			)
			( gate "@baseboard_fab2_lib.baseboard_fab2(sch_1):page167_i8"
				( attribute "BOM_COST" "SM_THERM"
					( Origin gFrontEnd )
				)
				( attribute "CDS_LIB" "mstr_discrete"
					( Origin gPackager )
				)
				( attribute "CDS_LOCATION" "R1M9"
					( Origin gPackager )
				)
				( attribute "CDS_SEC" "1"
					( Origin gPackager )
				)
				( attribute "LOCATION" "R1M9"
					( Origin gFrontEnd )
				)
				( attribute "MATERIAL" "CHIP"
					( Origin gFrontEnd )
				)
				( attribute "PACK_TYPE" "0402"
					( Origin gFrontEnd )
				)
				( attribute "PART_NUMBER" "G21796-173"
					( Origin gFrontEnd )
				)
				( attribute "PHYS_PAGE" "167"
					( Origin gFrontEnd )
				)
				( attribute "ROOM" "TEMP_SENSORS"
					( Origin gFrontEnd )
				)
				( attribute "ROT" "0"
					( Origin gFrontEnd )
				)
				( attribute "SEC" "1"
					( Origin gFrontEnd )
				)
				( attribute "SEC_TYPE" "0402"
					( Origin gFrontEnd )
				)
				( attribute "TOLERANCE" "1%"
					( Origin gFrontEnd )
				)
				( attribute "VALUE" "20.0"
					( Origin gFrontEnd )
				)
				( attribute "VER" "1"
					( Origin gFrontEnd )
				)
				( attribute "WATTAGE" "1/16W"
					( Origin gFrontEnd )
				)
				( attribute "XY" "(-2950,4500)"
					( Origin gFrontEnd )
				)
				( attribute "CHIPS_PART_NAME" "RES"
					( Origin gPackager )
				)
				( attribute "CDS_PART_NAME" "RES_0402-20.0,1%,1/16W,CHIP,G2A"
					( Origin gPackager )
				)
				( objectStatus "R1M9" )
				( pin "a"
					( attribute "PN" "1"
						( Origin gPackager )
					)
					( objectStatus "R1M9.1" )
				)
				( pin "b"
					( attribute "PN" "2"
						( Origin gPackager )
					)
					( objectStatus "R1M9.2" )
				)
			)
			( gate "@baseboard_fab2_lib.baseboard_fab2(sch_1):page167_i10"
				( attribute "BOM_COST" "SM_THERM"
					( Origin gFrontEnd )
				)
				( attribute "CDS_LIB" "mstr_discrete"
					( Origin gPackager )
				)
				( attribute "CDS_LOCATION" "R9B8"
					( Origin gPackager )
				)
				( attribute "CDS_SEC" "1"
					( Origin gPackager )
				)
				( attribute "LOCATION" "R9B8"
					( Origin gFrontEnd )
				)
				( attribute "MATERIAL" "CHIP"
					( Origin gFrontEnd )
				)
				( attribute "PACK_TYPE" "0402"
					( Origin gFrontEnd )
				)
				( attribute "PART_NUMBER" "G21796-026"
					( Origin gFrontEnd )
				)
				( attribute "PHYS_PAGE" "167"
					( Origin gFrontEnd )
				)
				( attribute "ROOM" "TEMP_SENSORS"
					( Origin gFrontEnd )
				)
				( attribute "ROT" "0"
					( Origin gFrontEnd )
				)
				( attribute "SEC" "1"
					( Origin gFrontEnd )
				)
				( attribute "SEC_TYPE" "0402"
					( Origin gFrontEnd )
				)
				( attribute "TOLERANCE" "1%"
					( Origin gFrontEnd )
				)
				( attribute "VALUE" "1.00K"
					( Origin gFrontEnd )
				)
				( attribute "VER" "2"
					( Origin gFrontEnd )
				)
				( attribute "WATTAGE" "1/16W"
					( Origin gFrontEnd )
				)
				( attribute "XY" "(-4775,4075)"
					( Origin gFrontEnd )
				)
				( attribute "CHIPS_PART_NAME" "RES"
					( Origin gPackager )
				)
				( attribute "CDS_PART_NAME" "RES_0402-1.00K,1%,1/16W,CHIP,GA"
					( Origin gPackager )
				)
				( objectStatus "R9B8" )
				( pin "a"
					( attribute "PN" "1"
						( Origin gPackager )
					)
					( objectStatus "R9B8.1" )
				)
				( pin "b"
					( attribute "PN" "2"
						( Origin gPackager )
					)
					( objectStatus "R9B8.2" )
				)
			)
			( gate "@baseboard_fab2_lib.baseboard_fab2(sch_1):page167_i24"
				( attribute "BOM_COST" "SM_THERM"
					( Origin gFrontEnd )
				)
				( attribute "CDS_LIB" "mstr_discrete"
					( Origin gPackager )
				)
				( attribute "CDS_LOCATION" "C1E19"
					( Origin gPackager )
				)
				( attribute "CDS_SEC" "1"
					( Origin gPackager )
				)
				( attribute "LOCATION" "C1E19"
					( Origin gFrontEnd )
				)
				( attribute "MATERIAL" "EMPTY"
					( Origin gFrontEnd )
				)
				( attribute "PACK_TYPE" "0402LF"
					( Origin gFrontEnd )
				)
				( attribute "PART_NUMBER" "A36095-025"
					( Origin gFrontEnd )
				)
				( attribute "PHYS_PAGE" "167"
					( Origin gFrontEnd )
				)
				( attribute "ROOM" "TEMP_SENSORS"
					( Origin gFrontEnd )
				)
				( attribute "ROT" "0"
					( Origin gFrontEnd )
				)
				( attribute "SEC" "1"
					( Origin gFrontEnd )
				)
				( attribute "SEC_TYPE" "0402LF"
					( Origin gFrontEnd )
				)
				( attribute "TOLERANCE" "5%"
					( Origin gFrontEnd )
				)
				( attribute "VALUE" "47.0PF"
					( Origin gFrontEnd )
				)
				( attribute "VER" "1"
					( Origin gFrontEnd )
				)
				( attribute "VOLTAGE" "50V"
					( Units "uVoltage" "V" 1.000000)
					( Origin gFrontEnd )
				)
				( attribute "XY" "(-4675,3175)"
					( Origin gFrontEnd )
				)
				( attribute "CHIPS_PART_NAME" "CAP"
					( Origin gPackager )
				)
				( attribute "CDS_PART_NAME" "CAP_0402LF-47.0PF,50V,5%,EMPTYA"
					( Origin gPackager )
				)
				( objectStatus "C1E19" )
				( pin "a"
					( attribute "PN" "1"
						( Origin gPackager )
					)
					( objectStatus "C1E19.1" )
				)
				( pin "b"
					( attribute "PN" "2"
						( Origin gPackager )
					)
					( objectStatus "C1E19.2" )
				)
			)
			( gate "@baseboard_fab2_lib.baseboard_fab2(sch_1):page167_i25"
				( attribute "BOM_COST" "SM_THERM"
					( Origin gFrontEnd )
				)
				( attribute "CDS_LIB" "mstr_discrete"
					( Origin gPackager )
				)
				( attribute "CDS_LOCATION" "R9R5"
					( Origin gPackager )
				)
				( attribute "CDS_SEC" "1"
					( Origin gPackager )
				)
				( attribute "LOCATION" "R9R5"
					( Origin gFrontEnd )
				)
				( attribute "MATERIAL" "CHIP"
					( Origin gFrontEnd )
				)
				( attribute "PACK_TYPE" "0402"
					( Origin gFrontEnd )
				)
				( attribute "PART_NUMBER" "G21796-047"
					( Origin gFrontEnd )
				)
				( attribute "PHYS_PAGE" "167"
					( Origin gFrontEnd )
				)
				( attribute "ROOM" "TEMP_SENSORS"
					( Origin gFrontEnd )
				)
				( attribute "ROT" "0"
					( Origin gFrontEnd )
				)
				( attribute "SEC" "1"
					( Origin gFrontEnd )
				)
				( attribute "SEC_TYPE" "0402"
					( Origin gFrontEnd )
				)
				( attribute "TOLERANCE" "1%"
					( Origin gFrontEnd )
				)
				( attribute "VALUE" "49.9"
					( Origin gFrontEnd )
				)
				( attribute "VER" "1"
					( Origin gFrontEnd )
				)
				( attribute "WATTAGE" "1/16W"
					( Origin gFrontEnd )
				)
				( attribute "XY" "(-5000,3325)"
					( Origin gFrontEnd )
				)
				( attribute "CHIPS_PART_NAME" "RES"
					( Origin gPackager )
				)
				( attribute "CDS_PART_NAME" "RES_0402-49.9,1%,1/16W,CHIP,G2A"
					( Origin gPackager )
				)
				( objectStatus "R9R5" )
				( pin "a"
					( attribute "PN" "1"
						( Origin gPackager )
					)
					( objectStatus "R9R5.1" )
				)
				( pin "b"
					( attribute "PN" "2"
						( Origin gPackager )
					)
					( objectStatus "R9R5.2" )
				)
			)
			( gate "@baseboard_fab2_lib.baseboard_fab2(sch_1):page167_i26"
				( attribute "BOM_COST" "SM_THERM"
					( Origin gFrontEnd )
				)
				( attribute "CDS_LIB" "mstr_discrete"
					( Origin gPackager )
				)
				( attribute "CDS_LOCATION" "R9R6"
					( Origin gPackager )
				)
				( attribute "CDS_SEC" "1"
					( Origin gPackager )
				)
				( attribute "LOCATION" "R9R6"
					( Origin gFrontEnd )
				)
				( attribute "MATERIAL" "CHIP"
					( Origin gFrontEnd )
				)
				( attribute "PACK_TYPE" "0402"
					( Origin gFrontEnd )
				)
				( attribute "PART_NUMBER" "G21796-047"
					( Origin gFrontEnd )
				)
				( attribute "PHYS_PAGE" "167"
					( Origin gFrontEnd )
				)
				( attribute "ROOM" "TEMP_SENSORS"
					( Origin gFrontEnd )
				)
				( attribute "ROT" "0"
					( Origin gFrontEnd )
				)
				( attribute "SEC" "1"
					( Origin gFrontEnd )
				)
				( attribute "SEC_TYPE" "0402"
					( Origin gFrontEnd )
				)
				( attribute "TOLERANCE" "1%"
					( Origin gFrontEnd )
				)
				( attribute "VALUE" "49.9"
					( Origin gFrontEnd )
				)
				( attribute "VER" "1"
					( Origin gFrontEnd )
				)
				( attribute "WATTAGE" "1/16W"
					( Origin gFrontEnd )
				)
				( attribute "XY" "(-4975,3000)"
					( Origin gFrontEnd )
				)
				( attribute "CHIPS_PART_NAME" "RES"
					( Origin gPackager )
				)
				( attribute "CDS_PART_NAME" "RES_0402-49.9,1%,1/16W,CHIP,G2A"
					( Origin gPackager )
				)
				( objectStatus "R9R6" )
				( pin "a"
					( attribute "PN" "1"
						( Origin gPackager )
					)
					( objectStatus "R9R6.1" )
				)
				( pin "b"
					( attribute "PN" "2"
						( Origin gPackager )
					)
					( objectStatus "R9R6.2" )
				)
			)
			( gate "@baseboard_fab2_lib.baseboard_fab2(sch_1):page167_i27"
				( attribute "BOM_COST" "SM_THERM"
					( Origin gFrontEnd )
				)
				( attribute "CDS_LIB" "mstr_discrete"
					( Origin gPackager )
				)
				( attribute "CDS_LOCATION" "Q1E1"
					( Origin gPackager )
				)
				( attribute "CDS_SEC" "1"
					( Origin gPackager )
				)
				( attribute "LOCATION" "Q1E1"
					( Origin gFrontEnd )
				)
				( attribute "MATERIAL" "IC"
					( Origin gFrontEnd )
				)
				( attribute "PACK_TYPE" "TO92"
					( Origin gFrontEnd )
				)
				( attribute "PART_NUMBER" "G73554-001"
					( Origin gFrontEnd )
				)
				( attribute "PHYS_PAGE" "167"
					( Origin gFrontEnd )
				)
				( attribute "ROOM" "TEMP_SENSORS"
					( Origin gFrontEnd )
				)
				( attribute "ROT" "0"
					( Origin gFrontEnd )
				)
				( attribute "SEC" "1"
					( Origin gFrontEnd )
				)
				( attribute "SEC_TYPE" "TO92"
					( Origin gFrontEnd )
				)
				( attribute "VALUE" "MPS2907"
					( Origin gFrontEnd )
				)
				( attribute "VER" "3"
					( Origin gFrontEnd )
				)
				( attribute "XY" "(-5700,3150)"
					( Origin gFrontEnd )
				)
				( attribute "CHIPS_PART_NAME" "PNP"
					( Origin gPackager )
				)
				( attribute "CDS_PART_NAME" "PNP_TO92-MPS2907,IC,G73554-001"
					( Origin gPackager )
				)
				( objectStatus "Q1E1" )
				( pin "b"
					( attribute "PN" "1"
						( Origin gPackager )
					)
					( objectStatus "Q1E1.1" )
				)
				( pin "c"
					( attribute "PN" "3"
						( Origin gPackager )
					)
					( objectStatus "Q1E1.3" )
				)
				( pin "e"
					( attribute "PN" "2"
						( Origin gPackager )
					)
					( objectStatus "Q1E1.2" )
				)
			)
			( gate "@baseboard_fab2_lib.baseboard_fab2(sch_1):page167_i30"
				( attribute "BOM_COST" "SM_THERM"
					( Origin gFrontEnd )
				)
				( attribute "CDS_LIB" "mstr_analog"
					( Origin gPackager )
				)
				( attribute "CDS_LOCATION" "U1E1"
					( Origin gPackager )
				)
				( attribute "CDS_SEC" "1"
					( Origin gPackager )
				)
				( attribute "LOCATION" "U1E1"
					( Origin gFrontEnd )
				)
				( attribute "MATERIAL" "IC"
					( Origin gFrontEnd )
				)
				( attribute "PACK_TYPE" "TSSOP"
					( Origin gFrontEnd )
				)
				( attribute "PART_NUMBER" "G62962-001"
					( Origin gFrontEnd )
				)
				( attribute "PHYS_PAGE" "167"
					( Origin gFrontEnd )
				)
				( attribute "ROOM" "TEMP_SENSORS"
					( Origin gFrontEnd )
				)
				( attribute "ROT" "0"
					( Origin gFrontEnd )
				)
				( attribute "SEC" "1"
					( Origin gFrontEnd )
				)
				( attribute "SEC_TYPE" "TSSOP"
					( Origin gFrontEnd )
				)
				( attribute "VER" "1"
					( Origin gFrontEnd )
				)
				( attribute "XY" "(-3825,3000)"
					( Origin gFrontEnd )
				)
				( attribute "CHIPS_PART_NAME" "TMP421"
					( Origin gPackager )
				)
				( attribute "CDS_PART_NAME" "TMP421_TSSOP-IC,G62962-001"
					( Origin gPackager )
				)
				( objectStatus "U1E1" )
				( pin "a(0)"
					( attribute "PN" "4"
						( Origin gPackager )
					)
					( objectStatus "U1E1.4" )
				)
				( pin "a(1)"
					( attribute "PN" "3"
						( Origin gPackager )
					)
					( objectStatus "U1E1.3" )
				)
				( pin "dxn"
					( attribute "PN" "2"
						( Origin gPackager )
					)
					( objectStatus "U1E1.2" )
				)
				( pin "dxp"
					( attribute "PN" "1"
						( Origin gPackager )
					)
					( objectStatus "U1E1.1" )
				)
				( pin "gnd"
					( attribute "PN" "5"
						( Origin gPackager )
					)
					( objectStatus "U1E1.5" )
				)
				( pin "scl"
					( attribute "PN" "7"
						( Origin gPackager )
					)
					( objectStatus "U1E1.7" )
				)
				( pin "sda"
					( attribute "PN" "6"
						( Origin gPackager )
					)
					( objectStatus "U1E1.6" )
				)
				( pin "vp"
					( attribute "PN" "8"
						( Origin gPackager )
					)
					( objectStatus "U1E1.8" )
				)
			)
			( gate "@baseboard_fab2_lib.baseboard_fab2(sch_1):page167_i34"
				( attribute "BOM_COST" "SM_THERM"
					( Origin gFrontEnd )
				)
				( attribute "CDS_LIB" "mstr_discrete"
					( Origin gPackager )
				)
				( attribute "CDS_LOCATION" "R1E9"
					( Origin gPackager )
				)
				( attribute "CDS_SEC" "1"
					( Origin gPackager )
				)
				( attribute "LOCATION" "R1E9"
					( Origin gFrontEnd )
				)
				( attribute "MATERIAL" "CHIP"
					( Origin gFrontEnd )
				)
				( attribute "PACK_TYPE" "0402"
					( Origin gFrontEnd )
				)
				( attribute "PART_NUMBER" "G21796-026"
					( Origin gFrontEnd )
				)
				( attribute "PHYS_PAGE" "167"
					( Origin gFrontEnd )
				)
				( attribute "ROOM" "TEMP_SENSORS"
					( Origin gFrontEnd )
				)
				( attribute "ROT" "0"
					( Origin gFrontEnd )
				)
				( attribute "SEC" "1"
					( Origin gFrontEnd )
				)
				( attribute "SEC_TYPE" "0402"
					( Origin gFrontEnd )
				)
				( attribute "TOLERANCE" "1%"
					( Origin gFrontEnd )
				)
				( attribute "VALUE" "1.00K"
					( Origin gFrontEnd )
				)
				( attribute "VER" "1"
					( Origin gFrontEnd )
				)
				( attribute "WATTAGE" "1/16W"
					( Origin gFrontEnd )
				)
				( attribute "XY" "(-5050,2850)"
					( Origin gFrontEnd )
				)
				( attribute "CHIPS_PART_NAME" "RES"
					( Origin gPackager )
				)
				( attribute "CDS_PART_NAME" "RES_0402-1.00K,1%,1/16W,CHIP,GA"
					( Origin gPackager )
				)
				( objectStatus "R1E9" )
				( pin "a"
					( attribute "PN" "1"
						( Origin gPackager )
					)
					( objectStatus "R1E9.1" )
				)
				( pin "b"
					( attribute "PN" "2"
						( Origin gPackager )
					)
					( objectStatus "R1E9.2" )
				)
			)
			( gate "@baseboard_fab2_lib.baseboard_fab2(sch_1):page167_i35"
				( attribute "BOM_COST" "SM_THERM"
					( Origin gFrontEnd )
				)
				( attribute "CDS_LIB" "mstr_discrete"
					( Origin gPackager )
				)
				( attribute "CDS_LOCATION" "R9B6"
					( Origin gPackager )
				)
				( attribute "CDS_SEC" "1"
					( Origin gPackager )
				)
				( attribute "LOCATION" "R9B6"
					( Origin gFrontEnd )
				)
				( attribute "MATERIAL" "CHIP"
					( Origin gFrontEnd )
				)
				( attribute "PACK_TYPE" "0402"
					( Origin gFrontEnd )
				)
				( attribute "PART_NUMBER" "G21796-026"
					( Origin gFrontEnd )
				)
				( attribute "PHYS_PAGE" "167"
					( Origin gFrontEnd )
				)
				( attribute "ROOM" "TEMP_SENSORS"
					( Origin gFrontEnd )
				)
				( attribute "ROT" "0"
					( Origin gFrontEnd )
				)
				( attribute "SEC" "1"
					( Origin gFrontEnd )
				)
				( attribute "SEC_TYPE" "0402"
					( Origin gFrontEnd )
				)
				( attribute "TOLERANCE" "1%"
					( Origin gFrontEnd )
				)
				( attribute "VALUE" "1.00K"
					( Origin gFrontEnd )
				)
				( attribute "VER" "1"
					( Origin gFrontEnd )
				)
				( attribute "WATTAGE" "1/16W"
					( Origin gFrontEnd )
				)
				( attribute "XY" "(-5450,4350)"
					( Origin gFrontEnd )
				)
				( attribute "CHIPS_PART_NAME" "RES"
					( Origin gPackager )
				)
				( attribute "CDS_PART_NAME" "RES_0402-1.00K,1%,1/16W,CHIP,GA"
					( Origin gPackager )
				)
				( objectStatus "R9B6" )
				( pin "a"
					( attribute "PN" "1"
						( Origin gPackager )
					)
					( objectStatus "R9B6.1" )
				)
				( pin "b"
					( attribute "PN" "2"
						( Origin gPackager )
					)
					( objectStatus "R9B6.2" )
				)
			)
			( gate "@baseboard_fab2_lib.baseboard_fab2(sch_1):page167_i38"
				( attribute "BOM_COST" "SM_THERM"
					( Origin gFrontEnd )
				)
				( attribute "CDS_LIB" "mstr_discrete"
					( Origin gPackager )
				)
				( attribute "CDS_LOCATION" "R1E10"
					( Origin gPackager )
				)
				( attribute "CDS_SEC" "1"
					( Origin gPackager )
				)
				( attribute "LOCATION" "R1E10"
					( Origin gFrontEnd )
				)
				( attribute "MATERIAL" "CHIP"
					( Origin gFrontEnd )
				)
				( attribute "PACK_TYPE" "0402"
					( Origin gFrontEnd )
				)
				( attribute "PART_NUMBER" "G21796-026"
					( Origin gFrontEnd )
				)
				( attribute "PHYS_PAGE" "167"
					( Origin gFrontEnd )
				)
				( attribute "ROOM" "TEMP_SENSORS"
					( Origin gFrontEnd )
				)
				( attribute "ROT" "0"
					( Origin gFrontEnd )
				)
				( attribute "SEC" "1"
					( Origin gFrontEnd )
				)
				( attribute "SEC_TYPE" "0402"
					( Origin gFrontEnd )
				)
				( attribute "TOLERANCE" "1%"
					( Origin gFrontEnd )
				)
				( attribute "VALUE" "1.00K"
					( Origin gFrontEnd )
				)
				( attribute "VER" "1"
					( Origin gFrontEnd )
				)
				( attribute "WATTAGE" "1/16W"
					( Origin gFrontEnd )
				)
				( attribute "XY" "(-4650,2900)"
					( Origin gFrontEnd )
				)
				( attribute "CHIPS_PART_NAME" "RES"
					( Origin gPackager )
				)
				( attribute "CDS_PART_NAME" "RES_0402-1.00K,1%,1/16W,CHIP,GA"
					( Origin gPackager )
				)
				( objectStatus "R1E10" )
				( pin "a"
					( attribute "PN" "1"
						( Origin gPackager )
					)
					( objectStatus "R1E10.1" )
				)
				( pin "b"
					( attribute "PN" "2"
						( Origin gPackager )
					)
					( objectStatus "R1E10.2" )
				)
			)
			( gate "@baseboard_fab2_lib.baseboard_fab2(sch_1):page167_i39"
				( attribute "BOM_COST" "SM_THERM"
					( Origin gFrontEnd )
				)
				( attribute "CDS_LIB" "dev_discrete"
					( Origin gPackager )
				)
				( attribute "CDS_LOCATION" "C9B7"
					( Origin gPackager )
				)
				( attribute "CDS_SEC" "1"
					( Origin gPackager )
				)
				( attribute "LOCATION" "C9B7"
					( Origin gFrontEnd )
				)
				( attribute "MATERIAL" "X7R"
					( Origin gFrontEnd )
				)
				( attribute "PACK_TYPE" "0402V"
					( Origin gFrontEnd )
				)
				( attribute "PART_NUMBER" "A36096-030"
					( Origin gFrontEnd )
				)
				( attribute "PHYS_PAGE" "167"
					( Origin gFrontEnd )
				)
				( attribute "ROOM" "TEMP_SENSORS"
					( Origin gFrontEnd )
				)
				( attribute "ROT" "0"
					( Origin gFrontEnd )
				)
				( attribute "SEC" "1"
					( Origin gFrontEnd )
				)
				( attribute "SEC_TYPE" "0402V"
					( Origin gFrontEnd )
				)
				( attribute "TOLERANCE" "10%"
					( Origin gFrontEnd )
				)
				( attribute "VALUE" "0.1UF"
					( Origin gFrontEnd )
				)
				( attribute "VER" "1"
					( Origin gFrontEnd )
				)
				( attribute "VOLTAGE" "16V"
					( Units "uVoltage" "V" 1.000000)
					( Origin gFrontEnd )
				)
				( attribute "XY" "(-7700,4350)"
					( Origin gFrontEnd )
				)
				( attribute "CHIPS_PART_NAME" "CAP_A"
					( Origin gPackager )
				)
				( attribute "CDS_PART_NAME" "CAP_A_0402V-0.1UF,16V,10%,X7R,A"
					( Origin gPackager )
				)
				( objectStatus "C9B7" )
				( pin "a"
					( attribute "PN" "1"
						( Origin gPackager )
					)
					( objectStatus "C9B7.1" )
				)
				( pin "b"
					( attribute "PN" "2"
						( Origin gPackager )
					)
					( objectStatus "C9B7.2" )
				)
			)
			( gate "@baseboard_fab2_lib.baseboard_fab2(sch_1):page167_i41"
				( attribute "BOM_COST" "SM_THERM"
					( Origin gFrontEnd )
				)
				( attribute "CDS_LIB" "dev_discrete"
					( Origin gPackager )
				)
				( attribute "CDS_LOCATION" "C9R14"
					( Origin gPackager )
				)
				( attribute "CDS_SEC" "1"
					( Origin gPackager )
				)
				( attribute "LOCATION" "C9R14"
					( Origin gFrontEnd )
				)
				( attribute "MATERIAL" "X7R"
					( Origin gFrontEnd )
				)
				( attribute "PACK_TYPE" "0402V"
					( Origin gFrontEnd )
				)
				( attribute "PART_NUMBER" "A36096-030"
					( Origin gFrontEnd )
				)
				( attribute "PHYS_PAGE" "167"
					( Origin gFrontEnd )
				)
				( attribute "ROOM" "TEMP_SENSORS"
					( Origin gFrontEnd )
				)
				( attribute "ROT" "0"
					( Origin gFrontEnd )
				)
				( attribute "SEC" "1"
					( Origin gFrontEnd )
				)
				( attribute "SEC_TYPE" "0402V"
					( Origin gFrontEnd )
				)
				( attribute "TOLERANCE" "10%"
					( Origin gFrontEnd )
				)
				( attribute "VALUE" "0.1UF"
					( Origin gFrontEnd )
				)
				( attribute "VER" "1"
					( Origin gFrontEnd )
				)
				( attribute "VOLTAGE" "16V"
					( Units "uVoltage" "V" 1.000000)
					( Origin gFrontEnd )
				)
				( attribute "XY" "(-7700,3675)"
					( Origin gFrontEnd )
				)
				( attribute "CHIPS_PART_NAME" "CAP_A"
					( Origin gPackager )
				)
				( attribute "CDS_PART_NAME" "CAP_A_0402V-0.1UF,16V,10%,X7R,A"
					( Origin gPackager )
				)
				( objectStatus "C9R14" )
				( pin "a"
					( attribute "PN" "1"
						( Origin gPackager )
					)
					( objectStatus "C9R14.1" )
				)
				( pin "b"
					( attribute "PN" "2"
						( Origin gPackager )
					)
					( objectStatus "C9R14.2" )
				)
			)
			( gate "@baseboard_fab2_lib.baseboard_fab2(sch_1):page167_i42"
				( attribute "BOM_COST" "SM_THERM"
					( Origin gFrontEnd )
				)
				( attribute "CDS_LIB" "dev_discrete"
					( Origin gPackager )
				)
				( attribute "CDS_LOCATION" "C9R13"
					( Origin gPackager )
				)
				( attribute "CDS_SEC" "1"
					( Origin gPackager )
				)
				( attribute "LOCATION" "C9R13"
					( Origin gFrontEnd )
				)
				( attribute "MATERIAL" "X7R"
					( Origin gFrontEnd )
				)
				( attribute "PACK_TYPE" "0402V"
					( Origin gFrontEnd )
				)
				( attribute "PART_NUMBER" "A36096-030"
					( Origin gFrontEnd )
				)
				( attribute "PHYS_PAGE" "167"
					( Origin gFrontEnd )
				)
				( attribute "ROOM" "TEMP_SENSORS"
					( Origin gFrontEnd )
				)
				( attribute "ROT" "0"
					( Origin gFrontEnd )
				)
				( attribute "SEC" "1"
					( Origin gFrontEnd )
				)
				( attribute "SEC_TYPE" "0402V"
					( Origin gFrontEnd )
				)
				( attribute "TOLERANCE" "10%"
					( Origin gFrontEnd )
				)
				( attribute "VALUE" "0.1UF"
					( Origin gFrontEnd )
				)
				( attribute "VER" "1"
					( Origin gFrontEnd )
				)
				( attribute "VOLTAGE" "16V"
					( Units "uVoltage" "V" 1.000000)
					( Origin gFrontEnd )
				)
				( attribute "XY" "(-1425,2150)"
					( Origin gFrontEnd )
				)
				( attribute "CHIPS_PART_NAME" "CAP_A"
					( Origin gPackager )
				)
				( attribute "CDS_PART_NAME" "CAP_A_0402V-0.1UF,16V,10%,X7R,A"
					( Origin gPackager )
				)
				( objectStatus "C9R13" )
				( pin "a"
					( attribute "PN" "1"
						( Origin gPackager )
					)
					( objectStatus "C9R13.1" )
				)
				( pin "b"
					( attribute "PN" "2"
						( Origin gPackager )
					)
					( objectStatus "C9R13.2" )
				)
			)
			( gate "@baseboard_fab2_lib.baseboard_fab2(sch_1):page167_i49"
				( attribute "BOM_COST" "SM_THERM"
					( Origin gFrontEnd )
				)
				( attribute "CDS_LIB" "mstr_memory"
					( Origin gPackager )
				)
				( attribute "CDS_LOCATION" "U8D4"
					( Origin gPackager )
				)
				( attribute "CDS_SEC" "1"
					( Origin gPackager )
				)
				( attribute "LOCATION" "U8D4"
					( Origin gFrontEnd )
				)
				( attribute "MATERIAL" "IC"
					( Origin gFrontEnd )
				)
				( attribute "PACK_TYPE" "SOICLF"
					( Origin gFrontEnd )
				)
				( attribute "PART_NUMBER" "C47049-001"
					( Origin gFrontEnd )
				)
				( attribute "PHYS_PAGE" "167"
					( Origin gFrontEnd )
				)
				( attribute "ROOM" "TEMP_SENSORS"
					( Origin gFrontEnd )
				)
				( attribute "ROT" "0"
					( Origin gFrontEnd )
				)
				( attribute "SEC" "1"
					( Origin gFrontEnd )
				)
				( attribute "SEC_TYPE" "SOICLF"
					( Origin gFrontEnd )
				)
				( attribute "VER" "1"
					( Origin gFrontEnd )
				)
				( attribute "XY" "(-2700,1650)"
					( Origin gFrontEnd )
				)
				( attribute "CHIPS_PART_NAME" "AT24C64"
					( Origin gPackager )
				)
				( attribute "CDS_PART_NAME" "AT24C64_SOICLF-IC,C47049-001-VA"
					( Origin gPackager )
				)
				( objectStatus "U8D4" )
				( pin "a0"
					( attribute "PN" "1"
						( Origin gPackager )
					)
					( objectStatus "U8D4.1" )
				)
				( pin "a1"
					( attribute "PN" "2"
						( Origin gPackager )
					)
					( objectStatus "U8D4.2" )
				)
				( pin "a2"
					( attribute "PN" "3"
						( Origin gPackager )
					)
					( objectStatus "U8D4.3" )
				)
				( pin "scl"
					( attribute "PN" "6"
						( Origin gPackager )
					)
					( objectStatus "U8D4.6" )
				)
				( pin "sda"
					( attribute "PN" "5"
						( Origin gPackager )
					)
					( objectStatus "U8D4.5" )
				)
				( pin "wp"
					( attribute "PN" "7"
						( Origin gPackager )
					)
					( objectStatus "U8D4.7" )
				)
			)
			( gate "@baseboard_fab2_lib.baseboard_fab2(sch_1):page167_i50"
				( attribute "BOM_COST" "SM_THERM"
					( Origin gFrontEnd )
				)
				( attribute "CDS_LIB" "mstr_discrete"
					( Origin gPackager )
				)
				( attribute "CDS_LOCATION" "R8D27"
					( Origin gPackager )
				)
				( attribute "CDS_SEC" "1"
					( Origin gPackager )
				)
				( attribute "LOCATION" "R8D27"
					( Origin gFrontEnd )
				)
				( attribute "MATERIAL" "CHIP"
					( Origin gFrontEnd )
				)
				( attribute "PACK_TYPE" "0402"
					( Origin gFrontEnd )
				)
				( attribute "PART_NUMBER" "G21796-026"
					( Origin gFrontEnd )
				)
				( attribute "PHYS_PAGE" "167"
					( Origin gFrontEnd )
				)
				( attribute "ROOM" "TEMP_SENSORS"
					( Origin gFrontEnd )
				)
				( attribute "ROT" "0"
					( Origin gFrontEnd )
				)
				( attribute "SEC" "1"
					( Origin gFrontEnd )
				)
				( attribute "SEC_TYPE" "0402"
					( Origin gFrontEnd )
				)
				( attribute "TOLERANCE" "1%"
					( Origin gFrontEnd )
				)
				( attribute "VALUE" "1.00K"
					( Origin gFrontEnd )
				)
				( attribute "VER" "2"
					( Origin gFrontEnd )
				)
				( attribute "WATTAGE" "1/16W"
					( Origin gFrontEnd )
				)
				( attribute "XY" "(-3500,1300)"
					( Origin gFrontEnd )
				)
				( attribute "CHIPS_PART_NAME" "RES"
					( Origin gPackager )
				)
				( attribute "CDS_PART_NAME" "RES_0402-1.00K,1%,1/16W,CHIP,GA"
					( Origin gPackager )
				)
				( objectStatus "R8D27" )
				( pin "a"
					( attribute "PN" "1"
						( Origin gPackager )
					)
					( objectStatus "R8D27.1" )
				)
				( pin "b"
					( attribute "PN" "2"
						( Origin gPackager )
					)
					( objectStatus "R8D27.2" )
				)
			)
			( gate "@baseboard_fab2_lib.baseboard_fab2(sch_1):page167_i58"
				( attribute "BOM_COST" "SM_CONTROLLER"
					( Origin gFrontEnd )
				)
				( attribute "CDS_LIB" "mstr_discrete"
					( Origin gPackager )
				)
				( attribute "CDS_LOCATION" "R9G15"
					( Origin gPackager )
				)
				( attribute "CDS_SEC" "1"
					( Origin gPackager )
				)
				( attribute "LOCATION" "R9G15"
					( Origin gFrontEnd )
				)
				( attribute "MATERIAL" "CHIP"
					( Origin gFrontEnd )
				)
				( attribute "PACK_TYPE" "0402"
					( Origin gFrontEnd )
				)
				( attribute "PART_NUMBER" "G21796-173"
					( Origin gFrontEnd )
				)
				( attribute "PHYS_PAGE" "167"
					( Origin gFrontEnd )
				)
				( attribute "ROOM" "SMBUS"
					( Origin gFrontEnd )
				)
				( attribute "ROT" "0"
					( Origin gFrontEnd )
				)
				( attribute "SEC" "1"
					( Origin gPackager )
				)
				( attribute "SKU" "B"
					( Origin gFrontEnd )
				)
				( attribute "TOLERANCE" "1%"
					( Origin gFrontEnd )
				)
				( attribute "VALUE" "20.0"
					( Origin gFrontEnd )
				)
				( attribute "VER" "1"
					( Origin gFrontEnd )
				)
				( attribute "WATTAGE" "1/16W"
					( Origin gFrontEnd )
				)
				( attribute "XY" "(-6725,1450)"
					( Origin gFrontEnd )
				)
				( attribute "CHIPS_PART_NAME" "RES"
					( Origin gPackager )
				)
				( attribute "CDS_PART_NAME" "RES_0402-20.0,1%,1/16W,CHIP,G2A"
					( Origin gPackager )
				)
				( objectStatus "R9G15" )
				( pin "a"
					( attribute "PN" "1"
						( Origin gPackager )
					)
					( objectStatus "R9G15.1" )
				)
				( pin "b"
					( attribute "PN" "2"
						( Origin gPackager )
					)
					( objectStatus "R9G15.2" )
				)
			)
			( gate "@baseboard_fab2_lib.baseboard_fab2(sch_1):page167_i70"
				( attribute "BOM_COST" "SM_THERM"
					( Origin gFrontEnd )
				)
				( attribute "CDS_LIB" "mstr_discrete"
					( Origin gPackager )
				)
				( attribute "CDS_LOCATION" "R8D28"
					( Origin gPackager )
				)
				( attribute "CDS_SEC" "1"
					( Origin gPackager )
				)
				( attribute "LOCATION" "R8D28"
					( Origin gFrontEnd )
				)
				( attribute "MATERIAL" "CHIP"
					( Origin gFrontEnd )
				)
				( attribute "PACK_TYPE" "0402"
					( Origin gFrontEnd )
				)
				( attribute "PART_NUMBER" "G21796-026"
					( Origin gFrontEnd )
				)
				( attribute "PHYS_PAGE" "167"
					( Origin gFrontEnd )
				)
				( attribute "ROOM" "TEMP_SENSORS"
					( Origin gFrontEnd )
				)
				( attribute "ROT" "0"
					( Origin gFrontEnd )
				)
				( attribute "SEC" "1"
					( Origin gFrontEnd )
				)
				( attribute "SEC_TYPE" "0402"
					( Origin gFrontEnd )
				)
				( attribute "TOLERANCE" "1%"
					( Origin gFrontEnd )
				)
				( attribute "VALUE" "1.00K"
					( Origin gFrontEnd )
				)
				( attribute "VER" "2"
					( Origin gFrontEnd )
				)
				( attribute "WATTAGE" "1/16W"
					( Origin gFrontEnd )
				)
				( attribute "XY" "(-3350,1975)"
					( Origin gFrontEnd )
				)
				( attribute "CHIPS_PART_NAME" "RES"
					( Origin gPackager )
				)
				( attribute "CDS_PART_NAME" "RES_0402-1.00K,1%,1/16W,CHIP,GA"
					( Origin gPackager )
				)
				( objectStatus "R8D28" )
				( pin "a"
					( attribute "PN" "1"
						( Origin gPackager )
					)
					( objectStatus "R8D28.1" )
				)
				( pin "b"
					( attribute "PN" "2"
						( Origin gPackager )
					)
					( objectStatus "R8D28.2" )
				)
			)
			( gate "@baseboard_fab2_lib.baseboard_fab2(sch_1):page167_i74"
				( attribute "BOM_COST" "SM_THERM"
					( Origin gFrontEnd )
				)
				( attribute "CDS_LIB" "mstr_discrete"
					( Origin gPackager )
				)
				( attribute "CDS_LOCATION" "R1M8"
					( Origin gPackager )
				)
				( attribute "CDS_SEC" "1"
					( Origin gPackager )
				)
				( attribute "LOCATION" "R1M8"
					( Origin gFrontEnd )
				)
				( attribute "MATERIAL" "CHIP"
					( Origin gFrontEnd )
				)
				( attribute "PACK_TYPE" "0402"
					( Origin gFrontEnd )
				)
				( attribute "PART_NUMBER" "G21796-173"
					( Origin gFrontEnd )
				)
				( attribute "PHYS_PAGE" "167"
					( Origin gFrontEnd )
				)
				( attribute "ROOM" "TEMP_SENSORS"
					( Origin gFrontEnd )
				)
				( attribute "ROT" "0"
					( Origin gFrontEnd )
				)
				( attribute "SEC" "1"
					( Origin gFrontEnd )
				)
				( attribute "SEC_TYPE" "0402"
					( Origin gFrontEnd )
				)
				( attribute "TOLERANCE" "1%"
					( Origin gFrontEnd )
				)
				( attribute "VALUE" "20.0"
					( Origin gFrontEnd )
				)
				( attribute "VER" "1"
					( Origin gFrontEnd )
				)
				( attribute "WATTAGE" "1/16W"
					( Origin gFrontEnd )
				)
				( attribute "XY" "(-2650,4450)"
					( Origin gFrontEnd )
				)
				( attribute "CHIPS_PART_NAME" "RES"
					( Origin gPackager )
				)
				( attribute "CDS_PART_NAME" "RES_0402-20.0,1%,1/16W,CHIP,G2A"
					( Origin gPackager )
				)
				( objectStatus "R1M8" )
				( pin "a"
					( attribute "PN" "1"
						( Origin gPackager )
					)
					( objectStatus "R1M8.1" )
				)
				( pin "b"
					( attribute "PN" "2"
						( Origin gPackager )
					)
					( objectStatus "R1M8.2" )
				)
			)
			( gate "@baseboard_fab2_lib.baseboard_fab2(sch_1):page167_i75"
				( attribute "BOM_COST" "SM_THERM"
					( Origin gFrontEnd )
				)
				( attribute "CDS_LIB" "mstr_discrete"
					( Origin gPackager )
				)
				( attribute "CDS_LOCATION" "R9R7"
					( Origin gPackager )
				)
				( attribute "CDS_SEC" "1"
					( Origin gPackager )
				)
				( attribute "LOCATION" "R9R7"
					( Origin gFrontEnd )
				)
				( attribute "MATERIAL" "CHIP"
					( Origin gFrontEnd )
				)
				( attribute "PACK_TYPE" "0402"
					( Origin gFrontEnd )
				)
				( attribute "PART_NUMBER" "G21796-173"
					( Origin gFrontEnd )
				)
				( attribute "PHYS_PAGE" "167"
					( Origin gFrontEnd )
				)
				( attribute "ROOM" "TEMP_SENSORS"
					( Origin gFrontEnd )
				)
				( attribute "ROT" "0"
					( Origin gFrontEnd )
				)
				( attribute "SEC" "1"
					( Origin gFrontEnd )
				)
				( attribute "SEC_TYPE" "0402"
					( Origin gFrontEnd )
				)
				( attribute "TOLERANCE" "1%"
					( Origin gFrontEnd )
				)
				( attribute "VALUE" "20.0"
					( Origin gFrontEnd )
				)
				( attribute "VER" "1"
					( Origin gFrontEnd )
				)
				( attribute "WATTAGE" "1/16W"
					( Origin gFrontEnd )
				)
				( attribute "XY" "(-2300,3000)"
					( Origin gFrontEnd )
				)
				( attribute "CHIPS_PART_NAME" "RES"
					( Origin gPackager )
				)
				( attribute "CDS_PART_NAME" "RES_0402-20.0,1%,1/16W,CHIP,G2A"
					( Origin gPackager )
				)
				( objectStatus "R9R7" )
				( pin "a"
					( attribute "PN" "1"
						( Origin gPackager )
					)
					( objectStatus "R9R7.1" )
				)
				( pin "b"
					( attribute "PN" "2"
						( Origin gPackager )
					)
					( objectStatus "R9R7.2" )
				)
			)
			( gate "@baseboard_fab2_lib.baseboard_fab2(sch_1):page167_i76"
				( attribute "BOM_COST" "SM_THERM"
					( Origin gFrontEnd )
				)
				( attribute "CDS_LIB" "mstr_discrete"
					( Origin gPackager )
				)
				( attribute "CDS_LOCATION" "R9R8"
					( Origin gPackager )
				)
				( attribute "CDS_SEC" "1"
					( Origin gPackager )
				)
				( attribute "LOCATION" "R9R8"
					( Origin gFrontEnd )
				)
				( attribute "MATERIAL" "CHIP"
					( Origin gFrontEnd )
				)
				( attribute "PACK_TYPE" "0402"
					( Origin gFrontEnd )
				)
				( attribute "PART_NUMBER" "G21796-173"
					( Origin gFrontEnd )
				)
				( attribute "PHYS_PAGE" "167"
					( Origin gFrontEnd )
				)
				( attribute "ROOM" "TEMP_SENSORS"
					( Origin gFrontEnd )
				)
				( attribute "ROT" "0"
					( Origin gFrontEnd )
				)
				( attribute "SEC" "1"
					( Origin gFrontEnd )
				)
				( attribute "SEC_TYPE" "0402"
					( Origin gFrontEnd )
				)
				( attribute "TOLERANCE" "1%"
					( Origin gFrontEnd )
				)
				( attribute "VALUE" "20.0"
					( Origin gFrontEnd )
				)
				( attribute "VER" "1"
					( Origin gFrontEnd )
				)
				( attribute "WATTAGE" "1/16W"
					( Origin gFrontEnd )
				)
				( attribute "XY" "(-2625,3050)"
					( Origin gFrontEnd )
				)
				( attribute "CHIPS_PART_NAME" "RES"
					( Origin gPackager )
				)
				( attribute "CDS_PART_NAME" "RES_0402-20.0,1%,1/16W,CHIP,G2A"
					( Origin gPackager )
				)
				( objectStatus "R9R8" )
				( pin "a"
					( attribute "PN" "1"
						( Origin gPackager )
					)
					( objectStatus "R9R8.1" )
				)
				( pin "b"
					( attribute "PN" "2"
						( Origin gPackager )
					)
					( objectStatus "R9R8.2" )
				)
			)
			( gate "@baseboard_fab2_lib.baseboard_fab2(sch_1):page167_i77"
				( attribute "BOM_COST" "SM_CONTROLLER"
					( Origin gFrontEnd )
				)
				( attribute "CDS_LIB" "mstr_discrete"
					( Origin gPackager )
				)
				( attribute "CDS_LOCATION" "R9G14"
					( Origin gPackager )
				)
				( attribute "CDS_SEC" "1"
					( Origin gPackager )
				)
				( attribute "LOCATION" "R9G14"
					( Origin gFrontEnd )
				)
				( attribute "MATERIAL" "CHIP"
					( Origin gFrontEnd )
				)
				( attribute "PACK_TYPE" "0402"
					( Origin gFrontEnd )
				)
				( attribute "PART_NUMBER" "G21796-173"
					( Origin gFrontEnd )
				)
				( attribute "PHYS_PAGE" "167"
					( Origin gFrontEnd )
				)
				( attribute "ROOM" "SMBUS"
					( Origin gFrontEnd )
				)
				( attribute "ROT" "0"
					( Origin gFrontEnd )
				)
				( attribute "SEC" "1"
					( Origin gPackager )
				)
				( attribute "SKU" "B"
					( Origin gFrontEnd )
				)
				( attribute "TOLERANCE" "1%"
					( Origin gFrontEnd )
				)
				( attribute "VALUE" "20.0"
					( Origin gFrontEnd )
				)
				( attribute "VER" "1"
					( Origin gFrontEnd )
				)
				( attribute "WATTAGE" "1/16W"
					( Origin gFrontEnd )
				)
				( attribute "XY" "(-6725,1325)"
					( Origin gFrontEnd )
				)
				( attribute "CHIPS_PART_NAME" "RES"
					( Origin gPackager )
				)
				( attribute "CDS_PART_NAME" "RES_0402-20.0,1%,1/16W,CHIP,G2A"
					( Origin gPackager )
				)
				( objectStatus "R9G14" )
				( pin "a"
					( attribute "PN" "1"
						( Origin gPackager )
					)
					( objectStatus "R9G14.1" )
				)
				( pin "b"
					( attribute "PN" "2"
						( Origin gPackager )
					)
					( objectStatus "R9G14.2" )
				)
			)
			( gate "@baseboard_fab2_lib.baseboard_fab2(sch_1):page167_i78"
				( attribute "BOM_COST" "SM_CONTROLLER"
					( Origin gFrontEnd )
				)
				( attribute "CDS_LIB" "mstr_discrete"
					( Origin gPackager )
				)
				( attribute "CDS_LOCATION" "R1U31"
					( Origin gPackager )
				)
				( attribute "CDS_SEC" "1"
					( Origin gPackager )
				)
				( attribute "LOCATION" "R1U31"
					( Origin gFrontEnd )
				)
				( attribute "MATERIAL" "CHIP"
					( Origin gFrontEnd )
				)
				( attribute "PACK_TYPE" "0402"
					( Origin gFrontEnd )
				)
				( attribute "PART_NUMBER" "G21796-173"
					( Origin gFrontEnd )
				)
				( attribute "PHYS_PAGE" "167"
					( Origin gFrontEnd )
				)
				( attribute "ROOM" "SMBUS"
					( Origin gFrontEnd )
				)
				( attribute "ROT" "0"
					( Origin gFrontEnd )
				)
				( attribute "SEC" "1"
					( Origin gPackager )
				)
				( attribute "SKU" "B"
					( Origin gFrontEnd )
				)
				( attribute "TOLERANCE" "1%"
					( Origin gFrontEnd )
				)
				( attribute "VALUE" "20.0"
					( Origin gFrontEnd )
				)
				( attribute "VER" "1"
					( Origin gFrontEnd )
				)
				( attribute "WATTAGE" "1/16W"
					( Origin gFrontEnd )
				)
				( attribute "XY" "(-6725,1150)"
					( Origin gFrontEnd )
				)
				( attribute "CHIPS_PART_NAME" "RES"
					( Origin gPackager )
				)
				( attribute "CDS_PART_NAME" "RES_0402-20.0,1%,1/16W,CHIP,G2A"
					( Origin gPackager )
				)
				( objectStatus "R1U31" )
				( pin "a"
					( attribute "PN" "1"
						( Origin gPackager )
					)
					( objectStatus "R1U31.1" )
				)
				( pin "b"
					( attribute "PN" "2"
						( Origin gPackager )
					)
					( objectStatus "R1U31.2" )
				)
			)
			( gate "@baseboard_fab2_lib.baseboard_fab2(sch_1):page167_i79"
				( attribute "BOM_COST" "SM_CONTROLLER"
					( Origin gFrontEnd )
				)
				( attribute "CDS_LIB" "mstr_discrete"
					( Origin gPackager )
				)
				( attribute "CDS_LOCATION" "R1U25"
					( Origin gPackager )
				)
				( attribute "CDS_SEC" "1"
					( Origin gPackager )
				)
				( attribute "LOCATION" "R1U25"
					( Origin gFrontEnd )
				)
				( attribute "MATERIAL" "CHIP"
					( Origin gFrontEnd )
				)
				( attribute "PACK_TYPE" "0402"
					( Origin gFrontEnd )
				)
				( attribute "PART_NUMBER" "G21796-173"
					( Origin gFrontEnd )
				)
				( attribute "PHYS_PAGE" "167"
					( Origin gFrontEnd )
				)
				( attribute "ROOM" "SMBUS"
					( Origin gFrontEnd )
				)
				( attribute "ROT" "0"
					( Origin gFrontEnd )
				)
				( attribute "SEC" "1"
					( Origin gPackager )
				)
				( attribute "SKU" "B"
					( Origin gFrontEnd )
				)
				( attribute "TOLERANCE" "1%"
					( Origin gFrontEnd )
				)
				( attribute "VALUE" "20.0"
					( Origin gFrontEnd )
				)
				( attribute "VER" "1"
					( Origin gFrontEnd )
				)
				( attribute "WATTAGE" "1/16W"
					( Origin gFrontEnd )
				)
				( attribute "XY" "(-6725,1025)"
					( Origin gFrontEnd )
				)
				( attribute "CHIPS_PART_NAME" "RES"
					( Origin gPackager )
				)
				( attribute "CDS_PART_NAME" "RES_0402-20.0,1%,1/16W,CHIP,G2A"
					( Origin gPackager )
				)
				( objectStatus "R1U25" )
				( pin "a"
					( attribute "PN" "1"
						( Origin gPackager )
					)
					( objectStatus "R1U25.1" )
				)
				( pin "b"
					( attribute "PN" "2"
						( Origin gPackager )
					)
					( objectStatus "R1U25.2" )
				)
			)
			( gate "@baseboard_fab2_lib.baseboard_fab2(sch_1):page167_i80"
				( attribute "BOM_COST" "SM_CONTROLLER"
					( Origin gFrontEnd )
				)
				( attribute "CDS_LIB" "mstr_discrete"
					( Origin gPackager )
				)
				( attribute "CDS_LOCATION" "R2U38"
					( Origin gPackager )
				)
				( attribute "CDS_SEC" "1"
					( Origin gPackager )
				)
				( attribute "LOCATION" "R2U38"
					( Origin gFrontEnd )
				)
				( attribute "MATERIAL" "CHIP"
					( Origin gFrontEnd )
				)
				( attribute "PACK_TYPE" "0402"
					( Origin gFrontEnd )
				)
				( attribute "PART_NUMBER" "G21796-235"
					( Origin gFrontEnd )
				)
				( attribute "PHYS_PAGE" "167"
					( Origin gFrontEnd )
				)
				( attribute "ROOM" "SMBUS"
					( Origin gFrontEnd )
				)
				( attribute "ROT" "0"
					( Origin gFrontEnd )
				)
				( attribute "SEC" "1"
					( Origin gFrontEnd )
				)
				( attribute "SEC_TYPE" "0402"
					( Origin gFrontEnd )
				)
				( attribute "TOLERANCE" "1.0%"
					( Origin gFrontEnd )
				)
				( attribute "VALUE" "665"
					( Origin gFrontEnd )
				)
				( attribute "VER" "2"
					( Origin gFrontEnd )
				)
				( attribute "WATTAGE" "1/16W"
					( Origin gFrontEnd )
				)
				( attribute "XY" "(-6075,1950)"
					( Origin gFrontEnd )
				)
				( attribute "CHIPS_PART_NAME" "RES"
					( Origin gPackager )
				)
				( attribute "CDS_PART_NAME" "RES_0402-665,1.0%,1/16W,CHIP,GA"
					( Origin gPackager )
				)
				( objectStatus "R2U38" )
				( pin "a"
					( attribute "PN" "1"
						( Origin gPackager )
					)
					( objectStatus "R2U38.1" )
				)
				( pin "b"
					( attribute "PN" "2"
						( Origin gPackager )
					)
					( objectStatus "R2U38.2" )
				)
			)
			( gate "@baseboard_fab2_lib.baseboard_fab2(sch_1):page167_i83"
				( attribute "BOM_COST" "SM_CONTROLLER"
					( Origin gFrontEnd )
				)
				( attribute "CDS_LIB" "mstr_discrete"
					( Origin gPackager )
				)
				( attribute "CDS_LOCATION" "R2U39"
					( Origin gPackager )
				)
				( attribute "CDS_SEC" "1"
					( Origin gPackager )
				)
				( attribute "LOCATION" "R2U39"
					( Origin gFrontEnd )
				)
				( attribute "MATERIAL" "CHIP"
					( Origin gFrontEnd )
				)
				( attribute "PACK_TYPE" "0402"
					( Origin gFrontEnd )
				)
				( attribute "PART_NUMBER" "G21796-235"
					( Origin gFrontEnd )
				)
				( attribute "PHYS_PAGE" "167"
					( Origin gFrontEnd )
				)
				( attribute "ROOM" "SMBUS"
					( Origin gFrontEnd )
				)
				( attribute "ROT" "0"
					( Origin gFrontEnd )
				)
				( attribute "SEC" "1"
					( Origin gFrontEnd )
				)
				( attribute "SEC_TYPE" "0402"
					( Origin gFrontEnd )
				)
				( attribute "TOLERANCE" "1.0%"
					( Origin gFrontEnd )
				)
				( attribute "VALUE" "665"
					( Origin gFrontEnd )
				)
				( attribute "VER" "2"
					( Origin gFrontEnd )
				)
				( attribute "WATTAGE" "1/16W"
					( Origin gFrontEnd )
				)
				( attribute "XY" "(-6425,1950)"
					( Origin gFrontEnd )
				)
				( attribute "CHIPS_PART_NAME" "RES"
					( Origin gPackager )
				)
				( attribute "CDS_PART_NAME" "RES_0402-665,1.0%,1/16W,CHIP,GA"
					( Origin gPackager )
				)
				( objectStatus "R2U39" )
				( pin "a"
					( attribute "PN" "1"
						( Origin gPackager )
					)
					( objectStatus "R2U39.1" )
				)
				( pin "b"
					( attribute "PN" "2"
						( Origin gPackager )
					)
					( objectStatus "R2U39.2" )
				)
			)
			( gate "@baseboard_fab2_lib.baseboard_fab2(sch_1):page167_i84"
				( attribute "BOM_COST" "SM_THERM"
					( Origin gFrontEnd )
				)
				( attribute "CDS_LIB" "mstr_discrete"
					( Origin gPackager )
				)
				( attribute "CDS_LOCATION" "R8D24"
					( Origin gPackager )
				)
				( attribute "CDS_SEC" "1"
					( Origin gPackager )
				)
				( attribute "LOCATION" "R8D24"
					( Origin gFrontEnd )
				)
				( attribute "MATERIAL" "CHIP"
					( Origin gFrontEnd )
				)
				( attribute "PACK_TYPE" "0402"
					( Origin gFrontEnd )
				)
				( attribute "PART_NUMBER" "G21796-173"
					( Origin gFrontEnd )
				)
				( attribute "PHYS_PAGE" "167"
					( Origin gFrontEnd )
				)
				( attribute "ROOM" "TEMP_SENSORS"
					( Origin gFrontEnd )
				)
				( attribute "ROT" "0"
					( Origin gFrontEnd )
				)
				( attribute "SEC" "1"
					( Origin gFrontEnd )
				)
				( attribute "SEC_TYPE" "0402"
					( Origin gFrontEnd )
				)
				( attribute "TOLERANCE" "1%"
					( Origin gFrontEnd )
				)
				( attribute "VALUE" "20.0"
					( Origin gFrontEnd )
				)
				( attribute "VER" "1"
					( Origin gFrontEnd )
				)
				( attribute "WATTAGE" "1/16W"
					( Origin gFrontEnd )
				)
				( attribute "XY" "(-3975,1550)"
					( Origin gFrontEnd )
				)
				( attribute "CHIPS_PART_NAME" "RES"
					( Origin gPackager )
				)
				( attribute "CDS_PART_NAME" "RES_0402-20.0,1%,1/16W,CHIP,G2A"
					( Origin gPackager )
				)
				( objectStatus "R8D24" )
				( pin "a"
					( attribute "PN" "1"
						( Origin gPackager )
					)
					( objectStatus "R8D24.1" )
				)
				( pin "b"
					( attribute "PN" "2"
						( Origin gPackager )
					)
					( objectStatus "R8D24.2" )
				)
			)
			( gate "@baseboard_fab2_lib.baseboard_fab2(sch_1):page167_i85"
				( attribute "BOM_COST" "SM_THERM"
					( Origin gFrontEnd )
				)
				( attribute "CDS_LIB" "mstr_discrete"
					( Origin gPackager )
				)
				( attribute "CDS_LOCATION" "R8D23"
					( Origin gPackager )
				)
				( attribute "CDS_SEC" "1"
					( Origin gPackager )
				)
				( attribute "LOCATION" "R8D23"
					( Origin gFrontEnd )
				)
				( attribute "MATERIAL" "CHIP"
					( Origin gFrontEnd )
				)
				( attribute "PACK_TYPE" "0402"
					( Origin gFrontEnd )
				)
				( attribute "PART_NUMBER" "G21796-173"
					( Origin gFrontEnd )
				)
				( attribute "PHYS_PAGE" "167"
					( Origin gFrontEnd )
				)
				( attribute "ROOM" "TEMP_SENSORS"
					( Origin gFrontEnd )
				)
				( attribute "ROT" "0"
					( Origin gFrontEnd )
				)
				( attribute "SEC" "1"
					( Origin gPackager )
				)
				( attribute "TOLERANCE" "1%"
					( Origin gFrontEnd )
				)
				( attribute "VALUE" "20.0"
					( Origin gFrontEnd )
				)
				( attribute "VER" "1"
					( Origin gFrontEnd )
				)
				( attribute "WATTAGE" "1/16W"
					( Origin gFrontEnd )
				)
				( attribute "XY" "(-1525,1550)"
					( Origin gFrontEnd )
				)
				( attribute "CHIPS_PART_NAME" "RES"
					( Origin gPackager )
				)
				( attribute "CDS_PART_NAME" "RES_0402-20.0,1%,1/16W,CHIP,G2A"
					( Origin gPackager )
				)
				( objectStatus "R8D23" )
				( pin "a"
					( attribute "PN" "1"
						( Origin gPackager )
					)
					( objectStatus "R8D23.1" )
				)
				( pin "b"
					( attribute "PN" "2"
						( Origin gPackager )
					)
					( objectStatus "R8D23.2" )
				)
			)
			( gate "@baseboard_fab2_lib.baseboard_fab2(sch_1):page168_i2"
				( attribute "BOM_COST" "DEBUG"
					( Origin gFrontEnd )
				)
				( attribute "CDS_LIB" "mstr_discrete"
					( Origin gPackager )
				)
				( attribute "CDS_LOCATION" "CR1L1"
					( Origin gPackager )
				)
				( attribute "CDS_SEC" "1"
					( Origin gPackager )
				)
				( attribute "LOCATION" "CR1L1"
					( Origin gFrontEnd )
				)
				( attribute "MATERIAL" "IC"
					( Origin gFrontEnd )
				)
				( attribute "PACK_TYPE" "SM"
					( Origin gFrontEnd )
				)
				( attribute "PART_NUMBER" "D89194-001"
					( Origin gFrontEnd )
				)
				( attribute "PHYS_PAGE" "168"
					( Origin gFrontEnd )
				)
				( attribute "ROOM" "UART_MUX"
					( Origin gFrontEnd )
				)
				( attribute "ROT" "0"
					( Origin gFrontEnd )
				)
				( attribute "SEC" "1"
					( Origin gFrontEnd )
				)
				( attribute "SEC_TYPE" "SM"
					( Origin gFrontEnd )
				)
				( attribute "VALUE" "1N4148W"
					( Origin gFrontEnd )
				)
				( attribute "VER" "1"
					( Origin gFrontEnd )
				)
				( attribute "XY" "(-6400,2750)"
					( Origin gFrontEnd )
				)
				( attribute "CHIPS_PART_NAME" "DIODE"
					( Origin gPackager )
				)
				( attribute "CDS_PART_NAME" "DIODE_SM-1N4148W,IC,D89194-001"
					( Origin gPackager )
				)
				( objectStatus "CR1L1" )
				( pin "a"
					( attribute "PN" "2"
						( Origin gPackager )
					)
					( objectStatus "CR1L1.2" )
				)
				( pin "c"
					( attribute "PN" "1"
						( Origin gPackager )
					)
					( objectStatus "CR1L1.1" )
				)
			)
			( gate "@baseboard_fab2_lib.baseboard_fab2(sch_1):page168_i3"
				( attribute "BOM_COST" "DEBUG"
					( Origin gFrontEnd )
				)
				( attribute "CDS_LIB" "mstr_discrete"
					( Origin gPackager )
				)
				( attribute "CDS_LOCATION" "CR1L2"
					( Origin gPackager )
				)
				( attribute "CDS_SEC" "1"
					( Origin gPackager )
				)
				( attribute "LOCATION" "CR1L2"
					( Origin gFrontEnd )
				)
				( attribute "MATERIAL" "IC"
					( Origin gFrontEnd )
				)
				( attribute "PACK_TYPE" "SM"
					( Origin gFrontEnd )
				)
				( attribute "PART_NUMBER" "D89194-001"
					( Origin gFrontEnd )
				)
				( attribute "PHYS_PAGE" "168"
					( Origin gFrontEnd )
				)
				( attribute "ROOM" "UART_MUX"
					( Origin gFrontEnd )
				)
				( attribute "ROT" "0"
					( Origin gFrontEnd )
				)
				( attribute "SEC" "1"
					( Origin gFrontEnd )
				)
				( attribute "SEC_TYPE" "SM"
					( Origin gFrontEnd )
				)
				( attribute "VALUE" "1N4148W"
					( Origin gFrontEnd )
				)
				( attribute "VER" "1"
					( Origin gFrontEnd )
				)
				( attribute "XY" "(-5850,2750)"
					( Origin gFrontEnd )
				)
				( attribute "CHIPS_PART_NAME" "DIODE"
					( Origin gPackager )
				)
				( attribute "CDS_PART_NAME" "DIODE_SM-1N4148W,IC,D89194-001"
					( Origin gPackager )
				)
				( objectStatus "CR1L2" )
				( pin "a"
					( attribute "PN" "2"
						( Origin gPackager )
					)
					( objectStatus "CR1L2.2" )
				)
				( pin "c"
					( attribute "PN" "1"
						( Origin gPackager )
					)
					( objectStatus "CR1L2.1" )
				)
			)
			( gate "@baseboard_fab2_lib.baseboard_fab2(sch_1):page168_i4"
				( attribute "BOM_COST" "DEBUG"
					( Origin gFrontEnd )
				)
				( attribute "CDS_LIB" "mstr_discrete"
					( Origin gPackager )
				)
				( attribute "CDS_LOCATION" "CR1L3"
					( Origin gPackager )
				)
				( attribute "CDS_SEC" "1"
					( Origin gPackager )
				)
				( attribute "LOCATION" "CR1L3"
					( Origin gFrontEnd )
				)
				( attribute "MATERIAL" "IC"
					( Origin gFrontEnd )
				)
				( attribute "PACK_TYPE" "SM"
					( Origin gFrontEnd )
				)
				( attribute "PART_NUMBER" "D89194-001"
					( Origin gFrontEnd )
				)
				( attribute "PHYS_PAGE" "168"
					( Origin gFrontEnd )
				)
				( attribute "ROOM" "UART_MUX"
					( Origin gFrontEnd )
				)
				( attribute "ROT" "0"
					( Origin gFrontEnd )
				)
				( attribute "SEC" "1"
					( Origin gFrontEnd )
				)
				( attribute "SEC_TYPE" "SM"
					( Origin gFrontEnd )
				)
				( attribute "VALUE" "1N4148W"
					( Origin gFrontEnd )
				)
				( attribute "VER" "1"
					( Origin gFrontEnd )
				)
				( attribute "XY" "(-5375,2750)"
					( Origin gFrontEnd )
				)
				( attribute "CHIPS_PART_NAME" "DIODE"
					( Origin gPackager )
				)
				( attribute "CDS_PART_NAME" "DIODE_SM-1N4148W,IC,D89194-001"
					( Origin gPackager )
				)
				( objectStatus "CR1L3" )
				( pin "a"
					( attribute "PN" "2"
						( Origin gPackager )
					)
					( objectStatus "CR1L3.2" )
				)
				( pin "c"
					( attribute "PN" "1"
						( Origin gPackager )
					)
					( objectStatus "CR1L3.1" )
				)
			)
			( gate "@baseboard_fab2_lib.baseboard_fab2(sch_1):page168_i5"
				( attribute "BOM_COST" "DEBUG"
					( Origin gFrontEnd )
				)
				( attribute "CDS_LIB" "mstr_discrete"
					( Origin gPackager )
				)
				( attribute "CDS_LOCATION" "CR1L4"
					( Origin gPackager )
				)
				( attribute "CDS_SEC" "1"
					( Origin gPackager )
				)
				( attribute "LOCATION" "CR1L4"
					( Origin gFrontEnd )
				)
				( attribute "MATERIAL" "IC"
					( Origin gFrontEnd )
				)
				( attribute "PACK_TYPE" "SM"
					( Origin gFrontEnd )
				)
				( attribute "PART_NUMBER" "D89194-001"
					( Origin gFrontEnd )
				)
				( attribute "PHYS_PAGE" "168"
					( Origin gFrontEnd )
				)
				( attribute "ROOM" "UART_MUX"
					( Origin gFrontEnd )
				)
				( attribute "ROT" "0"
					( Origin gFrontEnd )
				)
				( attribute "SEC" "1"
					( Origin gFrontEnd )
				)
				( attribute "SEC_TYPE" "SM"
					( Origin gFrontEnd )
				)
				( attribute "VALUE" "1N4148W"
					( Origin gFrontEnd )
				)
				( attribute "VER" "1"
					( Origin gFrontEnd )
				)
				( attribute "XY" "(-4875,2750)"
					( Origin gFrontEnd )
				)
				( attribute "CHIPS_PART_NAME" "DIODE"
					( Origin gPackager )
				)
				( attribute "CDS_PART_NAME" "DIODE_SM-1N4148W,IC,D89194-001"
					( Origin gPackager )
				)
				( objectStatus "CR1L4" )
				( pin "a"
					( attribute "PN" "2"
						( Origin gPackager )
					)
					( objectStatus "CR1L4.2" )
				)
				( pin "c"
					( attribute "PN" "1"
						( Origin gPackager )
					)
					( objectStatus "CR1L4.1" )
				)
			)
			( gate "@baseboard_fab2_lib.baseboard_fab2(sch_1):page168_i6"
				( attribute "BOM_COST" "DEBUG"
					( Origin gFrontEnd )
				)
				( attribute "CDS_LIB" "mstr_discrete"
					( Origin gPackager )
				)
				( attribute "CDS_LOCATION" "R1L6"
					( Origin gPackager )
				)
				( attribute "CDS_SEC" "1"
					( Origin gPackager )
				)
				( attribute "LOCATION" "R1L6"
					( Origin gFrontEnd )
				)
				( attribute "MATERIAL" "CHIP"
					( Origin gFrontEnd )
				)
				( attribute "PACK_TYPE" "0402"
					( Origin gFrontEnd )
				)
				( attribute "PART_NUMBER" "G21497-005"
					( Origin gFrontEnd )
				)
				( attribute "PHYS_PAGE" "168"
					( Origin gFrontEnd )
				)
				( attribute "ROOM" "UART_MUX"
					( Origin gFrontEnd )
				)
				( attribute "ROT" "0"
					( Origin gFrontEnd )
				)
				( attribute "SEC" "1"
					( Origin gFrontEnd )
				)
				( attribute "SEC_TYPE" "0402"
					( Origin gFrontEnd )
				)
				( attribute "TOLERANCE" "5%"
					( Origin gFrontEnd )
				)
				( attribute "VALUE" "0.0"
					( Origin gFrontEnd )
				)
				( attribute "VER" "1"
					( Origin gFrontEnd )
				)
				( attribute "WATTAGE" "1/16W"
					( Origin gFrontEnd )
				)
				( attribute "XY" "(-6975,2750)"
					( Origin gFrontEnd )
				)
				( attribute "CHIPS_PART_NAME" "RES"
					( Origin gPackager )
				)
				( attribute "CDS_PART_NAME" "RES_0402-0.0,5%,1/16W,CHIP,G21A"
					( Origin gPackager )
				)
				( objectStatus "R1L6" )
				( pin "a"
					( attribute "PN" "1"
						( Origin gPackager )
					)
					( objectStatus "R1L6.1" )
				)
				( pin "b"
					( attribute "PN" "2"
						( Origin gPackager )
					)
					( objectStatus "R1L6.2" )
				)
			)
			( gate "@baseboard_fab2_lib.baseboard_fab2(sch_1):page144_i89"
				( attribute "BOM_COST" "MIO_USB"
					( Origin gFrontEnd )
				)
				( attribute "CDS_LIB" "mstr_discrete"
					( Origin gPackager )
				)
				( attribute "LOCATION" "R6W17"
					( Origin gFrontEnd )
				)
				( attribute "MATERIAL" "CHIP"
					( Origin gFrontEnd )
				)
				( attribute "PACK_TYPE" "0402"
					( Origin gFrontEnd )
				)
				( attribute "PART_NUMBER" "G21497-005"
					( Origin gFrontEnd )
				)
				( attribute "PHYS_PAGE" "144"
					( Origin gFrontEnd )
				)
				( attribute "ROOM" "USB"
					( Origin gFrontEnd )
				)
				( attribute "ROT" "0"
					( Origin gFrontEnd )
				)
				( attribute "TOLERANCE" "5%"
					( Origin gFrontEnd )
				)
				( attribute "VALUE" "0.0"
					( Origin gFrontEnd )
				)
				( attribute "VER" "1"
					( Origin gFrontEnd )
				)
				( attribute "WATTAGE" "1/16W"
					( Origin gFrontEnd )
				)
				( attribute "XY" "(-6725,-3150)"
					( Origin gFrontEnd )
				)
				( attribute "CHIPS_PART_NAME" "RES"
					( Origin gPackager )
				)
				( attribute "CDS_PART_NAME" "RES_0402-0.0,5%,1/16W,CHIP,G21A"
					( Origin gPackager )
				)
				( attribute "CDS_LOCATION" "R6W17"
					( Origin gPackager )
				)
				( attribute "CDS_SEC" "1"
					( Origin gPackager )
				)
				( attribute "SEC" "1"
					( Origin gPackager )
				)
				( objectStatus "R6W17" )
				( pin "a"
					( attribute "PN" "1"
						( Origin gPackager )
					)
					( objectStatus "R6W17.1" )
				)
				( pin "b"
					( attribute "PN" "2"
						( Origin gPackager )
					)
					( objectStatus "R6W17.2" )
				)
			)
			( gate "@baseboard_fab2_lib.baseboard_fab2(sch_1):page168_i8"
				( attribute "BOM_COST" "DEBUG"
					( Origin gFrontEnd )
				)
				( attribute "CDS_LIB" "mstr_discrete"
					( Origin gPackager )
				)
				( attribute "CDS_LOCATION" "Q1L3"
					( Origin gPackager )
				)
				( attribute "CDS_SEC" "1"
					( Origin gPackager )
				)
				( attribute "LOCATION" "Q1L3"
					( Origin gFrontEnd )
				)
				( attribute "MATERIAL" "IC"
					( Origin gFrontEnd )
				)
				( attribute "PACK_TYPE" "SM"
					( Origin gFrontEnd )
				)
				( attribute "PART_NUMBER" "C52245-001"
					( Origin gFrontEnd )
				)
				( attribute "PHYS_PAGE" "168"
					( Origin gFrontEnd )
				)
				( attribute "ROOM" "UART_MUX"
					( Origin gFrontEnd )
				)
				( attribute "ROT" "0"
					( Origin gFrontEnd )
				)
				( attribute "SEC" "1"
					( Origin gFrontEnd )
				)
				( attribute "SEC_TYPE" "SM"
					( Origin gFrontEnd )
				)
				( attribute "VALUE" "MMBT3904"
					( Origin gFrontEnd )
				)
				( attribute "VER" "1"
					( Origin gFrontEnd )
				)
				( attribute "XY" "(-4275,2750)"
					( Origin gFrontEnd )
				)
				( attribute "CHIPS_PART_NAME" "NPN"
					( Origin gPackager )
				)
				( attribute "CDS_PART_NAME" "NPN_SM-MMBT3904,IC,C52245-001"
					( Origin gPackager )
				)
				( objectStatus "Q1L3" )
				( pin "b"
					( attribute "PN" "1"
						( Origin gPackager )
					)
					( objectStatus "Q1L3.1" )
				)
				( pin "c"
					( attribute "PN" "3"
						( Origin gPackager )
					)
					( objectStatus "Q1L3.3" )
				)
				( pin "e"
					( attribute "PN" "2"
						( Origin gPackager )
					)
					( objectStatus "Q1L3.2" )
				)
			)
			( gate "@baseboard_fab2_lib.baseboard_fab2(sch_1):page144_i90"
				( attribute "BOM_COST" "MIO_USB"
					( Origin gFrontEnd )
				)
				( attribute "CDS_LIB" "mstr_discrete"
					( Origin gPackager )
				)
				( attribute "LOCATION" "R6W18"
					( Origin gFrontEnd )
				)
				( attribute "MATERIAL" "CHIP"
					( Origin gFrontEnd )
				)
				( attribute "PACK_TYPE" "0402"
					( Origin gFrontEnd )
				)
				( attribute "PART_NUMBER" "G21497-005"
					( Origin gFrontEnd )
				)
				( attribute "PHYS_PAGE" "144"
					( Origin gFrontEnd )
				)
				( attribute "ROOM" "USB"
					( Origin gFrontEnd )
				)
				( attribute "ROT" "0"
					( Origin gFrontEnd )
				)
				( attribute "TOLERANCE" "5%"
					( Origin gFrontEnd )
				)
				( attribute "VALUE" "0.0"
					( Origin gFrontEnd )
				)
				( attribute "VER" "1"
					( Origin gFrontEnd )
				)
				( attribute "WATTAGE" "1/16W"
					( Origin gFrontEnd )
				)
				( attribute "XY" "(-6700,-3050)"
					( Origin gFrontEnd )
				)
				( attribute "CHIPS_PART_NAME" "RES"
					( Origin gPackager )
				)
				( attribute "CDS_PART_NAME" "RES_0402-0.0,5%,1/16W,CHIP,G21A"
					( Origin gPackager )
				)
				( attribute "CDS_LOCATION" "R6W18"
					( Origin gPackager )
				)
				( attribute "CDS_SEC" "1"
					( Origin gPackager )
				)
				( attribute "SEC" "1"
					( Origin gPackager )
				)
				( objectStatus "R6W18" )
				( pin "a"
					( attribute "PN" "1"
						( Origin gPackager )
					)
					( objectStatus "R6W18.1" )
				)
				( pin "b"
					( attribute "PN" "2"
						( Origin gPackager )
					)
					( objectStatus "R6W18.2" )
				)
			)
			( gate "@baseboard_fab2_lib.baseboard_fab2(sch_1):page168_i11"
				( attribute "BOM_COST" "DEBUG"
					( Origin gFrontEnd )
				)
				( attribute "CDS_LIB" "mstr_discrete"
					( Origin gPackager )
				)
				( attribute "CDS_LOCATION" "R1L36"
					( Origin gPackager )
				)
				( attribute "CDS_SEC" "1"
					( Origin gPackager )
				)
				( attribute "LOCATION" "R1L36"
					( Origin gFrontEnd )
				)
				( attribute "MATERIAL" "CHIP"
					( Origin gFrontEnd )
				)
				( attribute "PACK_TYPE" "0402"
					( Origin gFrontEnd )
				)
				( attribute "PART_NUMBER" "G21796-026"
					( Origin gFrontEnd )
				)
				( attribute "PHYS_PAGE" "168"
					( Origin gFrontEnd )
				)
				( attribute "ROOM" "UART_MUX"
					( Origin gFrontEnd )
				)
				( attribute "ROT" "0"
					( Origin gFrontEnd )
				)
				( attribute "SEC" "1"
					( Origin gFrontEnd )
				)
				( attribute "SEC_TYPE" "0402"
					( Origin gFrontEnd )
				)
				( attribute "TOLERANCE" "1%"
					( Origin gFrontEnd )
				)
				( attribute "VALUE" "1.00K"
					( Origin gFrontEnd )
				)
				( attribute "VER" "2"
					( Origin gFrontEnd )
				)
				( attribute "WATTAGE" "1/16W"
					( Origin gFrontEnd )
				)
				( attribute "XY" "(-4225,3050)"
					( Origin gFrontEnd )
				)
				( attribute "CHIPS_PART_NAME" "RES"
					( Origin gPackager )
				)
				( attribute "CDS_PART_NAME" "RES_0402-1.00K,1%,1/16W,CHIP,GA"
					( Origin gPackager )
				)
				( objectStatus "R1L36" )
				( pin "a"
					( attribute "PN" "1"
						( Origin gPackager )
					)
					( objectStatus "R1L36.1" )
				)
				( pin "b"
					( attribute "PN" "2"
						( Origin gPackager )
					)
					( objectStatus "R1L36.2" )
				)
			)
			( gate "@baseboard_fab2_lib.baseboard_fab2(sch_1):page168_i18"
				( attribute "BOM_COST" "DEBUG"
					( Origin gFrontEnd )
				)
				( attribute "CDS_LIB" "mstr_discrete"
					( Origin gPackager )
				)
				( attribute "CDS_LOCATION" "Q1L4"
					( Origin gPackager )
				)
				( attribute "CDS_SEC" "2"
					( Origin gPackager )
				)
				( attribute "LOCATION" "Q1L4"
					( Origin gFrontEnd )
				)
				( attribute "MATERIAL" "FET"
					( Origin gFrontEnd )
				)
				( attribute "PACK_TYPE" "SMLF"
					( Origin gFrontEnd )
				)
				( attribute "PART_NUMBER" "D24280-001"
					( Origin gFrontEnd )
				)
				( attribute "PHYS_PAGE" "168"
					( Origin gFrontEnd )
				)
				( attribute "ROOM" "UART_MUX"
					( Origin gFrontEnd )
				)
				( attribute "ROT" "0"
					( Origin gFrontEnd )
				)
				( attribute "SEC" "2"
					( Origin gFrontEnd )
				)
				( attribute "SEC_TYPE" "SMLF"
					( Origin gFrontEnd )
				)
				( attribute "VALUE" "2N7002DW"
					( Origin gFrontEnd )
				)
				( attribute "VER" "5"
					( Origin gFrontEnd )
				)
				( attribute "XY" "(-1525,4425)"
					( Origin gFrontEnd )
				)
				( attribute "CHIPS_PART_NAME" "FET_N_DUAL"
					( Origin gPackager )
				)
				( attribute "CDS_PART_NAME" "FET_N_DUAL_SMLF-2N7002DW,FET,DA"
					( Origin gPackager )
				)
				( objectStatus "Q1L4" )
				( pin "drain(0)"
					( attribute "PN" "3"
						( Origin gPackager )
					)
					( objectStatus "Q1L4.3" )
				)
				( pin "gate(0)"
					( attribute "PN" "5"
						( Origin gPackager )
					)
					( objectStatus "Q1L4.5" )
				)
				( pin "source(0)"
					( attribute "PN" "4"
						( Origin gPackager )
					)
					( objectStatus "Q1L4.4" )
				)
			)
			( gate "@baseboard_fab2_lib.baseboard_fab2(sch_1):page168_i19"
				( attribute "BOM_COST" "DEBUG"
					( Origin gFrontEnd )
				)
				( attribute "CDS_LIB" "mstr_discrete"
					( Origin gPackager )
				)
				( attribute "CDS_LOCATION" "Q1L4"
					( Origin gPackager )
				)
				( attribute "CDS_SEC" "1"
					( Origin gPackager )
				)
				( attribute "LOCATION" "Q1L4"
					( Origin gFrontEnd )
				)
				( attribute "MATERIAL" "FET"
					( Origin gFrontEnd )
				)
				( attribute "PACK_TYPE" "SMLF"
					( Origin gFrontEnd )
				)
				( attribute "PART_NUMBER" "D24280-001"
					( Origin gFrontEnd )
				)
				( attribute "PHYS_PAGE" "168"
					( Origin gFrontEnd )
				)
				( attribute "ROOM" "UART_MUX"
					( Origin gFrontEnd )
				)
				( attribute "ROT" "0"
					( Origin gFrontEnd )
				)
				( attribute "SEC" "1"
					( Origin gFrontEnd )
				)
				( attribute "SEC_TYPE" "SMLF"
					( Origin gFrontEnd )
				)
				( attribute "VALUE" "2N7002DW"
					( Origin gFrontEnd )
				)
				( attribute "VER" "5"
					( Origin gFrontEnd )
				)
				( attribute "XY" "(-3250,3000)"
					( Origin gFrontEnd )
				)
				( attribute "CHIPS_PART_NAME" "FET_N_DUAL"
					( Origin gPackager )
				)
				( attribute "CDS_PART_NAME" "FET_N_DUAL_SMLF-2N7002DW,FET,DA"
					( Origin gPackager )
				)
				( objectStatus "Q1L4" )
				( pin "drain(0)"
					( attribute "PN" "6"
						( Origin gPackager )
					)
					( objectStatus "Q1L4.6" )
				)
				( pin "gate(0)"
					( attribute "PN" "2"
						( Origin gPackager )
					)
					( objectStatus "Q1L4.2" )
				)
				( pin "source(0)"
					( attribute "PN" "1"
						( Origin gPackager )
					)
					( objectStatus "Q1L4.1" )
				)
			)
			( gate "@baseboard_fab2_lib.baseboard_fab2(sch_1):page168_i22"
				( attribute "BOM_COST" "DEBUG"
					( Origin gFrontEnd )
				)
				( attribute "CDS_LIB" "mstr_discrete"
					( Origin gPackager )
				)
				( attribute "CDS_LOCATION" "R1L38"
					( Origin gPackager )
				)
				( attribute "CDS_SEC" "1"
					( Origin gPackager )
				)
				( attribute "LOCATION" "R1L38"
					( Origin gFrontEnd )
				)
				( attribute "MATERIAL" "CHIP"
					( Origin gFrontEnd )
				)
				( attribute "PACK_TYPE" "0402"
					( Origin gFrontEnd )
				)
				( attribute "PART_NUMBER" "G21796-026"
					( Origin gFrontEnd )
				)
				( attribute "PHYS_PAGE" "168"
					( Origin gFrontEnd )
				)
				( attribute "ROOM" "UART_MUX"
					( Origin gFrontEnd )
				)
				( attribute "ROT" "0"
					( Origin gFrontEnd )
				)
				( attribute "SEC" "1"
					( Origin gFrontEnd )
				)
				( attribute "SEC_TYPE" "0402"
					( Origin gFrontEnd )
				)
				( attribute "TOLERANCE" "1%"
					( Origin gFrontEnd )
				)
				( attribute "VALUE" "1.00K"
					( Origin gFrontEnd )
				)
				( attribute "VER" "2"
					( Origin gFrontEnd )
				)
				( attribute "WATTAGE" "1/16W"
					( Origin gFrontEnd )
				)
				( attribute "XY" "(-3250,3425)"
					( Origin gFrontEnd )
				)
				( attribute "CHIPS_PART_NAME" "RES"
					( Origin gPackager )
				)
				( attribute "CDS_PART_NAME" "RES_0402-1.00K,1%,1/16W,CHIP,GA"
					( Origin gPackager )
				)
				( objectStatus "R1L38" )
				( pin "a"
					( attribute "PN" "1"
						( Origin gPackager )
					)
					( objectStatus "R1L38.1" )
				)
				( pin "b"
					( attribute "PN" "2"
						( Origin gPackager )
					)
					( objectStatus "R1L38.2" )
				)
			)
			( gate "@baseboard_fab2_lib.baseboard_fab2(sch_1):page169_i56"
				( attribute "BOM_COST" "SM_HM"
					( Origin gFrontEnd )
				)
				( attribute "CDS_LIB" "mstr_discrete"
					( Origin gPackager )
				)
				( attribute "CDS_LOCATION" "C1U21"
					( Origin gPackager )
				)
				( attribute "CDS_SEC" "1"
					( Origin gPackager )
				)
				( attribute "LOCATION" "C1U21"
					( Origin gFrontEnd )
				)
				( attribute "MATERIAL" "COG"
					( Origin gFrontEnd )
				)
				( attribute "PACK_TYPE" "0402LF"
					( Origin gFrontEnd )
				)
				( attribute "PART_NUMBER" "A36095-025"
					( Origin gFrontEnd )
				)
				( attribute "PHYS_PAGE" "169"
					( Origin gFrontEnd )
				)
				( attribute "ROOM" "BMC_VOLT_MONITOR"
					( Origin gFrontEnd )
				)
				( attribute "ROT" "0"
					( Origin gFrontEnd )
				)
				( attribute "SEC" "1"
					( Origin gFrontEnd )
				)
				( attribute "SEC_TYPE" "0402LF"
					( Origin gFrontEnd )
				)
				( attribute "TOLERANCE" "5%"
					( Origin gFrontEnd )
				)
				( attribute "VALUE" "47.0PF"
					( Origin gFrontEnd )
				)
				( attribute "VER" "1"
					( Origin gFrontEnd )
				)
				( attribute "VOLTAGE" "50V"
					( Units "uVoltage" "V" 1.000000)
					( Origin gFrontEnd )
				)
				( attribute "XY" "(-4825,3250)"
					( Origin gFrontEnd )
				)
				( attribute "CHIPS_PART_NAME" "CAP"
					( Origin gPackager )
				)
				( attribute "CDS_PART_NAME" "CAP_0402LF-47.0PF,50V,5%,COG,AA"
					( Origin gPackager )
				)
				( objectStatus "C1U21" )
				( pin "a"
					( attribute "PN" "1"
						( Origin gPackager )
					)
					( objectStatus "C1U21.1" )
				)
				( pin "b"
					( attribute "PN" "2"
						( Origin gPackager )
					)
					( objectStatus "C1U21.2" )
				)
			)
			( gate "@baseboard_fab2_lib.baseboard_fab2(sch_1):page169_i57"
				( attribute "BOM_COST" "SM_HM"
					( Origin gFrontEnd )
				)
				( attribute "CDS_LIB" "mstr_discrete"
					( Origin gPackager )
				)
				( attribute "CDS_LOCATION" "FB1U3"
					( Origin gPackager )
				)
				( attribute "CDS_SEC" "1"
					( Origin gPackager )
				)
				( attribute "LOCATION" "FB1U3"
					( Origin gFrontEnd )
				)
				( attribute "MATERIAL" "FB"
					( Origin gFrontEnd )
				)
				( attribute "PACK_TYPE" "SMLF"
					( Origin gFrontEnd )
				)
				( attribute "PART_NUMBER" "693286-021"
					( Origin gFrontEnd )
				)
				( attribute "PHYS_PAGE" "169"
					( Origin gFrontEnd )
				)
				( attribute "ROOM" "BMC_VOLT_MONITOR"
					( Origin gFrontEnd )
				)
				( attribute "ROT" "0"
					( Origin gFrontEnd )
				)
				( attribute "SEC" "1"
					( Origin gFrontEnd )
				)
				( attribute "SEC_TYPE" "SMLF"
					( Origin gFrontEnd )
				)
				( attribute "VALUE" "30"
					( Origin gFrontEnd )
				)
				( attribute "VER" "4"
					( Origin gFrontEnd )
				)
				( attribute "XY" "(-4825,3600)"
					( Origin gFrontEnd )
				)
				( attribute "CHIPS_PART_NAME" "FERRITE"
					( Origin gPackager )
				)
				( attribute "CDS_PART_NAME" "FERRITE_SMLF-30,FB,693286-021"
					( Origin gPackager )
				)
				( objectStatus "FB1U3" )
				( pin "a"
					( attribute "PN" "1"
						( Origin gPackager )
					)
					( objectStatus "FB1U3.1" )
				)
				( pin "b"
					( attribute "PN" "2"
						( Origin gPackager )
					)
					( objectStatus "FB1U3.2" )
				)
			)
			( gate "@baseboard_fab2_lib.baseboard_fab2(sch_1):page169_i68"
				( attribute "BOM_COST" "SM_HM"
					( Origin gFrontEnd )
				)
				( attribute "CDS_LIB" "mstr_discrete"
					( Origin gPackager )
				)
				( attribute "CDS_LOCATION" "C9G21"
					( Origin gPackager )
				)
				( attribute "CDS_SEC" "1"
					( Origin gPackager )
				)
				( attribute "LOCATION" "C9G21"
					( Origin gFrontEnd )
				)
				( attribute "MATERIAL" "COG"
					( Origin gFrontEnd )
				)
				( attribute "PACK_TYPE" "0402LF"
					( Origin gFrontEnd )
				)
				( attribute "PART_NUMBER" "A36095-025"
					( Origin gFrontEnd )
				)
				( attribute "PHYS_PAGE" "169"
					( Origin gFrontEnd )
				)
				( attribute "ROOM" "BMC_VOLT_MONITOR"
					( Origin gFrontEnd )
				)
				( attribute "ROT" "0"
					( Origin gFrontEnd )
				)
				( attribute "SEC" "1"
					( Origin gFrontEnd )
				)
				( attribute "SEC_TYPE" "0402LF"
					( Origin gFrontEnd )
				)
				( attribute "TOLERANCE" "5%"
					( Origin gFrontEnd )
				)
				( attribute "VALUE" "47.0PF"
					( Origin gFrontEnd )
				)
				( attribute "VER" "1"
					( Origin gFrontEnd )
				)
				( attribute "VOLTAGE" "50V"
					( Units "uVoltage" "V" 1.000000)
					( Origin gFrontEnd )
				)
				( attribute "XY" "(-2500,1350)"
					( Origin gFrontEnd )
				)
				( attribute "CHIPS_PART_NAME" "CAP"
					( Origin gPackager )
				)
				( attribute "CDS_PART_NAME" "CAP_0402LF-47.0PF,50V,5%,COG,AA"
					( Origin gPackager )
				)
				( objectStatus "C9G21" )
				( pin "a"
					( attribute "PN" "1"
						( Origin gPackager )
					)
					( objectStatus "C9G21.1" )
				)
				( pin "b"
					( attribute "PN" "2"
						( Origin gPackager )
					)
					( objectStatus "C9G21.2" )
				)
			)
			( gate "@baseboard_fab2_lib.baseboard_fab2(sch_1):page169_i80"
				( attribute "BOM_COST" "SM_HM"
					( Origin gFrontEnd )
				)
				( attribute "CDS_LIB" "mstr_discrete"
					( Origin gPackager )
				)
				( attribute "CDS_LOCATION" "C9G17"
					( Origin gPackager )
				)
				( attribute "CDS_SEC" "1"
					( Origin gPackager )
				)
				( attribute "LOCATION" "C9G17"
					( Origin gFrontEnd )
				)
				( attribute "MATERIAL" "COG"
					( Origin gFrontEnd )
				)
				( attribute "PACK_TYPE" "0402LF"
					( Origin gFrontEnd )
				)
				( attribute "PART_NUMBER" "A36095-025"
					( Origin gFrontEnd )
				)
				( attribute "PHYS_PAGE" "169"
					( Origin gFrontEnd )
				)
				( attribute "ROOM" "BMC_VOLT_MONITOR"
					( Origin gFrontEnd )
				)
				( attribute "ROT" "0"
					( Origin gFrontEnd )
				)
				( attribute "SEC" "1"
					( Origin gFrontEnd )
				)
				( attribute "SEC_TYPE" "0402LF"
					( Origin gFrontEnd )
				)
				( attribute "TOLERANCE" "5%"
					( Origin gFrontEnd )
				)
				( attribute "VALUE" "47.0PF"
					( Origin gFrontEnd )
				)
				( attribute "VER" "1"
					( Origin gFrontEnd )
				)
				( attribute "VOLTAGE" "50V"
					( Units "uVoltage" "V" 1.000000)
					( Origin gFrontEnd )
				)
				( attribute "XY" "(-775,1450)"
					( Origin gFrontEnd )
				)
				( attribute "CHIPS_PART_NAME" "CAP"
					( Origin gPackager )
				)
				( attribute "CDS_PART_NAME" "CAP_0402LF-47.0PF,50V,5%,COG,AA"
					( Origin gPackager )
				)
				( objectStatus "C9G17" )
				( pin "a"
					( attribute "PN" "1"
						( Origin gPackager )
					)
					( objectStatus "C9G17.1" )
				)
				( pin "b"
					( attribute "PN" "2"
						( Origin gPackager )
					)
					( objectStatus "C9G17.2" )
				)
			)
			( gate "@baseboard_fab2_lib.baseboard_fab2(sch_1):page169_i82"
				( attribute "BOM_COST" "SM_HM"
					( Origin gFrontEnd )
				)
				( attribute "CDS_LIB" "mstr_discrete"
					( Origin gPackager )
				)
				( attribute "CDS_LOCATION" "R1U32"
					( Origin gPackager )
				)
				( attribute "CDS_SEC" "1"
					( Origin gPackager )
				)
				( attribute "LOCATION" "R1U32"
					( Origin gFrontEnd )
				)
				( attribute "MATERIAL" "CHIP"
					( Origin gFrontEnd )
				)
				( attribute "PACK_TYPE" "0402"
					( Origin gFrontEnd )
				)
				( attribute "PART_NUMBER" "G21796-140"
					( Origin gFrontEnd )
				)
				( attribute "PHYS_PAGE" "169"
					( Origin gFrontEnd )
				)
				( attribute "ROOM" "BMC_VOLT_MONITOR"
					( Origin gFrontEnd )
				)
				( attribute "ROT" "0"
					( Origin gFrontEnd )
				)
				( attribute "SEC" "1"
					( Origin gFrontEnd )
				)
				( attribute "SEC_TYPE" "0402"
					( Origin gFrontEnd )
				)
				( attribute "TOLERANCE" "1%"
					( Origin gFrontEnd )
				)
				( attribute "VALUE" "5.11K"
					( Origin gFrontEnd )
				)
				( attribute "VER" "2"
					( Origin gFrontEnd )
				)
				( attribute "WATTAGE" "1/16W"
					( Origin gFrontEnd )
				)
				( attribute "XY" "(-1125,1825)"
					( Origin gFrontEnd )
				)
				( attribute "CHIPS_PART_NAME" "RES"
					( Origin gPackager )
				)
				( attribute "CDS_PART_NAME" "RES_0402-5.11K,1%,1/16W,CHIP,GA"
					( Origin gPackager )
				)
				( objectStatus "R1U32" )
				( pin "a"
					( attribute "PN" "1"
						( Origin gPackager )
					)
					( objectStatus "R1U32.1" )
				)
				( pin "b"
					( attribute "PN" "2"
						( Origin gPackager )
					)
					( objectStatus "R1U32.2" )
				)
			)
			( gate "@baseboard_fab2_lib.baseboard_fab2(sch_1):page169_i83"
				( attribute "BOM_COST" "SM_HM"
					( Origin gFrontEnd )
				)
				( attribute "CDS_LIB" "mstr_discrete"
					( Origin gPackager )
				)
				( attribute "CDS_LOCATION" "R1U33"
					( Origin gPackager )
				)
				( attribute "CDS_SEC" "1"
					( Origin gPackager )
				)
				( attribute "LOCATION" "R1U33"
					( Origin gFrontEnd )
				)
				( attribute "MATERIAL" "CHIP"
					( Origin gFrontEnd )
				)
				( attribute "PACK_TYPE" "0402"
					( Origin gFrontEnd )
				)
				( attribute "PART_NUMBER" "G21796-026"
					( Origin gFrontEnd )
				)
				( attribute "PHYS_PAGE" "169"
					( Origin gFrontEnd )
				)
				( attribute "ROOM" "BMC_VOLT_MONITOR"
					( Origin gFrontEnd )
				)
				( attribute "ROT" "0"
					( Origin gFrontEnd )
				)
				( attribute "SEC" "1"
					( Origin gFrontEnd )
				)
				( attribute "SEC_TYPE" "0402"
					( Origin gFrontEnd )
				)
				( attribute "TOLERANCE" "1%"
					( Origin gFrontEnd )
				)
				( attribute "VALUE" "1.00K"
					( Origin gFrontEnd )
				)
				( attribute "VER" "2"
					( Origin gFrontEnd )
				)
				( attribute "WATTAGE" "1/16W"
					( Origin gFrontEnd )
				)
				( attribute "XY" "(-1125,1450)"
					( Origin gFrontEnd )
				)
				( attribute "CHIPS_PART_NAME" "RES"
					( Origin gPackager )
				)
				( attribute "CDS_PART_NAME" "RES_0402-1.00K,1%,1/16W,CHIP,GA"
					( Origin gPackager )
				)
				( objectStatus "R1U33" )
				( pin "a"
					( attribute "PN" "1"
						( Origin gPackager )
					)
					( objectStatus "R1U33.1" )
				)
				( pin "b"
					( attribute "PN" "2"
						( Origin gPackager )
					)
					( objectStatus "R1U33.2" )
				)
			)
			( gate "@baseboard_fab2_lib.baseboard_fab2(sch_1):page169_i86"
				( attribute "BOM_COST" "SM_HM"
					( Origin gFrontEnd )
				)
				( attribute "CDS_LIB" "mstr_discrete"
					( Origin gPackager )
				)
				( attribute "CDS_LOCATION" "C9G20"
					( Origin gPackager )
				)
				( attribute "CDS_SEC" "1"
					( Origin gPackager )
				)
				( attribute "LOCATION" "C9G20"
					( Origin gFrontEnd )
				)
				( attribute "MATERIAL" "COG"
					( Origin gFrontEnd )
				)
				( attribute "PACK_TYPE" "0402LF"
					( Origin gFrontEnd )
				)
				( attribute "PART_NUMBER" "A36095-025"
					( Origin gFrontEnd )
				)
				( attribute "PHYS_PAGE" "169"
					( Origin gFrontEnd )
				)
				( attribute "ROOM" "BMC_VOLT_MONITOR"
					( Origin gFrontEnd )
				)
				( attribute "ROT" "0"
					( Origin gFrontEnd )
				)
				( attribute "SEC" "1"
					( Origin gFrontEnd )
				)
				( attribute "SEC_TYPE" "0402LF"
					( Origin gFrontEnd )
				)
				( attribute "TOLERANCE" "5%"
					( Origin gFrontEnd )
				)
				( attribute "VALUE" "47.0PF"
					( Origin gFrontEnd )
				)
				( attribute "VER" "1"
					( Origin gFrontEnd )
				)
				( attribute "VOLTAGE" "50V"
					( Units "uVoltage" "V" 1.000000)
					( Origin gFrontEnd )
				)
				( attribute "XY" "(-4525,1425)"
					( Origin gFrontEnd )
				)
				( attribute "CHIPS_PART_NAME" "CAP"
					( Origin gPackager )
				)
				( attribute "CDS_PART_NAME" "CAP_0402LF-47.0PF,50V,5%,COG,AA"
					( Origin gPackager )
				)
				( objectStatus "C9G20" )
				( pin "a"
					( attribute "PN" "1"
						( Origin gPackager )
					)
					( objectStatus "C9G20.1" )
				)
				( pin "b"
					( attribute "PN" "2"
						( Origin gPackager )
					)
					( objectStatus "C9G20.2" )
				)
			)
			( gate "@baseboard_fab2_lib.baseboard_fab2(sch_1):page169_i88"
				( attribute "BOM_COST" "SM_HM"
					( Origin gFrontEnd )
				)
				( attribute "CDS_LIB" "mstr_discrete"
					( Origin gPackager )
				)
				( attribute "CDS_LOCATION" "R1U39"
					( Origin gPackager )
				)
				( attribute "CDS_SEC" "1"
					( Origin gPackager )
				)
				( attribute "LOCATION" "R1U39"
					( Origin gFrontEnd )
				)
				( attribute "MATERIAL" "CHIP"
					( Origin gFrontEnd )
				)
				( attribute "PACK_TYPE" "0402"
					( Origin gFrontEnd )
				)
				( attribute "PART_NUMBER" "G21796-140"
					( Origin gFrontEnd )
				)
				( attribute "PHYS_PAGE" "169"
					( Origin gFrontEnd )
				)
				( attribute "ROOM" "BMC_VOLT_MONITOR"
					( Origin gFrontEnd )
				)
				( attribute "ROT" "0"
					( Origin gFrontEnd )
				)
				( attribute "SEC" "1"
					( Origin gFrontEnd )
				)
				( attribute "SEC_TYPE" "0402"
					( Origin gFrontEnd )
				)
				( attribute "TOLERANCE" "1%"
					( Origin gFrontEnd )
				)
				( attribute "VALUE" "5.11K"
					( Origin gFrontEnd )
				)
				( attribute "VER" "2"
					( Origin gFrontEnd )
				)
				( attribute "WATTAGE" "1/16W"
					( Origin gFrontEnd )
				)
				( attribute "XY" "(-4825,1800)"
					( Origin gFrontEnd )
				)
				( attribute "CHIPS_PART_NAME" "RES"
					( Origin gPackager )
				)
				( attribute "CDS_PART_NAME" "RES_0402-5.11K,1%,1/16W,CHIP,GA"
					( Origin gPackager )
				)
				( objectStatus "R1U39" )
				( pin "a"
					( attribute "PN" "1"
						( Origin gPackager )
					)
					( objectStatus "R1U39.1" )
				)
				( pin "b"
					( attribute "PN" "2"
						( Origin gPackager )
					)
					( objectStatus "R1U39.2" )
				)
			)
			( gate "@baseboard_fab2_lib.baseboard_fab2(sch_1):page169_i106"
				( attribute "BOM_COST" "SM_HM"
					( Origin gFrontEnd )
				)
				( attribute "CDS_LIB" "mstr_discrete"
					( Origin gPackager )
				)
				( attribute "CDS_LOCATION" "R9G26"
					( Origin gPackager )
				)
				( attribute "CDS_SEC" "1"
					( Origin gPackager )
				)
				( attribute "LOCATION" "R9G26"
					( Origin gFrontEnd )
				)
				( attribute "MATERIAL" "CHIP"
					( Origin gFrontEnd )
				)
				( attribute "PACK_TYPE" "0402"
					( Origin gFrontEnd )
				)
				( attribute "PART_NUMBER" "G21796-010"
					( Origin gFrontEnd )
				)
				( attribute "PHYS_PAGE" "169"
					( Origin gFrontEnd )
				)
				( attribute "ROOM" "BMC_VOLT_MONITOR"
					( Origin gFrontEnd )
				)
				( attribute "ROT" "0"
					( Origin gFrontEnd )
				)
				( attribute "SEC" "1"
					( Origin gFrontEnd )
				)
				( attribute "SEC_TYPE" "0402"
					( Origin gFrontEnd )
				)
				( attribute "TOLERANCE" "1%"
					( Origin gFrontEnd )
				)
				( attribute "VALUE" "100.0K"
					( Origin gFrontEnd )
				)
				( attribute "VER" "2"
					( Origin gFrontEnd )
				)
				( attribute "WATTAGE" "1/16W"
					( Origin gFrontEnd )
				)
				( attribute "XY" "(400,2725)"
					( Origin gFrontEnd )
				)
				( attribute "CHIPS_PART_NAME" "RES"
					( Origin gPackager )
				)
				( attribute "CDS_PART_NAME" "RES_0402-100.0K,1%,1/16W,CHIP,A"
					( Origin gPackager )
				)
				( objectStatus "R9G26" )
				( pin "a"
					( attribute "PN" "1"
						( Origin gPackager )
					)
					( objectStatus "R9G26.1" )
				)
				( pin "b"
					( attribute "PN" "2"
						( Origin gPackager )
					)
					( objectStatus "R9G26.2" )
				)
			)
			( gate "@baseboard_fab2_lib.baseboard_fab2(sch_1):page169_i108"
				( attribute "BOM_COST" "SM_HM"
					( Origin gFrontEnd )
				)
				( attribute "CDS_LIB" "mstr_discrete"
					( Origin gPackager )
				)
				( attribute "CDS_LOCATION" "C9G22"
					( Origin gPackager )
				)
				( attribute "CDS_SEC" "1"
					( Origin gPackager )
				)
				( attribute "LOCATION" "C9G22"
					( Origin gFrontEnd )
				)
				( attribute "MATERIAL" "COG"
					( Origin gFrontEnd )
				)
				( attribute "PACK_TYPE" "0402LF"
					( Origin gFrontEnd )
				)
				( attribute "PART_NUMBER" "A36094-025"
					( Origin gFrontEnd )
				)
				( attribute "PHYS_PAGE" "169"
					( Origin gFrontEnd )
				)
				( attribute "ROOM" "BMC_VOLT_MONITOR"
					( Origin gFrontEnd )
				)
				( attribute "ROT" "0"
					( Origin gFrontEnd )
				)
				( attribute "SEC" "1"
					( Origin gFrontEnd )
				)
				( attribute "SEC_TYPE" "0402LF"
					( Origin gFrontEnd )
				)
				( attribute "TOLERANCE" "5%"
					( Origin gFrontEnd )
				)
				( attribute "VALUE" "10.0PF"
					( Origin gFrontEnd )
				)
				( attribute "VER" "1"
					( Origin gFrontEnd )
				)
				( attribute "VOLTAGE" "50V"
					( Units "uVoltage" "V" 1.000000)
					( Origin gFrontEnd )
				)
				( attribute "XY" "(800,2700)"
					( Origin gFrontEnd )
				)
				( attribute "CHIPS_PART_NAME" "CAP"
					( Origin gPackager )
				)
				( attribute "CDS_PART_NAME" "CAP_0402LF-10.0PF,50V,5%,COG,AA"
					( Origin gPackager )
				)
				( objectStatus "C9G22" )
				( pin "a"
					( attribute "PN" "1"
						( Origin gPackager )
					)
					( objectStatus "C9G22.1" )
				)
				( pin "b"
					( attribute "PN" "2"
						( Origin gPackager )
					)
					( objectStatus "C9G22.2" )
				)
			)
			( gate "@baseboard_fab2_lib.baseboard_fab2(sch_1):page169_i114"
				( attribute "BOM_COST" "SM_HM"
					( Origin gFrontEnd )
				)
				( attribute "CDS_LIB" "mstr_discrete"
					( Origin gPackager )
				)
				( attribute "CDS_LOCATION" "R1U38"
					( Origin gPackager )
				)
				( attribute "CDS_SEC" "1"
					( Origin gPackager )
				)
				( attribute "LOCATION" "R1U38"
					( Origin gFrontEnd )
				)
				( attribute "MATERIAL" "CHIP"
					( Origin gFrontEnd )
				)
				( attribute "PACK_TYPE" "0402"
					( Origin gFrontEnd )
				)
				( attribute "PART_NUMBER" "G21796-345"
					( Origin gFrontEnd )
				)
				( attribute "PHYS_PAGE" "169"
					( Origin gFrontEnd )
				)
				( attribute "ROOM" "BMC_VOLT_MONITOR"
					( Origin gFrontEnd )
				)
				( attribute "ROT" "0"
					( Origin gFrontEnd )
				)
				( attribute "SEC" "1"
					( Origin gFrontEnd )
				)
				( attribute "SEC_TYPE" "0402"
					( Origin gFrontEnd )
				)
				( attribute "TOLERANCE" "1%"
					( Origin gFrontEnd )
				)
				( attribute "VALUE" "8.2K"
					( Origin gFrontEnd )
				)
				( attribute "VER" "2"
					( Origin gFrontEnd )
				)
				( attribute "WATTAGE" "1/16W"
					( Origin gFrontEnd )
				)
				( attribute "XY" "(-4825,1425)"
					( Origin gFrontEnd )
				)
				( attribute "CHIPS_PART_NAME" "RES"
					( Origin gPackager )
				)
				( attribute "CDS_PART_NAME" "RES_0402-8.2K,1%,1/16W,CHIP,G2A"
					( Origin gPackager )
				)
				( objectStatus "R1U38" )
				( pin "a"
					( attribute "PN" "1"
						( Origin gPackager )
					)
					( objectStatus "R1U38.1" )
				)
				( pin "b"
					( attribute "PN" "2"
						( Origin gPackager )
					)
					( objectStatus "R1U38.2" )
				)
			)
			( gate "@baseboard_fab2_lib.baseboard_fab2(sch_1):page169_i115"
				( attribute "BOM_COST" "SM_HM"
					( Origin gFrontEnd )
				)
				( attribute "CDS_LIB" "mstr_discrete"
					( Origin gPackager )
				)
				( attribute "CDS_LOCATION" "R1U47"
					( Origin gPackager )
				)
				( attribute "CDS_SEC" "1"
					( Origin gPackager )
				)
				( attribute "LOCATION" "R1U47"
					( Origin gFrontEnd )
				)
				( attribute "MATERIAL" "CHIP"
					( Origin gFrontEnd )
				)
				( attribute "PACK_TYPE" "0402"
					( Origin gFrontEnd )
				)
				( attribute "PART_NUMBER" "G21796-140"
					( Origin gFrontEnd )
				)
				( attribute "PHYS_PAGE" "169"
					( Origin gFrontEnd )
				)
				( attribute "ROOM" "BMC_VOLT_MONITOR"
					( Origin gFrontEnd )
				)
				( attribute "ROT" "0"
					( Origin gFrontEnd )
				)
				( attribute "SEC" "1"
					( Origin gFrontEnd )
				)
				( attribute "SEC_TYPE" "0402"
					( Origin gFrontEnd )
				)
				( attribute "TOLERANCE" "1%"
					( Origin gFrontEnd )
				)
				( attribute "VALUE" "5.11K"
					( Origin gFrontEnd )
				)
				( attribute "VER" "2"
					( Origin gFrontEnd )
				)
				( attribute "WATTAGE" "1/16W"
					( Origin gFrontEnd )
				)
				( attribute "XY" "(-2850,1750)"
					( Origin gFrontEnd )
				)
				( attribute "CHIPS_PART_NAME" "RES"
					( Origin gPackager )
				)
				( attribute "CDS_PART_NAME" "RES_0402-5.11K,1%,1/16W,CHIP,GA"
					( Origin gPackager )
				)
				( objectStatus "R1U47" )
				( pin "a"
					( attribute "PN" "1"
						( Origin gPackager )
					)
					( objectStatus "R1U47.1" )
				)
				( pin "b"
					( attribute "PN" "2"
						( Origin gPackager )
					)
					( objectStatus "R1U47.2" )
				)
			)
			( gate "@baseboard_fab2_lib.baseboard_fab2(sch_1):page169_i116"
				( attribute "BOM_COST" "SM_HM"
					( Origin gFrontEnd )
				)
				( attribute "CDS_LIB" "mstr_discrete"
					( Origin gPackager )
				)
				( attribute "CDS_LOCATION" "R1U44"
					( Origin gPackager )
				)
				( attribute "CDS_SEC" "1"
					( Origin gPackager )
				)
				( attribute "LOCATION" "R1U44"
					( Origin gFrontEnd )
				)
				( attribute "MATERIAL" "CHIP"
					( Origin gFrontEnd )
				)
				( attribute "PACK_TYPE" "0402"
					( Origin gFrontEnd )
				)
				( attribute "PART_NUMBER" "G21796-279"
					( Origin gFrontEnd )
				)
				( attribute "PHYS_PAGE" "169"
					( Origin gFrontEnd )
				)
				( attribute "ROOM" "BMC_VOLT_MONITOR"
					( Origin gFrontEnd )
				)
				( attribute "ROT" "0"
					( Origin gFrontEnd )
				)
				( attribute "SEC" "1"
					( Origin gPackager )
				)
				( attribute "TOLERANCE" "1.0%"
					( Origin gFrontEnd )
				)
				( attribute "VALUE" "3.48K"
					( Origin gFrontEnd )
				)
				( attribute "VER" "2"
					( Origin gFrontEnd )
				)
				( attribute "WATTAGE" "1/16W"
					( Origin gFrontEnd )
				)
				( attribute "XY" "(-2850,1350)"
					( Origin gFrontEnd )
				)
				( attribute "CHIPS_PART_NAME" "RES"
					( Origin gPackager )
				)
				( attribute "CDS_PART_NAME" "RES_0402-3.48K,1.0%,1/16W,CHIPA"
					( Origin gPackager )
				)
				( objectStatus "R1U44" )
				( pin "a"
					( attribute "PN" "1"
						( Origin gPackager )
					)
					( objectStatus "R1U44.1" )
				)
				( pin "b"
					( attribute "PN" "2"
						( Origin gPackager )
					)
					( objectStatus "R1U44.2" )
				)
			)
			( gate "@baseboard_fab2_lib.baseboard_fab2(sch_1):page169_i126"
				( attribute "BOM_COST" "SM_HM"
					( Origin gFrontEnd )
				)
				( attribute "CDS_LIB" "mstr_discrete"
					( Origin gPackager )
				)
				( attribute "CDS_LOCATION" "R1U50"
					( Origin gPackager )
				)
				( attribute "CDS_SEC" "1"
					( Origin gPackager )
				)
				( attribute "LOCATION" "R1U50"
					( Origin gFrontEnd )
				)
				( attribute "MATERIAL" "CHIP"
					( Origin gFrontEnd )
				)
				( attribute "PACK_TYPE" "0402"
					( Origin gFrontEnd )
				)
				( attribute "PART_NUMBER" "G21796-080"
					( Origin gFrontEnd )
				)
				( attribute "PHYS_PAGE" "169"
					( Origin gFrontEnd )
				)
				( attribute "ROOM" "BMC_VOLT_MONITOR"
					( Origin gFrontEnd )
				)
				( attribute "ROT" "0"
					( Origin gFrontEnd )
				)
				( attribute "SEC" "1"
					( Origin gFrontEnd )
				)
				( attribute "SEC_TYPE" "0402"
					( Origin gFrontEnd )
				)
				( attribute "TOLERANCE" "1%"
					( Origin gFrontEnd )
				)
				( attribute "VALUE" "200.0K"
					( Origin gFrontEnd )
				)
				( attribute "VER" "2"
					( Origin gFrontEnd )
				)
				( attribute "WATTAGE" "1/16W"
					( Origin gFrontEnd )
				)
				( attribute "XY" "(200,4025)"
					( Origin gFrontEnd )
				)
				( attribute "CHIPS_PART_NAME" "RES"
					( Origin gPackager )
				)
				( attribute "CDS_PART_NAME" "RES_0402-200.0K,1%,1/16W,CHIP,A"
					( Origin gPackager )
				)
				( objectStatus "R1U50" )
				( pin "a"
					( attribute "PN" "1"
						( Origin gPackager )
					)
					( objectStatus "R1U50.1" )
				)
				( pin "b"
					( attribute "PN" "2"
						( Origin gPackager )
					)
					( objectStatus "R1U50.2" )
				)
			)
			( gate "@baseboard_fab2_lib.baseboard_fab2(sch_1):page169_i139"
				( attribute "BOM_COST" "SM_HM"
					( Origin gFrontEnd )
				)
				( attribute "CDS_LIB" "mstr_discrete"
					( Origin gPackager )
				)
				( attribute "CDS_LOCATION" "C9G15"
					( Origin gPackager )
				)
				( attribute "CDS_SEC" "1"
					( Origin gPackager )
				)
				( attribute "LOCATION" "C9G15"
					( Origin gFrontEnd )
				)
				( attribute "MATERIAL" "COG"
					( Origin gFrontEnd )
				)
				( attribute "PACK_TYPE" "0402LF"
					( Origin gFrontEnd )
				)
				( attribute "PART_NUMBER" "A36095-025"
					( Origin gFrontEnd )
				)
				( attribute "PHYS_PAGE" "169"
					( Origin gFrontEnd )
				)
				( attribute "ROOM" "BMC_VOLT_MONITOR"
					( Origin gFrontEnd )
				)
				( attribute "ROT" "0"
					( Origin gFrontEnd )
				)
				( attribute "SEC" "1"
					( Origin gFrontEnd )
				)
				( attribute "SEC_TYPE" "0402LF"
					( Origin gFrontEnd )
				)
				( attribute "TOLERANCE" "5%"
					( Origin gFrontEnd )
				)
				( attribute "VALUE" "47.0PF"
					( Origin gFrontEnd )
				)
				( attribute "VER" "1"
					( Origin gFrontEnd )
				)
				( attribute "VOLTAGE" "50V"
					( Units "uVoltage" "V" 1.000000)
					( Origin gFrontEnd )
				)
				( attribute "XY" "(-4350,4550)"
					( Origin gFrontEnd )
				)
				( attribute "CHIPS_PART_NAME" "CAP"
					( Origin gPackager )
				)
				( attribute "CDS_PART_NAME" "CAP_0402LF-47.0PF,50V,5%,COG,AA"
					( Origin gPackager )
				)
				( objectStatus "C9G15" )
				( pin "a"
					( attribute "PN" "1"
						( Origin gPackager )
					)
					( objectStatus "C9G15.1" )
				)
				( pin "b"
					( attribute "PN" "2"
						( Origin gPackager )
					)
					( objectStatus "C9G15.2" )
				)
			)
			( gate "@baseboard_fab2_lib.baseboard_fab2(sch_1):page169_i141"
				( attribute "BOM_COST" "SM_HM"
					( Origin gFrontEnd )
				)
				( attribute "CDS_LIB" "mstr_discrete"
					( Origin gPackager )
				)
				( attribute "CDS_LOCATION" "R1U29"
					( Origin gPackager )
				)
				( attribute "CDS_SEC" "1"
					( Origin gPackager )
				)
				( attribute "LOCATION" "R1U29"
					( Origin gFrontEnd )
				)
				( attribute "MATERIAL" "CHIP"
					( Origin gFrontEnd )
				)
				( attribute "PACK_TYPE" "0402"
					( Origin gFrontEnd )
				)
				( attribute "PART_NUMBER" "G21796-140"
					( Origin gFrontEnd )
				)
				( attribute "PHYS_PAGE" "169"
					( Origin gFrontEnd )
				)
				( attribute "ROOM" "BMC_VOLT_MONITOR"
					( Origin gFrontEnd )
				)
				( attribute "ROT" "0"
					( Origin gFrontEnd )
				)
				( attribute "SEC" "1"
					( Origin gFrontEnd )
				)
				( attribute "SEC_TYPE" "0402"
					( Origin gFrontEnd )
				)
				( attribute "TOLERANCE" "1%"
					( Origin gFrontEnd )
				)
				( attribute "VALUE" "5.11K"
					( Origin gFrontEnd )
				)
				( attribute "VER" "2"
					( Origin gFrontEnd )
				)
				( attribute "WATTAGE" "1/16W"
					( Origin gFrontEnd )
				)
				( attribute "XY" "(-4700,4950)"
					( Origin gFrontEnd )
				)
				( attribute "CHIPS_PART_NAME" "RES"
					( Origin gPackager )
				)
				( attribute "CDS_PART_NAME" "RES_0402-5.11K,1%,1/16W,CHIP,GA"
					( Origin gPackager )
				)
				( objectStatus "R1U29" )
				( pin "a"
					( attribute "PN" "1"
						( Origin gPackager )
					)
					( objectStatus "R1U29.1" )
				)
				( pin "b"
					( attribute "PN" "2"
						( Origin gPackager )
					)
					( objectStatus "R1U29.2" )
				)
			)
			( gate "@baseboard_fab2_lib.baseboard_fab2(sch_1):page169_i142"
				( attribute "BOM_COST" "SM_HM"
					( Origin gFrontEnd )
				)
				( attribute "CDS_LIB" "mstr_discrete"
					( Origin gPackager )
				)
				( attribute "CDS_LOCATION" "R1U28"
					( Origin gPackager )
				)
				( attribute "CDS_SEC" "1"
					( Origin gPackager )
				)
				( attribute "LOCATION" "R1U28"
					( Origin gFrontEnd )
				)
				( attribute "MATERIAL" "CHIP"
					( Origin gFrontEnd )
				)
				( attribute "PACK_TYPE" "0402"
					( Origin gFrontEnd )
				)
				( attribute "PART_NUMBER" "G21796-279"
					( Origin gFrontEnd )
				)
				( attribute "PHYS_PAGE" "169"
					( Origin gFrontEnd )
				)
				( attribute "ROOM" "BMC_VOLT_MONITOR"
					( Origin gFrontEnd )
				)
				( attribute "ROT" "0"
					( Origin gFrontEnd )
				)
				( attribute "SEC" "1"
					( Origin gFrontEnd )
				)
				( attribute "SEC_TYPE" "0402"
					( Origin gFrontEnd )
				)
				( attribute "TOLERANCE" "1.0%"
					( Origin gFrontEnd )
				)
				( attribute "VALUE" "3.48K"
					( Origin gFrontEnd )
				)
				( attribute "VER" "2"
					( Origin gFrontEnd )
				)
				( attribute "WATTAGE" "1/16W"
					( Origin gFrontEnd )
				)
				( attribute "XY" "(-4700,4550)"
					( Origin gFrontEnd )
				)
				( attribute "CHIPS_PART_NAME" "RES"
					( Origin gPackager )
				)
				( attribute "CDS_PART_NAME" "RES_0402-3.48K,1.0%,1/16W,CHIPA"
					( Origin gPackager )
				)
				( objectStatus "R1U28" )
				( pin "a"
					( attribute "PN" "1"
						( Origin gPackager )
					)
					( objectStatus "R1U28.1" )
				)
				( pin "b"
					( attribute "PN" "2"
						( Origin gPackager )
					)
					( objectStatus "R1U28.2" )
				)
			)
			( gate "@baseboard_fab2_lib.baseboard_fab2(sch_1):page169_i146"
				( attribute "BOM_COST" "SM_HM"
					( Origin gFrontEnd )
				)
				( attribute "CDS_LIB" "mstr_discrete"
					( Origin gPackager )
				)
				( attribute "CDS_LOCATION" "C9G14"
					( Origin gPackager )
				)
				( attribute "CDS_SEC" "1"
					( Origin gPackager )
				)
				( attribute "LOCATION" "C9G14"
					( Origin gFrontEnd )
				)
				( attribute "MATERIAL" "COG"
					( Origin gFrontEnd )
				)
				( attribute "PACK_TYPE" "0402LF"
					( Origin gFrontEnd )
				)
				( attribute "PART_NUMBER" "A36095-025"
					( Origin gFrontEnd )
				)
				( attribute "PHYS_PAGE" "169"
					( Origin gFrontEnd )
				)
				( attribute "ROOM" "BMC_VOLT_MONITOR"
					( Origin gFrontEnd )
				)
				( attribute "ROT" "0"
					( Origin gFrontEnd )
				)
				( attribute "SEC" "1"
					( Origin gFrontEnd )
				)
				( attribute "SEC_TYPE" "0402LF"
					( Origin gFrontEnd )
				)
				( attribute "TOLERANCE" "5%"
					( Origin gFrontEnd )
				)
				( attribute "VALUE" "47.0PF"
					( Origin gFrontEnd )
				)
				( attribute "VER" "1"
					( Origin gFrontEnd )
				)
				( attribute "VOLTAGE" "50V"
					( Units "uVoltage" "V" 1.000000)
					( Origin gFrontEnd )
				)
				( attribute "XY" "(-2550,4600)"
					( Origin gFrontEnd )
				)
				( attribute "CHIPS_PART_NAME" "CAP"
					( Origin gPackager )
				)
				( attribute "CDS_PART_NAME" "CAP_0402LF-47.0PF,50V,5%,COG,AA"
					( Origin gPackager )
				)
				( objectStatus "C9G14" )
				( pin "a"
					( attribute "PN" "1"
						( Origin gPackager )
					)
					( objectStatus "C9G14.1" )
				)
				( pin "b"
					( attribute "PN" "2"
						( Origin gPackager )
					)
					( objectStatus "C9G14.2" )
				)
			)
			( gate "@baseboard_fab2_lib.baseboard_fab2(sch_1):page169_i148"
				( attribute "BOM_COST" "SM_HM"
					( Origin gFrontEnd )
				)
				( attribute "CDS_LIB" "mstr_discrete"
					( Origin gPackager )
				)
				( attribute "CDS_LOCATION" "R1U26"
					( Origin gPackager )
				)
				( attribute "CDS_SEC" "1"
					( Origin gPackager )
				)
				( attribute "LOCATION" "R1U26"
					( Origin gFrontEnd )
				)
				( attribute "MATERIAL" "CHIP"
					( Origin gFrontEnd )
				)
				( attribute "PACK_TYPE" "0402"
					( Origin gFrontEnd )
				)
				( attribute "PART_NUMBER" "G21796-140"
					( Origin gFrontEnd )
				)
				( attribute "PHYS_PAGE" "169"
					( Origin gFrontEnd )
				)
				( attribute "ROOM" "BMC_VOLT_MONITOR"
					( Origin gFrontEnd )
				)
				( attribute "ROT" "0"
					( Origin gFrontEnd )
				)
				( attribute "SEC" "1"
					( Origin gFrontEnd )
				)
				( attribute "SEC_TYPE" "0402"
					( Origin gFrontEnd )
				)
				( attribute "TOLERANCE" "1%"
					( Origin gFrontEnd )
				)
				( attribute "VALUE" "5.11K"
					( Origin gFrontEnd )
				)
				( attribute "VER" "2"
					( Origin gFrontEnd )
				)
				( attribute "WATTAGE" "1/16W"
					( Origin gFrontEnd )
				)
				( attribute "XY" "(-2875,5000)"
					( Origin gFrontEnd )
				)
				( attribute "CHIPS_PART_NAME" "RES"
					( Origin gPackager )
				)
				( attribute "CDS_PART_NAME" "RES_0402-5.11K,1%,1/16W,CHIP,GA"
					( Origin gPackager )
				)
				( objectStatus "R1U26" )
				( pin "a"
					( attribute "PN" "1"
						( Origin gPackager )
					)
					( objectStatus "R1U26.1" )
				)
				( pin "b"
					( attribute "PN" "2"
						( Origin gPackager )
					)
					( objectStatus "R1U26.2" )
				)
			)
			( gate "@baseboard_fab2_lib.baseboard_fab2(sch_1):page169_i149"
				( attribute "BOM_COST" "SM_HM"
					( Origin gFrontEnd )
				)
				( attribute "CDS_LIB" "mstr_discrete"
					( Origin gPackager )
				)
				( attribute "CDS_LOCATION" "R1U27"
					( Origin gPackager )
				)
				( attribute "CDS_SEC" "1"
					( Origin gPackager )
				)
				( attribute "LOCATION" "R1U27"
					( Origin gFrontEnd )
				)
				( attribute "MATERIAL" "CHIP"
					( Origin gFrontEnd )
				)
				( attribute "PACK_TYPE" "0402"
					( Origin gFrontEnd )
				)
				( attribute "PART_NUMBER" "G21796-345"
					( Origin gFrontEnd )
				)
				( attribute "PHYS_PAGE" "169"
					( Origin gFrontEnd )
				)
				( attribute "ROOM" "BMC_VOLT_MONITOR"
					( Origin gFrontEnd )
				)
				( attribute "ROT" "0"
					( Origin gFrontEnd )
				)
				( attribute "SEC" "1"
					( Origin gFrontEnd )
				)
				( attribute "SEC_TYPE" "0402"
					( Origin gFrontEnd )
				)
				( attribute "TOLERANCE" "1%"
					( Origin gFrontEnd )
				)
				( attribute "VALUE" "8.2K"
					( Origin gFrontEnd )
				)
				( attribute "VER" "2"
					( Origin gFrontEnd )
				)
				( attribute "WATTAGE" "1/16W"
					( Origin gFrontEnd )
				)
				( attribute "XY" "(-2875,4625)"
					( Origin gFrontEnd )
				)
				( attribute "CHIPS_PART_NAME" "RES"
					( Origin gPackager )
				)
				( attribute "CDS_PART_NAME" "RES_0402-8.2K,1%,1/16W,CHIP,G2A"
					( Origin gPackager )
				)
				( objectStatus "R1U27" )
				( pin "a"
					( attribute "PN" "1"
						( Origin gPackager )
					)
					( objectStatus "R1U27.1" )
				)
				( pin "b"
					( attribute "PN" "2"
						( Origin gPackager )
					)
					( objectStatus "R1U27.2" )
				)
			)
			( gate "@baseboard_fab2_lib.baseboard_fab2(sch_1):page169_i153"
				( attribute "BOM_COST" "SM_HM"
					( Origin gFrontEnd )
				)
				( attribute "CDS_LIB" "mstr_discrete"
					( Origin gPackager )
				)
				( attribute "CDS_LOCATION" "C9G18"
					( Origin gPackager )
				)
				( attribute "CDS_SEC" "1"
					( Origin gPackager )
				)
				( attribute "LOCATION" "C9G18"
					( Origin gFrontEnd )
				)
				( attribute "MATERIAL" "COG"
					( Origin gFrontEnd )
				)
				( attribute "PACK_TYPE" "0402LF"
					( Origin gFrontEnd )
				)
				( attribute "PART_NUMBER" "A36095-025"
					( Origin gFrontEnd )
				)
				( attribute "PHYS_PAGE" "169"
					( Origin gFrontEnd )
				)
				( attribute "ROOM" "BMC_VOLT_MONITOR"
					( Origin gFrontEnd )
				)
				( attribute "ROT" "0"
					( Origin gFrontEnd )
				)
				( attribute "SEC" "1"
					( Origin gFrontEnd )
				)
				( attribute "SEC_TYPE" "0402LF"
					( Origin gFrontEnd )
				)
				( attribute "TOLERANCE" "5%"
					( Origin gFrontEnd )
				)
				( attribute "VALUE" "47.0PF"
					( Origin gFrontEnd )
				)
				( attribute "VER" "1"
					( Origin gFrontEnd )
				)
				( attribute "VOLTAGE" "50V"
					( Units "uVoltage" "V" 1.000000)
					( Origin gFrontEnd )
				)
				( attribute "XY" "(800,1475)"
					( Origin gFrontEnd )
				)
				( attribute "CHIPS_PART_NAME" "CAP"
					( Origin gPackager )
				)
				( attribute "CDS_PART_NAME" "CAP_0402LF-47.0PF,50V,5%,COG,AA"
					( Origin gPackager )
				)
				( objectStatus "C9G18" )
				( pin "a"
					( attribute "PN" "1"
						( Origin gPackager )
					)
					( objectStatus "C9G18.1" )
				)
				( pin "b"
					( attribute "PN" "2"
						( Origin gPackager )
					)
					( objectStatus "C9G18.2" )
				)
			)
			( gate "@baseboard_fab2_lib.baseboard_fab2(sch_1):page169_i155"
				( attribute "BOM_COST" "SM_HM"
					( Origin gFrontEnd )
				)
				( attribute "CDS_LIB" "mstr_discrete"
					( Origin gPackager )
				)
				( attribute "CDS_LOCATION" "FB1U4"
					( Origin gPackager )
				)
				( attribute "CDS_SEC" "1"
					( Origin gPackager )
				)
				( attribute "LOCATION" "FB1U4"
					( Origin gFrontEnd )
				)
				( attribute "MATERIAL" "FB"
					( Origin gFrontEnd )
				)
				( attribute "PACK_TYPE" "SMLF"
					( Origin gFrontEnd )
				)
				( attribute "PART_NUMBER" "693286-021"
					( Origin gFrontEnd )
				)
				( attribute "PHYS_PAGE" "169"
					( Origin gFrontEnd )
				)
				( attribute "ROOM" "BMC_VOLT_MONITOR"
					( Origin gFrontEnd )
				)
				( attribute "ROT" "0"
					( Origin gFrontEnd )
				)
				( attribute "SEC" "1"
					( Origin gFrontEnd )
				)
				( attribute "SEC_TYPE" "SMLF"
					( Origin gFrontEnd )
				)
				( attribute "VALUE" "30"
					( Origin gFrontEnd )
				)
				( attribute "VER" "4"
					( Origin gFrontEnd )
				)
				( attribute "XY" "(800,1850)"
					( Origin gFrontEnd )
				)
				( attribute "CHIPS_PART_NAME" "FERRITE"
					( Origin gPackager )
				)
				( attribute "CDS_PART_NAME" "FERRITE_SMLF-30,FB,693286-021"
					( Origin gPackager )
				)
				( objectStatus "FB1U4" )
				( pin "a"
					( attribute "PN" "1"
						( Origin gPackager )
					)
					( objectStatus "FB1U4.1" )
				)
				( pin "b"
					( attribute "PN" "2"
						( Origin gPackager )
					)
					( objectStatus "FB1U4.2" )
				)
			)
			( gate "@baseboard_fab2_lib.baseboard_fab2(sch_1):page169_i157"
				( attribute "BOM_COST" "SM_HM"
					( Origin gFrontEnd )
				)
				( attribute "CDS_LIB" "mstr_discrete"
					( Origin gPackager )
				)
				( attribute "CDS_LOCATION" "Q9G1"
					( Origin gPackager )
				)
				( attribute "CDS_SEC" "2"
					( Origin gPackager )
				)
				( attribute "LOCATION" "Q9G1"
					( Origin gFrontEnd )
				)
				( attribute "MATERIAL" "FET"
					( Origin gFrontEnd )
				)
				( attribute "PACK_TYPE" "SMLF"
					( Origin gFrontEnd )
				)
				( attribute "PART_NUMBER" "E40049-001"
					( Origin gFrontEnd )
				)
				( attribute "PHYS_PAGE" "169"
					( Origin gFrontEnd )
				)
				( attribute "ROOM" "BMC_VOLT_MONITOR"
					( Origin gFrontEnd )
				)
				( attribute "ROT" "0"
					( Origin gFrontEnd )
				)
				( attribute "SEC" "2"
					( Origin gFrontEnd )
				)
				( attribute "SEC_TYPE" "SMLF"
					( Origin gFrontEnd )
				)
				( attribute "VALUE" "NTJD4001N"
					( Origin gFrontEnd )
				)
				( attribute "VER" "5"
					( Origin gFrontEnd )
				)
				( attribute "XY" "(200,3225)"
					( Origin gFrontEnd )
				)
				( attribute "CHIPS_PART_NAME" "FET_N_DUAL"
					( Origin gPackager )
				)
				( attribute "CDS_PART_NAME" "FET_N_DUAL_SMLF-NTJD4001N,FET,A"
					( Origin gPackager )
				)
				( objectStatus "Q9G1" )
				( pin "drain(0)"
					( attribute "PN" "3"
						( Origin gPackager )
					)
					( objectStatus "Q9G1.3" )
				)
				( pin "gate(0)"
					( attribute "PN" "5"
						( Origin gPackager )
					)
					( objectStatus "Q9G1.5" )
				)
				( pin "source(0)"
					( attribute "PN" "4"
						( Origin gPackager )
					)
					( objectStatus "Q9G1.4" )
				)
			)
			( gate "@baseboard_fab2_lib.baseboard_fab2(sch_1):page169_i162"
				( attribute "BOM_COST" "SM_HM"
					( Origin gFrontEnd )
				)
				( attribute "CDS_LIB" "mstr_discrete"
					( Origin gPackager )
				)
				( attribute "CDS_LOCATION" "Q9G1"
					( Origin gPackager )
				)
				( attribute "CDS_SEC" "1"
					( Origin gPackager )
				)
				( attribute "LOCATION" "Q9G1"
					( Origin gFrontEnd )
				)
				( attribute "MATERIAL" "FET"
					( Origin gFrontEnd )
				)
				( attribute "PACK_TYPE" "SMLF"
					( Origin gFrontEnd )
				)
				( attribute "PART_NUMBER" "E40049-001"
					( Origin gFrontEnd )
				)
				( attribute "PHYS_PAGE" "169"
					( Origin gFrontEnd )
				)
				( attribute "ROOM" "BMC_VOLT_MONITOR"
					( Origin gFrontEnd )
				)
				( attribute "ROT" "0"
					( Origin gFrontEnd )
				)
				( attribute "SEC" "1"
					( Origin gFrontEnd )
				)
				( attribute "SEC_TYPE" "SMLF"
					( Origin gFrontEnd )
				)
				( attribute "VALUE" "NTJD4001N"
					( Origin gFrontEnd )
				)
				( attribute "VER" "5"
					( Origin gFrontEnd )
				)
				( attribute "XY" "(-875,2900)"
					( Origin gFrontEnd )
				)
				( attribute "CHIPS_PART_NAME" "FET_N_DUAL"
					( Origin gPackager )
				)
				( attribute "CDS_PART_NAME" "FET_N_DUAL_SMLF-NTJD4001N,FET,A"
					( Origin gPackager )
				)
				( objectStatus "Q9G1" )
				( pin "drain(0)"
					( attribute "PN" "6"
						( Origin gPackager )
					)
					( objectStatus "Q9G1.6" )
				)
				( pin "gate(0)"
					( attribute "PN" "2"
						( Origin gPackager )
					)
					( objectStatus "Q9G1.2" )
				)
				( pin "source(0)"
					( attribute "PN" "1"
						( Origin gPackager )
					)
					( objectStatus "Q9G1.1" )
				)
			)
			( gate "@baseboard_fab2_lib.baseboard_fab2(sch_1):page169_i163"
				( attribute "BOM_COST" "SM_HM"
					( Origin gFrontEnd )
				)
				( attribute "CDS_LIB" "mstr_discrete"
					( Origin gPackager )
				)
				( attribute "CDS_LOCATION" "R1U49"
					( Origin gPackager )
				)
				( attribute "CDS_SEC" "1"
					( Origin gPackager )
				)
				( attribute "LOCATION" "R1U49"
					( Origin gFrontEnd )
				)
				( attribute "MATERIAL" "CHIP"
					( Origin gFrontEnd )
				)
				( attribute "PACK_TYPE" "0402"
					( Origin gFrontEnd )
				)
				( attribute "PART_NUMBER" "G21796-344"
					( Origin gFrontEnd )
				)
				( attribute "PHYS_PAGE" "169"
					( Origin gFrontEnd )
				)
				( attribute "ROOM" "BMC_VOLT_MONITOR"
					( Origin gFrontEnd )
				)
				( attribute "ROT" "0"
					( Origin gFrontEnd )
				)
				( attribute "SEC" "1"
					( Origin gFrontEnd )
				)
				( attribute "SEC_TYPE" "0402"
					( Origin gFrontEnd )
				)
				( attribute "TOLERANCE" "1%"
					( Origin gFrontEnd )
				)
				( attribute "VALUE" "2.7K"
					( Origin gFrontEnd )
				)
				( attribute "VER" "2"
					( Origin gFrontEnd )
				)
				( attribute "WATTAGE" "1/16W"
					( Origin gFrontEnd )
				)
				( attribute "XY" "(-650,3375)"
					( Origin gFrontEnd )
				)
				( attribute "CHIPS_PART_NAME" "RES"
					( Origin gPackager )
				)
				( attribute "CDS_PART_NAME" "RES_0402-2.7K,1%,1/16W,CHIP,G2A"
					( Origin gPackager )
				)
				( objectStatus "R1U49" )
				( pin "a"
					( attribute "PN" "1"
						( Origin gPackager )
					)
					( objectStatus "R1U49.1" )
				)
				( pin "b"
					( attribute "PN" "2"
						( Origin gPackager )
					)
					( objectStatus "R1U49.2" )
				)
			)
			( gate "@baseboard_fab2_lib.baseboard_fab2(sch_1):page169_i164"
				( attribute "CDS_LIB" "mstr_discrete"
					( Origin gPackager )
				)
				( attribute "CDS_LOCATION" "R9G35"
					( Origin gPackager )
				)
				( attribute "CDS_SEC" "1"
					( Origin gPackager )
				)
				( attribute "LOCATION" "R9G35"
					( Origin gFrontEnd )
				)
				( attribute "MATERIAL" "CHIP"
					( Origin gFrontEnd )
				)
				( attribute "PACK_TYPE" "0402"
					( Origin gFrontEnd )
				)
				( attribute "PART_NUMBER" "G21796-344"
					( Origin gFrontEnd )
				)
				( attribute "PHYS_PAGE" "169"
					( Origin gFrontEnd )
				)
				( attribute "ROT" "0"
					( Origin gFrontEnd )
				)
				( attribute "SEC" "1"
					( Origin gFrontEnd )
				)
				( attribute "SEC_TYPE" "0402"
					( Origin gFrontEnd )
				)
				( attribute "TOLERANCE" "1%"
					( Origin gFrontEnd )
				)
				( attribute "VALUE" "2.7K"
					( Origin gFrontEnd )
				)
				( attribute "VER" "2"
					( Origin gFrontEnd )
				)
				( attribute "WATTAGE" "1/16W"
					( Origin gFrontEnd )
				)
				( attribute "XY" "(-1400,3025)"
					( Origin gFrontEnd )
				)
				( attribute "CHIPS_PART_NAME" "RES"
					( Origin gPackager )
				)
				( attribute "CDS_PART_NAME" "RES_0402-2.7K,1%,1/16W,CHIP,G2A"
					( Origin gPackager )
				)
				( objectStatus "R9G35" )
				( pin "a"
					( attribute "PN" "1"
						( Origin gPackager )
					)
					( objectStatus "R9G35.1" )
				)
				( pin "b"
					( attribute "PN" "2"
						( Origin gPackager )
					)
					( objectStatus "R9G35.2" )
				)
			)
			( gate "@baseboard_fab2_lib.baseboard_fab2(sch_1):page170_i2"
				( attribute "BOM_COST" "FAST_PROCHOT"
					( Origin gFrontEnd )
				)
				( attribute "CDS_LIB" "mstr_discrete"
					( Origin gPackager )
				)
				( attribute "CDS_LOCATION" "R2P3"
					( Origin gPackager )
				)
				( attribute "CDS_SEC" "1"
					( Origin gPackager )
				)
				( attribute "LOCATION" "R2P3"
					( Origin gFrontEnd )
				)
				( attribute "MATERIAL" "CHIP"
					( Origin gFrontEnd )
				)
				( attribute "PACK_TYPE" "0402"
					( Origin gFrontEnd )
				)
				( attribute "PART_NUMBER" "G21796-072"
					( Origin gFrontEnd )
				)
				( attribute "PHYS_PAGE" "170"
					( Origin gFrontEnd )
				)
				( attribute "ROOM" "FAST_PROCHOT"
					( Origin gFrontEnd )
				)
				( attribute "ROT" "0"
					( Origin gFrontEnd )
				)
				( attribute "SEC" "1"
					( Origin gFrontEnd )
				)
				( attribute "SEC_TYPE" "0402"
					( Origin gFrontEnd )
				)
				( attribute "TOLERANCE" "1%"
					( Origin gFrontEnd )
				)
				( attribute "VALUE" "4.75K"
					( Origin gFrontEnd )
				)
				( attribute "VER" "2"
					( Origin gFrontEnd )
				)
				( attribute "WATTAGE" "1/16W"
					( Origin gFrontEnd )
				)
				( attribute "XY" "(-2350,5250)"
					( Origin gFrontEnd )
				)
				( attribute "CHIPS_PART_NAME" "RES"
					( Origin gPackager )
				)
				( attribute "CDS_PART_NAME" "RES_0402-4.75K,1%,1/16W,CHIP,GA"
					( Origin gPackager )
				)
				( objectStatus "R2P3" )
				( pin "a"
					( attribute "PN" "1"
						( Origin gPackager )
					)
					( objectStatus "R2P3.1" )
				)
				( pin "b"
					( attribute "PN" "2"
						( Origin gPackager )
					)
					( objectStatus "R2P3.2" )
				)
			)
			( gate "@baseboard_fab2_lib.baseboard_fab2(sch_1):page170_i4"
				( attribute "BOM_COST" "FAST_PROCHOT"
					( Origin gFrontEnd )
				)
				( attribute "CDS_LIB" "mstr_ttl"
					( Origin gPackager )
				)
				( attribute "CDS_LOCATION" "U8D3"
					( Origin gPackager )
				)
				( attribute "CDS_SEC" "1"
					( Origin gPackager )
				)
				( attribute "LOCATION" "U8D3"
					( Origin gFrontEnd )
				)
				( attribute "MATERIAL" "IC"
					( Origin gFrontEnd )
				)
				( attribute "PACK_TYPE" "SOP"
					( Origin gFrontEnd )
				)
				( attribute "PART_NUMBER" "C88419-001"
					( Origin gFrontEnd )
				)
				( attribute "PHYS_PAGE" "170"
					( Origin gFrontEnd )
				)
				( attribute "ROOM" "FAST_PROCHOT"
					( Origin gFrontEnd )
				)
				( attribute "ROT" "0"
					( Origin gFrontEnd )
				)
				( attribute "SEC" "1"
					( Origin gPackager )
				)
				( attribute "VALUE" "74LVC1G07"
					( Origin gFrontEnd )
				)
				( attribute "VER" "1"
					( Origin gFrontEnd )
				)
				( attribute "XY" "(-2625,4775)"
					( Origin gFrontEnd )
				)
				( attribute "CHIPS_PART_NAME" "TTL1G07_A"
					( Origin gPackager )
				)
				( attribute "CDS_PART_NAME" "TTL1G07_A_SOP-74LVC1G07,IC,C88B"
					( Origin gPackager )
				)
				( objectStatus "U8D3" )
				( pin "a"
					( attribute "PN" "2"
						( Origin gPackager )
					)
					( objectStatus "U8D3.2" )
				)
				( pin "y"
					( attribute "PN" "4"
						( Origin gPackager )
					)
					( objectStatus "U8D3.4" )
				)
			)
			( gate "@baseboard_fab2_lib.baseboard_fab2(sch_1):page170_i8"
				( attribute "BOM_COST" "FAST_PROCHOT"
					( Origin gFrontEnd )
				)
				( attribute "CDS_LIB" "dev_discrete"
					( Origin gPackager )
				)
				( attribute "CDS_LOCATION" "C2P1"
					( Origin gPackager )
				)
				( attribute "CDS_SEC" "1"
					( Origin gPackager )
				)
				( attribute "LOCATION" "C2P1"
					( Origin gFrontEnd )
				)
				( attribute "MATERIAL" "X7R"
					( Origin gFrontEnd )
				)
				( attribute "PACK_TYPE" "0402V"
					( Origin gFrontEnd )
				)
				( attribute "PART_NUMBER" "A36096-030"
					( Origin gFrontEnd )
				)
				( attribute "PHYS_PAGE" "170"
					( Origin gFrontEnd )
				)
				( attribute "ROOM" "FAST_PROCHOT"
					( Origin gFrontEnd )
				)
				( attribute "ROT" "0"
					( Origin gFrontEnd )
				)
				( attribute "SEC" "1"
					( Origin gFrontEnd )
				)
				( attribute "SEC_TYPE" "0402V"
					( Origin gFrontEnd )
				)
				( attribute "TOLERANCE" "10%"
					( Origin gFrontEnd )
				)
				( attribute "VALUE" "0.1UF"
					( Origin gFrontEnd )
				)
				( attribute "VER" "1"
					( Origin gFrontEnd )
				)
				( attribute "VOLTAGE" "16V"
					( Units "uVoltage" "V" 1.000000)
					( Origin gFrontEnd )
				)
				( attribute "XY" "(-5100,3350)"
					( Origin gFrontEnd )
				)
				( attribute "CHIPS_PART_NAME" "CAP_A"
					( Origin gPackager )
				)
				( attribute "CDS_PART_NAME" "CAP_A_0402V-0.1UF,16V,10%,X7R,A"
					( Origin gPackager )
				)
				( objectStatus "C2P1" )
				( pin "a"
					( attribute "PN" "1"
						( Origin gPackager )
					)
					( objectStatus "C2P1.1" )
				)
				( pin "b"
					( attribute "PN" "2"
						( Origin gPackager )
					)
					( objectStatus "C2P1.2" )
				)
			)
			( gate "@baseboard_fab2_lib.baseboard_fab2(sch_1):page170_i10"
				( attribute "BOM_COST" "FAST_PROCHOT"
					( Origin gFrontEnd )
				)
				( attribute "CDS_LIB" "mstr_ttl"
					( Origin gPackager )
				)
				( attribute "CDS_LOCATION" "U8E1"
					( Origin gPackager )
				)
				( attribute "CDS_SEC" "4"
					( Origin gPackager )
				)
				( attribute "LOCATION" "U8E1"
					( Origin gFrontEnd )
				)
				( attribute "MATERIAL" "IC"
					( Origin gFrontEnd )
				)
				( attribute "PACK_TYPE" "QFN15"
					( Origin gFrontEnd )
				)
				( attribute "PART_NUMBER" "D90404-001"
					( Origin gFrontEnd )
				)
				( attribute "PHYS_PAGE" "170"
					( Origin gFrontEnd )
				)
				( attribute "ROOM" "FAST_PROCHOT"
					( Origin gFrontEnd )
				)
				( attribute "ROT" "0"
					( Origin gFrontEnd )
				)
				( attribute "SEC" "4"
					( Origin gFrontEnd )
				)
				( attribute "SEC_TYPE" "QFN15"
					( Origin gFrontEnd )
				)
				( attribute "VALUE" "74LVC08A"
					( Origin gFrontEnd )
				)
				( attribute "VER" "1"
					( Origin gFrontEnd )
				)
				( attribute "XY" "(-1400,4375)"
					( Origin gFrontEnd )
				)
				( attribute "CHIPS_PART_NAME" "TTL08"
					( Origin gPackager )
				)
				( attribute "CDS_PART_NAME" "TTL08_QFN15-74LVC08A,IC,D90404B"
					( Origin gPackager )
				)
				( objectStatus "U8E1" )
				( pin "a(0)"
					( attribute "PN" "1"
						( Origin gPackager )
					)
					( objectStatus "U8E1.1" )
				)
				( pin "b(0)"
					( attribute "PN" "2"
						( Origin gPackager )
					)
					( objectStatus "U8E1.2" )
				)
				( pin "y(0)"
					( attribute "PN" "3"
						( Origin gPackager )
					)
					( objectStatus "U8E1.3" )
				)
			)
			( gate "@baseboard_fab2_lib.baseboard_fab2(sch_1):page170_i11"
				( attribute "BOM_COST" "FAST_PROCHOT"
					( Origin gFrontEnd )
				)
				( attribute "CDS_LIB" "mstr_ttl"
					( Origin gPackager )
				)
				( attribute "CDS_LOCATION" "U8E1"
					( Origin gPackager )
				)
				( attribute "CDS_SEC" "3"
					( Origin gPackager )
				)
				( attribute "LOCATION" "U8E1"
					( Origin gFrontEnd )
				)
				( attribute "MATERIAL" "IC"
					( Origin gFrontEnd )
				)
				( attribute "PACK_TYPE" "QFN15"
					( Origin gFrontEnd )
				)
				( attribute "PART_NUMBER" "D90404-001"
					( Origin gFrontEnd )
				)
				( attribute "PHYS_PAGE" "170"
					( Origin gFrontEnd )
				)
				( attribute "ROOM" "FAST_PROCHOT"
					( Origin gFrontEnd )
				)
				( attribute "ROT" "0"
					( Origin gFrontEnd )
				)
				( attribute "SEC" "3"
					( Origin gFrontEnd )
				)
				( attribute "SEC_TYPE" "QFN15"
					( Origin gFrontEnd )
				)
				( attribute "VALUE" "74LVC08A"
					( Origin gFrontEnd )
				)
				( attribute "VER" "1"
					( Origin gFrontEnd )
				)
				( attribute "XY" "(-1400,3650)"
					( Origin gFrontEnd )
				)
				( attribute "CHIPS_PART_NAME" "TTL08"
					( Origin gPackager )
				)
				( attribute "CDS_PART_NAME" "TTL08_QFN15-74LVC08A,IC,D90404B"
					( Origin gPackager )
				)
				( objectStatus "U8E1" )
				( pin "a(0)"
					( attribute "PN" "4"
						( Origin gPackager )
					)
					( objectStatus "U8E1.4" )
				)
				( pin "b(0)"
					( attribute "PN" "5"
						( Origin gPackager )
					)
					( objectStatus "U8E1.5" )
				)
				( pin "y(0)"
					( attribute "PN" "6"
						( Origin gPackager )
					)
					( objectStatus "U8E1.6" )
				)
			)
			( gate "@baseboard_fab2_lib.baseboard_fab2(sch_1):page170_i12"
				( attribute "BOM_COST" "FAST_PROCHOT"
					( Origin gFrontEnd )
				)
				( attribute "CDS_LIB" "mstr_ttl"
					( Origin gPackager )
				)
				( attribute "CDS_LOCATION" "U8E1"
					( Origin gPackager )
				)
				( attribute "CDS_SEC" "1"
					( Origin gPackager )
				)
				( attribute "LOCATION" "U8E1"
					( Origin gFrontEnd )
				)
				( attribute "MATERIAL" "IC"
					( Origin gFrontEnd )
				)
				( attribute "PACK_TYPE" "QFN15"
					( Origin gFrontEnd )
				)
				( attribute "PART_NUMBER" "D90404-001"
					( Origin gFrontEnd )
				)
				( attribute "PHYS_PAGE" "170"
					( Origin gFrontEnd )
				)
				( attribute "ROOM" "FAST_PROCHOT"
					( Origin gFrontEnd )
				)
				( attribute "ROT" "0"
					( Origin gFrontEnd )
				)
				( attribute "SEC" "1"
					( Origin gFrontEnd )
				)
				( attribute "SEC_TYPE" "QFN15"
					( Origin gFrontEnd )
				)
				( attribute "VALUE" "74LVC08A"
					( Origin gFrontEnd )
				)
				( attribute "VER" "1"
					( Origin gFrontEnd )
				)
				( attribute "XY" "(-250,4075)"
					( Origin gFrontEnd )
				)
				( attribute "CHIPS_PART_NAME" "TTL08"
					( Origin gPackager )
				)
				( attribute "CDS_PART_NAME" "TTL08_QFN15-74LVC08A,IC,D90404B"
					( Origin gPackager )
				)
				( objectStatus "U8E1" )
				( pin "a(0)"
					( attribute "PN" "12"
						( Origin gPackager )
					)
					( objectStatus "U8E1.12" )
				)
				( pin "b(0)"
					( attribute "PN" "13"
						( Origin gPackager )
					)
					( objectStatus "U8E1.13" )
				)
				( pin "y(0)"
					( attribute "PN" "11"
						( Origin gPackager )
					)
					( objectStatus "U8E1.11" )
				)
			)
			( gate "@baseboard_fab2_lib.baseboard_fab2(sch_1):page170_i20"
				( attribute "BOM_COST" "FAST_PROCHOT"
					( Origin gFrontEnd )
				)
				( attribute "CDS_LIB" "mstr_ttl"
					( Origin gPackager )
				)
				( attribute "CDS_LOCATION" "U1R2"
					( Origin gPackager )
				)
				( attribute "CDS_SEC" "1"
					( Origin gPackager )
				)
				( attribute "LOCATION" "U1R2"
					( Origin gFrontEnd )
				)
				( attribute "MATERIAL" "IC"
					( Origin gFrontEnd )
				)
				( attribute "PACK_TYPE" "SOT"
					( Origin gFrontEnd )
				)
				( attribute "PART_NUMBER" "A79322-001"
					( Origin gFrontEnd )
				)
				( attribute "PHYS_PAGE" "170"
					( Origin gFrontEnd )
				)
				( attribute "ROOM" "FAST_PROCHOT"
					( Origin gFrontEnd )
				)
				( attribute "ROT" "0"
					( Origin gFrontEnd )
				)
				( attribute "SEC" "1"
					( Origin gFrontEnd )
				)
				( attribute "SEC_TYPE" "SOT"
					( Origin gFrontEnd )
				)
				( attribute "VALUE" "74HC1G126"
					( Origin gFrontEnd )
				)
				( attribute "VER" "1"
					( Origin gFrontEnd )
				)
				( attribute "XY" "(-2525,2525)"
					( Origin gFrontEnd )
				)
				( attribute "CHIPS_PART_NAME" "TTL1G126_A"
					( Origin gPackager )
				)
				( attribute "CDS_PART_NAME" "TTL1G126_A_SOT-74HC1G126,IC,A7B"
					( Origin gPackager )
				)
				( objectStatus "U1R2" )
				( pin "a"
					( attribute "PN" "2"
						( Origin gPackager )
					)
					( objectStatus "U1R2.2" )
				)
				( pin "oe"
					( attribute "PN" "1"
						( Origin gPackager )
					)
					( objectStatus "U1R2.1" )
				)
				( pin "y"
					( attribute "PN" "4"
						( Origin gPackager )
					)
					( objectStatus "U1R2.4" )
				)
			)
			( gate "@baseboard_fab2_lib.baseboard_fab2(sch_1):page170_i30"
				( attribute "BOM_COST" "FAST_PROCHOT"
					( Origin gFrontEnd )
				)
				( attribute "CDS_LIB" "dev_discrete"
					( Origin gPackager )
				)
				( attribute "CDS_LOCATION" "C1R27"
					( Origin gPackager )
				)
				( attribute "CDS_SEC" "1"
					( Origin gPackager )
				)
				( attribute "LOCATION" "C1R27"
					( Origin gFrontEnd )
				)
				( attribute "MATERIAL" "X7R"
					( Origin gFrontEnd )
				)
				( attribute "PACK_TYPE" "0402V"
					( Origin gFrontEnd )
				)
				( attribute "PART_NUMBER" "A36096-030"
					( Origin gFrontEnd )
				)
				( attribute "PHYS_PAGE" "170"
					( Origin gFrontEnd )
				)
				( attribute "ROOM" "FAST_PROCHOT"
					( Origin gFrontEnd )
				)
				( attribute "ROT" "0"
					( Origin gFrontEnd )
				)
				( attribute "SEC" "1"
					( Origin gFrontEnd )
				)
				( attribute "SEC_TYPE" "0402V"
					( Origin gFrontEnd )
				)
				( attribute "TOLERANCE" "10%"
					( Origin gFrontEnd )
				)
				( attribute "VALUE" "0.1UF"
					( Origin gFrontEnd )
				)
				( attribute "VER" "1"
					( Origin gFrontEnd )
				)
				( attribute "VOLTAGE" "16V"
					( Units "uVoltage" "V" 1.000000)
					( Origin gFrontEnd )
				)
				( attribute "XY" "(-5150,1325)"
					( Origin gFrontEnd )
				)
				( attribute "CHIPS_PART_NAME" "CAP_A"
					( Origin gPackager )
				)
				( attribute "CDS_PART_NAME" "CAP_A_0402V-0.1UF,16V,10%,X7R,A"
					( Origin gPackager )
				)
				( objectStatus "C1R27" )
				( pin "a"
					( attribute "PN" "1"
						( Origin gPackager )
					)
					( objectStatus "C1R27.1" )
				)
				( pin "b"
					( attribute "PN" "2"
						( Origin gPackager )
					)
					( objectStatus "C1R27.2" )
				)
			)
			( gate "@baseboard_fab2_lib.baseboard_fab2(sch_1):page170_i33"
				( attribute "BOM_COST" "FAST_PROCHOT"
					( Origin gFrontEnd )
				)
				( attribute "CDS_LIB" "dev_discrete"
					( Origin gPackager )
				)
				( attribute "CDS_LOCATION" "C8D2"
					( Origin gPackager )
				)
				( attribute "CDS_SEC" "1"
					( Origin gPackager )
				)
				( attribute "LOCATION" "C8D2"
					( Origin gFrontEnd )
				)
				( attribute "MATERIAL" "X7R"
					( Origin gFrontEnd )
				)
				( attribute "PACK_TYPE" "0402V"
					( Origin gFrontEnd )
				)
				( attribute "PART_NUMBER" "A36096-030"
					( Origin gFrontEnd )
				)
				( attribute "PHYS_PAGE" "170"
					( Origin gFrontEnd )
				)
				( attribute "ROOM" "FAST_PROCHOT"
					( Origin gFrontEnd )
				)
				( attribute "ROT" "0"
					( Origin gFrontEnd )
				)
				( attribute "SEC" "1"
					( Origin gFrontEnd )
				)
				( attribute "SEC_TYPE" "0402V"
					( Origin gFrontEnd )
				)
				( attribute "TOLERANCE" "10%"
					( Origin gFrontEnd )
				)
				( attribute "VALUE" "0.1UF"
					( Origin gFrontEnd )
				)
				( attribute "VER" "1"
					( Origin gFrontEnd )
				)
				( attribute "VOLTAGE" "16V"
					( Units "uVoltage" "V" 1.000000)
					( Origin gFrontEnd )
				)
				( attribute "XY" "(-425,4775)"
					( Origin gFrontEnd )
				)
				( attribute "CHIPS_PART_NAME" "CAP_A"
					( Origin gPackager )
				)
				( attribute "CDS_PART_NAME" "CAP_A_0402V-0.1UF,16V,10%,X7R,A"
					( Origin gPackager )
				)
				( objectStatus "C8D2" )
				( pin "a"
					( attribute "PN" "1"
						( Origin gPackager )
					)
					( objectStatus "C8D2.1" )
				)
				( pin "b"
					( attribute "PN" "2"
						( Origin gPackager )
					)
					( objectStatus "C8D2.2" )
				)
			)
			( gate "@baseboard_fab2_lib.baseboard_fab2(sch_1):page170_i38"
				( attribute "BOM_COST" "PROC_SIDEBAND"
					( Origin gFrontEnd )
				)
				( attribute "CDS_LIB" "mstr_ttl"
					( Origin gPackager )
				)
				( attribute "CDS_LOCATION" "U8D5"
					( Origin gPackager )
				)
				( attribute "CDS_SEC" "1"
					( Origin gPackager )
				)
				( attribute "LOCATION" "U8D5"
					( Origin gFrontEnd )
				)
				( attribute "MATERIAL" "IC"
					( Origin gFrontEnd )
				)
				( attribute "PACK_TYPE" "SOT"
					( Origin gFrontEnd )
				)
				( attribute "PART_NUMBER" "A79322-001"
					( Origin gFrontEnd )
				)
				( attribute "PHYS_PAGE" "170"
					( Origin gFrontEnd )
				)
				( attribute "ROOM" "PROC_SIDEBAND"
					( Origin gFrontEnd )
				)
				( attribute "ROT" "0"
					( Origin gFrontEnd )
				)
				( attribute "SEC" "1"
					( Origin gFrontEnd )
				)
				( attribute "SEC_TYPE" "SOT"
					( Origin gFrontEnd )
				)
				( attribute "VALUE" "74HC1G126"
					( Origin gFrontEnd )
				)
				( attribute "VER" "1"
					( Origin gFrontEnd )
				)
				( attribute "XY" "(-3500,4775)"
					( Origin gFrontEnd )
				)
				( attribute "CHIPS_PART_NAME" "TTL1G126_A"
					( Origin gPackager )
				)
				( attribute "CDS_PART_NAME" "TTL1G126_A_SOT-74HC1G126,IC,A7B"
					( Origin gPackager )
				)
				( objectStatus "U8D5" )
				( pin "a"
					( attribute "PN" "2"
						( Origin gPackager )
					)
					( objectStatus "U8D5.2" )
				)
				( pin "oe"
					( attribute "PN" "1"
						( Origin gPackager )
					)
					( objectStatus "U8D5.1" )
				)
				( pin "y"
					( attribute "PN" "4"
						( Origin gPackager )
					)
					( objectStatus "U8D5.4" )
				)
			)
			( gate "@baseboard_fab2_lib.baseboard_fab2(sch_1):page170_i40"
				( attribute "BOM_COST" "PROC_SIDEBAND"
					( Origin gFrontEnd )
				)
				( attribute "CDS_LIB" "dev_discrete"
					( Origin gPackager )
				)
				( attribute "CDS_LOCATION" "C8E2"
					( Origin gPackager )
				)
				( attribute "CDS_SEC" "1"
					( Origin gPackager )
				)
				( attribute "LOCATION" "C8E2"
					( Origin gFrontEnd )
				)
				( attribute "MATERIAL" "X7R"
					( Origin gFrontEnd )
				)
				( attribute "PACK_TYPE" "0402V"
					( Origin gFrontEnd )
				)
				( attribute "PART_NUMBER" "A36096-030"
					( Origin gFrontEnd )
				)
				( attribute "PHYS_PAGE" "170"
					( Origin gFrontEnd )
				)
				( attribute "ROOM" "PROC_SIDEBAND"
					( Origin gFrontEnd )
				)
				( attribute "ROT" "0"
					( Origin gFrontEnd )
				)
				( attribute "SEC" "1"
					( Origin gFrontEnd )
				)
				( attribute "SEC_TYPE" "0402V"
					( Origin gFrontEnd )
				)
				( attribute "TOLERANCE" "10%"
					( Origin gFrontEnd )
				)
				( attribute "VALUE" "0.1UF"
					( Origin gFrontEnd )
				)
				( attribute "VER" "1"
					( Origin gFrontEnd )
				)
				( attribute "VOLTAGE" "16V"
					( Units "uVoltage" "V" 1.000000)
					( Origin gFrontEnd )
				)
				( attribute "XY" "(-1575,5100)"
					( Origin gFrontEnd )
				)
				( attribute "CHIPS_PART_NAME" "CAP_A"
					( Origin gPackager )
				)
				( attribute "CDS_PART_NAME" "CAP_A_0402V-0.1UF,16V,10%,X7R,A"
					( Origin gPackager )
				)
				( objectStatus "C8E2" )
				( pin "a"
					( attribute "PN" "1"
						( Origin gPackager )
					)
					( objectStatus "C8E2.1" )
				)
				( pin "b"
					( attribute "PN" "2"
						( Origin gPackager )
					)
					( objectStatus "C8E2.2" )
				)
			)
			( gate "@baseboard_fab2_lib.baseboard_fab2(sch_1):page170_i42"
				( attribute "BOM_COST" "PROC_SIDEBAND"
					( Origin gFrontEnd )
				)
				( attribute "CDS_LIB" "mstr_discrete"
					( Origin gPackager )
				)
				( attribute "CDS_LOCATION" "C8D3"
					( Origin gPackager )
				)
				( attribute "CDS_SEC" "1"
					( Origin gPackager )
				)
				( attribute "LOCATION" "C8D3"
					( Origin gFrontEnd )
				)
				( attribute "MATERIAL" "EMPTY"
					( Origin gFrontEnd )
				)
				( attribute "PACK_TYPE" "0402LF"
					( Origin gFrontEnd )
				)
				( attribute "PART_NUMBER" "A36096-049"
					( Origin gFrontEnd )
				)
				( attribute "PHYS_PAGE" "170"
					( Origin gFrontEnd )
				)
				( attribute "ROOM" "PROC_SIDEBAND"
					( Origin gFrontEnd )
				)
				( attribute "ROT" "0"
					( Origin gFrontEnd )
				)
				( attribute "SEC" "1"
					( Origin gFrontEnd )
				)
				( attribute "SEC_TYPE" "0402LF"
					( Origin gFrontEnd )
				)
				( attribute "TOLERANCE" "10%"
					( Origin gFrontEnd )
				)
				( attribute "VALUE" "470PF"
					( Origin gFrontEnd )
				)
				( attribute "VER" "1"
					( Origin gFrontEnd )
				)
				( attribute "VOLTAGE" "50V"
					( Units "uVoltage" "V" 1.000000)
					( Origin gFrontEnd )
				)
				( attribute "XY" "(-3700,4250)"
					( Origin gFrontEnd )
				)
				( attribute "CHIPS_PART_NAME" "CAP"
					( Origin gPackager )
				)
				( attribute "CDS_PART_NAME" "CAP_0402LF-470PF,50V,10%,EMPTYA"
					( Origin gPackager )
				)
				( objectStatus "C8D3" )
				( pin "a"
					( attribute "PN" "1"
						( Origin gPackager )
					)
					( objectStatus "C8D3.1" )
				)
				( pin "b"
					( attribute "PN" "2"
						( Origin gPackager )
					)
					( objectStatus "C8D3.2" )
				)
			)
			( gate "@baseboard_fab2_lib.baseboard_fab2(sch_1):page170_i46"
				( attribute "BOM_COST" "FAST_PROCHOT"
					( Origin gFrontEnd )
				)
				( attribute "CDS_LIB" "mstr_ttl"
					( Origin gPackager )
				)
				( attribute "CDS_LOCATION" "U1R1"
					( Origin gPackager )
				)
				( attribute "CDS_SEC" "1"
					( Origin gPackager )
				)
				( attribute "LOCATION" "U1R1"
					( Origin gFrontEnd )
				)
				( attribute "MATERIAL" "IC"
					( Origin gFrontEnd )
				)
				( attribute "PACK_TYPE" "SOP"
					( Origin gFrontEnd )
				)
				( attribute "PART_NUMBER" "C88419-001"
					( Origin gFrontEnd )
				)
				( attribute "PHYS_PAGE" "170"
					( Origin gFrontEnd )
				)
				( attribute "ROOM" "FAST_PROCHOT"
					( Origin gFrontEnd )
				)
				( attribute "ROT" "0"
					( Origin gFrontEnd )
				)
				( attribute "SEC" "1"
					( Origin gFrontEnd )
				)
				( attribute "SEC_TYPE" "SOP"
					( Origin gFrontEnd )
				)
				( attribute "VALUE" "74LVC1G07"
					( Origin gFrontEnd )
				)
				( attribute "VER" "1"
					( Origin gFrontEnd )
				)
				( attribute "XY" "(-1400,2525)"
					( Origin gFrontEnd )
				)
				( attribute "CHIPS_PART_NAME" "TTL1G07_A"
					( Origin gPackager )
				)
				( attribute "CDS_PART_NAME" "TTL1G07_A_SOP-74LVC1G07,IC,C88B"
					( Origin gPackager )
				)
				( objectStatus "U1R1" )
				( pin "a"
					( attribute "PN" "2"
						( Origin gPackager )
					)
					( objectStatus "U1R1.2" )
				)
				( pin "y"
					( attribute "PN" "4"
						( Origin gPackager )
					)
					( objectStatus "U1R1.4" )
				)
			)
			( gate "@baseboard_fab2_lib.baseboard_fab2(sch_1):page170_i49"
				( attribute "BOM_COST" "FAST_PROCHOT"
					( Origin gFrontEnd )
				)
				( attribute "CDS_LIB" "dev_discrete"
					( Origin gPackager )
				)
				( attribute "CDS_LOCATION" "C1R28"
					( Origin gPackager )
				)
				( attribute "CDS_SEC" "1"
					( Origin gPackager )
				)
				( attribute "LOCATION" "C1R28"
					( Origin gFrontEnd )
				)
				( attribute "MATERIAL" "X7R"
					( Origin gFrontEnd )
				)
				( attribute "PACK_TYPE" "0402V"
					( Origin gFrontEnd )
				)
				( attribute "PART_NUMBER" "A36096-030"
					( Origin gFrontEnd )
				)
				( attribute "PHYS_PAGE" "170"
					( Origin gFrontEnd )
				)
				( attribute "ROOM" "FAST_PROCHOT"
					( Origin gFrontEnd )
				)
				( attribute "ROT" "0"
					( Origin gFrontEnd )
				)
				( attribute "SEC" "1"
					( Origin gFrontEnd )
				)
				( attribute "SEC_TYPE" "0402V"
					( Origin gFrontEnd )
				)
				( attribute "TOLERANCE" "10%"
					( Origin gFrontEnd )
				)
				( attribute "VALUE" "0.1UF"
					( Origin gFrontEnd )
				)
				( attribute "VER" "1"
					( Origin gFrontEnd )
				)
				( attribute "VOLTAGE" "16V"
					( Units "uVoltage" "V" 1.000000)
					( Origin gFrontEnd )
				)
				( attribute "XY" "(-1600,1700)"
					( Origin gFrontEnd )
				)
				( attribute "CHIPS_PART_NAME" "CAP_A"
					( Origin gPackager )
				)
				( attribute "CDS_PART_NAME" "CAP_A_0402V-0.1UF,16V,10%,X7R,A"
					( Origin gPackager )
				)
				( objectStatus "C1R28" )
				( pin "a"
					( attribute "PN" "1"
						( Origin gPackager )
					)
					( objectStatus "C1R28.1" )
				)
				( pin "b"
					( attribute "PN" "2"
						( Origin gPackager )
					)
					( objectStatus "C1R28.2" )
				)
			)
			( gate "@baseboard_fab2_lib.baseboard_fab2(sch_1):page170_i51"
				( attribute "BOM_COST" "PROC_SIDEBAND"
					( Origin gFrontEnd )
				)
				( attribute "CDS_LIB" "mstr_discrete"
					( Origin gPackager )
				)
				( attribute "CDS_LOCATION" "R1R8"
					( Origin gPackager )
				)
				( attribute "CDS_SEC" "1"
					( Origin gPackager )
				)
				( attribute "LOCATION" "R1R8"
					( Origin gFrontEnd )
				)
				( attribute "MATERIAL" "CHIP"
					( Origin gFrontEnd )
				)
				( attribute "PACK_TYPE" "0402"
					( Origin gFrontEnd )
				)
				( attribute "PART_NUMBER" "G21497-005"
					( Origin gFrontEnd )
				)
				( attribute "PHYS_PAGE" "170"
					( Origin gFrontEnd )
				)
				( attribute "ROOM" "PROC_SIDEBAND"
					( Origin gFrontEnd )
				)
				( attribute "ROT" "0"
					( Origin gFrontEnd )
				)
				( attribute "SEC" "1"
					( Origin gFrontEnd )
				)
				( attribute "SEC_TYPE" "0402"
					( Origin gFrontEnd )
				)
				( attribute "TOLERANCE" "5%"
					( Origin gFrontEnd )
				)
				( attribute "VALUE" "0.0"
					( Origin gFrontEnd )
				)
				( attribute "VER" "1"
					( Origin gFrontEnd )
				)
				( attribute "WATTAGE" "1/16W"
					( Origin gFrontEnd )
				)
				( attribute "XY" "(-650,2525)"
					( Origin gFrontEnd )
				)
				( attribute "CHIPS_PART_NAME" "RES"
					( Origin gPackager )
				)
				( attribute "CDS_PART_NAME" "RES_0402-0.0,5%,1/16W,CHIP,G21A"
					( Origin gPackager )
				)
				( objectStatus "R1R8" )
				( pin "a"
					( attribute "PN" "1"
						( Origin gPackager )
					)
					( objectStatus "R1R8.1" )
				)
				( pin "b"
					( attribute "PN" "2"
						( Origin gPackager )
					)
					( objectStatus "R1R8.2" )
				)
			)
			( gate "@baseboard_fab2_lib.baseboard_fab2(sch_1):page170_i52"
				( attribute "BOM_COST" "PROC_SIDEBAND"
					( Origin gFrontEnd )
				)
				( attribute "CDS_LIB" "mstr_discrete"
					( Origin gPackager )
				)
				( attribute "CDS_LOCATION" "R2P8"
					( Origin gPackager )
				)
				( attribute "CDS_SEC" "1"
					( Origin gPackager )
				)
				( attribute "LOCATION" "R2P8"
					( Origin gFrontEnd )
				)
				( attribute "MATERIAL" "CHIP"
					( Origin gFrontEnd )
				)
				( attribute "PACK_TYPE" "0402"
					( Origin gFrontEnd )
				)
				( attribute "PART_NUMBER" "G21497-062"
					( Origin gFrontEnd )
				)
				( attribute "PHYS_PAGE" "170"
					( Origin gFrontEnd )
				)
				( attribute "ROOM" "PROC_SIDEBAND"
					( Origin gFrontEnd )
				)
				( attribute "ROT" "0"
					( Origin gFrontEnd )
				)
				( attribute "SEC" "1"
					( Origin gFrontEnd )
				)
				( attribute "SEC_TYPE" "0402"
					( Origin gFrontEnd )
				)
				( attribute "TOLERANCE" "5%"
					( Origin gFrontEnd )
				)
				( attribute "VALUE" "560"
					( Origin gFrontEnd )
				)
				( attribute "VER" "2"
					( Origin gFrontEnd )
				)
				( attribute "WATTAGE" "1/16W"
					( Origin gFrontEnd )
				)
				( attribute "XY" "(-3825,5100)"
					( Origin gFrontEnd )
				)
				( attribute "CHIPS_PART_NAME" "RES"
					( Origin gPackager )
				)
				( attribute "CDS_PART_NAME" "RES_0402-560,5%,1/16W,CHIP,G21A"
					( Origin gPackager )
				)
				( objectStatus "R2P8" )
				( pin "a"
					( attribute "PN" "1"
						( Origin gPackager )
					)
					( objectStatus "R2P8.1" )
				)
				( pin "b"
					( attribute "PN" "2"
						( Origin gPackager )
					)
					( objectStatus "R2P8.2" )
				)
			)
			( gate "@baseboard_fab2_lib.baseboard_fab2(sch_1):page170_i54"
				( attribute "BOM_COST" "FAST_PROCHOT"
					( Origin gFrontEnd )
				)
				( attribute "CDS_LIB" "mstr_discrete"
					( Origin gPackager )
				)
				( attribute "CDS_LOCATION" "R2T3"
					( Origin gPackager )
				)
				( attribute "CDS_SEC" "1"
					( Origin gPackager )
				)
				( attribute "LOCATION" "R2T3"
					( Origin gFrontEnd )
				)
				( attribute "MATERIAL" "CHIP"
					( Origin gFrontEnd )
				)
				( attribute "PACK_TYPE" "0402"
					( Origin gFrontEnd )
				)
				( attribute "PART_NUMBER" "G21796-072"
					( Origin gFrontEnd )
				)
				( attribute "PHYS_PAGE" "170"
					( Origin gFrontEnd )
				)
				( attribute "ROOM" "FAST_PROCHOT"
					( Origin gFrontEnd )
				)
				( attribute "ROT" "0"
					( Origin gFrontEnd )
				)
				( attribute "SEC" "1"
					( Origin gFrontEnd )
				)
				( attribute "SEC_TYPE" "0402"
					( Origin gFrontEnd )
				)
				( attribute "TOLERANCE" "1%"
					( Origin gFrontEnd )
				)
				( attribute "VALUE" "4.75K"
					( Origin gFrontEnd )
				)
				( attribute "VER" "2"
					( Origin gFrontEnd )
				)
				( attribute "WATTAGE" "1/16W"
					( Origin gFrontEnd )
				)
				( attribute "XY" "(-3450,2075)"
					( Origin gFrontEnd )
				)
				( attribute "CHIPS_PART_NAME" "RES"
					( Origin gPackager )
				)
				( attribute "CDS_PART_NAME" "RES_0402-4.75K,1%,1/16W,CHIP,GA"
					( Origin gPackager )
				)
				( objectStatus "R2T3" )
				( pin "a"
					( attribute "PN" "1"
						( Origin gPackager )
					)
					( objectStatus "R2T3.1" )
				)
				( pin "b"
					( attribute "PN" "2"
						( Origin gPackager )
					)
					( objectStatus "R2T3.2" )
				)
			)
			( gate "@baseboard_fab2_lib.baseboard_fab2(sch_1):page170_i56"
				( attribute "BOM_COST" "PROC_SIDEBAND"
					( Origin gFrontEnd )
				)
				( attribute "CDS_LIB" "mstr_discrete"
					( Origin gPackager )
				)
				( attribute "CDS_LOCATION" "R2P5"
					( Origin gPackager )
				)
				( attribute "CDS_SEC" "1"
					( Origin gPackager )
				)
				( attribute "LOCATION" "R2P5"
					( Origin gFrontEnd )
				)
				( attribute "MATERIAL" "CHIP"
					( Origin gFrontEnd )
				)
				( attribute "PACK_TYPE" "0402"
					( Origin gFrontEnd )
				)
				( attribute "PART_NUMBER" "G21796-072"
					( Origin gFrontEnd )
				)
				( attribute "PHYS_PAGE" "170"
					( Origin gFrontEnd )
				)
				( attribute "ROOM" "PROC_SIDEBAND"
					( Origin gFrontEnd )
				)
				( attribute "ROT" "0"
					( Origin gFrontEnd )
				)
				( attribute "SEC" "1"
					( Origin gFrontEnd )
				)
				( attribute "SEC_TYPE" "0402"
					( Origin gFrontEnd )
				)
				( attribute "TOLERANCE" "1%"
					( Origin gFrontEnd )
				)
				( attribute "VALUE" "4.75K"
					( Origin gFrontEnd )
				)
				( attribute "VER" "2"
					( Origin gFrontEnd )
				)
				( attribute "WATTAGE" "1/16W"
					( Origin gFrontEnd )
				)
				( attribute "XY" "(-4150,5100)"
					( Origin gFrontEnd )
				)
				( attribute "CHIPS_PART_NAME" "RES"
					( Origin gPackager )
				)
				( attribute "CDS_PART_NAME" "RES_0402-4.75K,1%,1/16W,CHIP,GA"
					( Origin gPackager )
				)
				( objectStatus "R2P5" )
				( pin "a"
					( attribute "PN" "1"
						( Origin gPackager )
					)
					( objectStatus "R2P5.1" )
				)
				( pin "b"
					( attribute "PN" "2"
						( Origin gPackager )
					)
					( objectStatus "R2P5.2" )
				)
			)
			( gate "@baseboard_fab2_lib.baseboard_fab2(sch_1):page170_i58"
				( attribute "BOM_COST" "PROC_SIDEBAND"
					( Origin gFrontEnd )
				)
				( attribute "CDS_LIB" "mstr_discrete"
					( Origin gPackager )
				)
				( attribute "CDS_LOCATION" "Q2P1"
					( Origin gPackager )
				)
				( attribute "CDS_SEC" "1"
					( Origin gPackager )
				)
				( attribute "LOCATION" "Q2P1"
					( Origin gFrontEnd )
				)
				( attribute "MATERIAL" "FET"
					( Origin gFrontEnd )
				)
				( attribute "PACK_TYPE" "SOT23LF"
					( Origin gFrontEnd )
				)
				( attribute "PART_NUMBER" "C79254-001"
					( Origin gFrontEnd )
				)
				( attribute "PHYS_PAGE" "170"
					( Origin gFrontEnd )
				)
				( attribute "ROOM" "PROC_SIDEBAND"
					( Origin gFrontEnd )
				)
				( attribute "ROT" "0"
					( Origin gFrontEnd )
				)
				( attribute "SEC" "1"
					( Origin gFrontEnd )
				)
				( attribute "SEC_TYPE" "SOT23LF"
					( Origin gFrontEnd )
				)
				( attribute "VALUE" "2N7002"
					( Origin gFrontEnd )
				)
				( attribute "VER" "8"
					( Origin gFrontEnd )
				)
				( attribute "XY" "(-4150,4225)"
					( Origin gFrontEnd )
				)
				( attribute "CHIPS_PART_NAME" "FET_N"
					( Origin gPackager )
				)
				( attribute "CDS_PART_NAME" "FET_N_SOT23LF-2N7002,FET,C7925A"
					( Origin gPackager )
				)
				( objectStatus "Q2P1" )
				( pin "drn"
					( attribute "PN" "3"
						( Origin gPackager )
					)
					( objectStatus "Q2P1.3" )
				)
				( pin "gate"
					( attribute "PN" "1"
						( Origin gPackager )
					)
					( objectStatus "Q2P1.1" )
				)
				( pin "src"
					( attribute "PN" "2"
						( Origin gPackager )
					)
					( objectStatus "Q2P1.2" )
				)
			)
			( gate "@baseboard_fab2_lib.baseboard_fab2(sch_1):page170_i61"
				( attribute "BOM_COST" "PROC_SIDEBAND"
					( Origin gFrontEnd )
				)
				( attribute "CDS_LIB" "mstr_discrete"
					( Origin gPackager )
				)
				( attribute "CDS_LOCATION" "R2P13"
					( Origin gPackager )
				)
				( attribute "CDS_SEC" "1"
					( Origin gPackager )
				)
				( attribute "LOCATION" "R2P13"
					( Origin gFrontEnd )
				)
				( attribute "MATERIAL" "CHIP"
					( Origin gFrontEnd )
				)
				( attribute "PACK_TYPE" "0402"
					( Origin gFrontEnd )
				)
				( attribute "PART_NUMBER" "G21796-072"
					( Origin gFrontEnd )
				)
				( attribute "PHYS_PAGE" "170"
					( Origin gFrontEnd )
				)
				( attribute "ROOM" "PROC_SIDEBAND"
					( Origin gFrontEnd )
				)
				( attribute "ROT" "0"
					( Origin gFrontEnd )
				)
				( attribute "SEC" "1"
					( Origin gFrontEnd )
				)
				( attribute "SEC_TYPE" "0402"
					( Origin gFrontEnd )
				)
				( attribute "TOLERANCE" "1%"
					( Origin gFrontEnd )
				)
				( attribute "VALUE" "4.75K"
					( Origin gFrontEnd )
				)
				( attribute "VER" "2"
					( Origin gFrontEnd )
				)
				( attribute "WATTAGE" "1/16W"
					( Origin gFrontEnd )
				)
				( attribute "XY" "(-4600,4350)"
					( Origin gFrontEnd )
				)
				( attribute "CHIPS_PART_NAME" "RES"
					( Origin gPackager )
				)
				( attribute "CDS_PART_NAME" "RES_0402-4.75K,1%,1/16W,CHIP,GA"
					( Origin gPackager )
				)
				( objectStatus "R2P13" )
				( pin "a"
					( attribute "PN" "1"
						( Origin gPackager )
					)
					( objectStatus "R2P13.1" )
				)
				( pin "b"
					( attribute "PN" "2"
						( Origin gPackager )
					)
					( objectStatus "R2P13.2" )
				)
			)
			( gate "@baseboard_fab2_lib.baseboard_fab2(sch_1):page170_i63"
				( attribute "BOM_COST" "PROC_SIDEBAND"
					( Origin gFrontEnd )
				)
				( attribute "CDS_LIB" "mstr_discrete"
					( Origin gPackager )
				)
				( attribute "CDS_LOCATION" "R2P11"
					( Origin gPackager )
				)
				( attribute "CDS_SEC" "1"
					( Origin gPackager )
				)
				( attribute "LOCATION" "R2P11"
					( Origin gFrontEnd )
				)
				( attribute "MATERIAL" "EMPTY"
					( Origin gFrontEnd )
				)
				( attribute "PACK_TYPE" "0402"
					( Origin gFrontEnd )
				)
				( attribute "PART_NUMBER" "G21796-026"
					( Origin gFrontEnd )
				)
				( attribute "PHYS_PAGE" "170"
					( Origin gFrontEnd )
				)
				( attribute "ROOM" "PROC_SIDEBAND"
					( Origin gFrontEnd )
				)
				( attribute "ROT" "0"
					( Origin gFrontEnd )
				)
				( attribute "SEC" "1"
					( Origin gPackager )
				)
				( attribute "TOLERANCE" "1%"
					( Origin gFrontEnd )
				)
				( attribute "VALUE" "1.00K"
					( Origin gFrontEnd )
				)
				( attribute "VER" "2"
					( Origin gFrontEnd )
				)
				( attribute "WATTAGE" "1/16W"
					( Origin gFrontEnd )
				)
				( attribute "XY" "(-4525,3925)"
					( Origin gFrontEnd )
				)
				( attribute "CHIPS_PART_NAME" "RES"
					( Origin gPackager )
				)
				( attribute "CDS_PART_NAME" "RES_0402-1.00K,1%,1/16W,EMPTY,A"
					( Origin gPackager )
				)
				( objectStatus "R2P11" )
				( pin "a"
					( attribute "PN" "1"
						( Origin gPackager )
					)
					( objectStatus "R2P11.1" )
				)
				( pin "b"
					( attribute "PN" "2"
						( Origin gPackager )
					)
					( objectStatus "R2P11.2" )
				)
			)
			( gate "@baseboard_fab2_lib.baseboard_fab2(sch_1):page170_i65"
				( attribute "BOM_COST" "PROC_SIDEBAND"
					( Origin gFrontEnd )
				)
				( attribute "CDS_LIB" "mstr_discrete"
					( Origin gPackager )
				)
				( attribute "CDS_LOCATION" "R9F3"
					( Origin gPackager )
				)
				( attribute "CDS_SEC" "1"
					( Origin gPackager )
				)
				( attribute "LOCATION" "R9F3"
					( Origin gFrontEnd )
				)
				( attribute "MATERIAL" "CHIP"
					( Origin gFrontEnd )
				)
				( attribute "PACK_TYPE" "0402"
					( Origin gFrontEnd )
				)
				( attribute "PART_NUMBER" "G21796-072"
					( Origin gFrontEnd )
				)
				( attribute "PHYS_PAGE" "170"
					( Origin gFrontEnd )
				)
				( attribute "ROOM" "PROC_SIDEBAND"
					( Origin gFrontEnd )
				)
				( attribute "ROT" "0"
					( Origin gFrontEnd )
				)
				( attribute "SEC" "1"
					( Origin gFrontEnd )
				)
				( attribute "SEC_TYPE" "0402"
					( Origin gFrontEnd )
				)
				( attribute "TOLERANCE" "1%"
					( Origin gFrontEnd )
				)
				( attribute "VALUE" "4.75K"
					( Origin gFrontEnd )
				)
				( attribute "VER" "2"
					( Origin gFrontEnd )
				)
				( attribute "WATTAGE" "1/16W"
					( Origin gFrontEnd )
				)
				( attribute "XY" "(-2950,2775)"
					( Origin gFrontEnd )
				)
				( attribute "CHIPS_PART_NAME" "RES"
					( Origin gPackager )
				)
				( attribute "CDS_PART_NAME" "RES_0402-4.75K,1%,1/16W,CHIP,GA"
					( Origin gPackager )
				)
				( objectStatus "R9F3" )
				( pin "a"
					( attribute "PN" "1"
						( Origin gPackager )
					)
					( objectStatus "R9F3.1" )
				)
				( pin "b"
					( attribute "PN" "2"
						( Origin gPackager )
					)
					( objectStatus "R9F3.2" )
				)
			)
			( gate "@baseboard_fab2_lib.baseboard_fab2(sch_1):page170_i67"
				( attribute "BOM_COST" "PROC_SIDEBAND"
					( Origin gFrontEnd )
				)
				( attribute "CDS_LIB" "mstr_discrete"
					( Origin gPackager )
				)
				( attribute "CDS_LOCATION" "Q8F2"
					( Origin gPackager )
				)
				( attribute "CDS_SEC" "1"
					( Origin gPackager )
				)
				( attribute "LOCATION" "Q8F2"
					( Origin gFrontEnd )
				)
				( attribute "MATERIAL" "FET"
					( Origin gFrontEnd )
				)
				( attribute "PACK_TYPE" "SOT23LF"
					( Origin gFrontEnd )
				)
				( attribute "PART_NUMBER" "C79254-001"
					( Origin gFrontEnd )
				)
				( attribute "PHYS_PAGE" "170"
					( Origin gFrontEnd )
				)
				( attribute "ROOM" "PROC_SIDEBAND"
					( Origin gFrontEnd )
				)
				( attribute "ROT" "0"
					( Origin gFrontEnd )
				)
				( attribute "SEC" "1"
					( Origin gFrontEnd )
				)
				( attribute "SEC_TYPE" "SOT23LF"
					( Origin gFrontEnd )
				)
				( attribute "VALUE" "2N7002"
					( Origin gFrontEnd )
				)
				( attribute "VER" "8"
					( Origin gFrontEnd )
				)
				( attribute "XY" "(-2950,1900)"
					( Origin gFrontEnd )
				)
				( attribute "CHIPS_PART_NAME" "FET_N"
					( Origin gPackager )
				)
				( attribute "CDS_PART_NAME" "FET_N_SOT23LF-2N7002,FET,C7925A"
					( Origin gPackager )
				)
				( objectStatus "Q8F2" )
				( pin "drn"
					( attribute "PN" "3"
						( Origin gPackager )
					)
					( objectStatus "Q8F2.3" )
				)
				( pin "gate"
					( attribute "PN" "1"
						( Origin gPackager )
					)
					( objectStatus "Q8F2.1" )
				)
				( pin "src"
					( attribute "PN" "2"
						( Origin gPackager )
					)
					( objectStatus "Q8F2.2" )
				)
			)
			( gate "@baseboard_fab2_lib.baseboard_fab2(sch_1):page170_i71"
				( attribute "BOM_COST" "FAST_PROCHOT"
					( Origin gFrontEnd )
				)
				( attribute "CDS_LIB" "mstr_discrete"
					( Origin gPackager )
				)
				( attribute "CDS_LOCATION" "R8D26"
					( Origin gPackager )
				)
				( attribute "CDS_SEC" "1"
					( Origin gPackager )
				)
				( attribute "LOCATION" "R8D26"
					( Origin gFrontEnd )
				)
				( attribute "MATERIAL" "CHIP"
					( Origin gFrontEnd )
				)
				( attribute "PACK_TYPE" "0402"
					( Origin gFrontEnd )
				)
				( attribute "PART_NUMBER" "G21796-072"
					( Origin gFrontEnd )
				)
				( attribute "PHYS_PAGE" "170"
					( Origin gFrontEnd )
				)
				( attribute "ROOM" "FAST_PROCHOT"
					( Origin gFrontEnd )
				)
				( attribute "ROT" "0"
					( Origin gFrontEnd )
				)
				( attribute "SEC" "1"
					( Origin gFrontEnd )
				)
				( attribute "SEC_TYPE" "0402"
					( Origin gFrontEnd )
				)
				( attribute "TOLERANCE" "1%"
					( Origin gFrontEnd )
				)
				( attribute "VALUE" "4.75K"
					( Origin gFrontEnd )
				)
				( attribute "VER" "2"
					( Origin gFrontEnd )
				)
				( attribute "WATTAGE" "1/16W"
					( Origin gFrontEnd )
				)
				( attribute "XY" "(-3150,5100)"
					( Origin gFrontEnd )
				)
				( attribute "CHIPS_PART_NAME" "RES"
					( Origin gPackager )
				)
				( attribute "CDS_PART_NAME" "RES_0402-4.75K,1%,1/16W,CHIP,GA"
					( Origin gPackager )
				)
				( objectStatus "R8D26" )
				( pin "a"
					( attribute "PN" "1"
						( Origin gPackager )
					)
					( objectStatus "R8D26.1" )
				)
				( pin "b"
					( attribute "PN" "2"
						( Origin gPackager )
					)
					( objectStatus "R8D26.2" )
				)
			)
			( gate "@baseboard_fab2_lib.baseboard_fab2(sch_1):page170_i73"
				( attribute "BOM_COST" "FAST_PROCHOT"
					( Origin gFrontEnd )
				)
				( attribute "CDS_LIB" "mstr_discrete"
					( Origin gPackager )
				)
				( attribute "CDS_LOCATION" "R1R5"
					( Origin gPackager )
				)
				( attribute "CDS_SEC" "1"
					( Origin gPackager )
				)
				( attribute "LOCATION" "R1R5"
					( Origin gFrontEnd )
				)
				( attribute "MATERIAL" "CHIP"
					( Origin gFrontEnd )
				)
				( attribute "PACK_TYPE" "0402"
					( Origin gFrontEnd )
				)
				( attribute "PART_NUMBER" "G21796-072"
					( Origin gFrontEnd )
				)
				( attribute "PHYS_PAGE" "170"
					( Origin gFrontEnd )
				)
				( attribute "ROOM" "FAST_PROCHOT"
					( Origin gFrontEnd )
				)
				( attribute "ROT" "0"
					( Origin gFrontEnd )
				)
				( attribute "SEC" "1"
					( Origin gFrontEnd )
				)
				( attribute "SEC_TYPE" "0402"
					( Origin gFrontEnd )
				)
				( attribute "TOLERANCE" "1%"
					( Origin gFrontEnd )
				)
				( attribute "VALUE" "4.75K"
					( Origin gFrontEnd )
				)
				( attribute "VER" "2"
					( Origin gFrontEnd )
				)
				( attribute "WATTAGE" "1/16W"
					( Origin gFrontEnd )
				)
				( attribute "XY" "(-2025,2850)"
					( Origin gFrontEnd )
				)
				( attribute "CHIPS_PART_NAME" "RES"
					( Origin gPackager )
				)
				( attribute "CDS_PART_NAME" "RES_0402-4.75K,1%,1/16W,CHIP,GA"
					( Origin gPackager )
				)
				( objectStatus "R1R5" )
				( pin "a"
					( attribute "PN" "1"
						( Origin gPackager )
					)
					( objectStatus "R1R5.1" )
				)
				( pin "b"
					( attribute "PN" "2"
						( Origin gPackager )
					)
					( objectStatus "R1R5.2" )
				)
			)
			( gate "@baseboard_fab2_lib.baseboard_fab2(sch_1):page170_i74"
				( attribute "CDS_LIB" "mstr_discrete"
					( Origin gPackager )
				)
				( attribute "CDS_LOCATION" "R2P4"
					( Origin gPackager )
				)
				( attribute "CDS_SEC" "1"
					( Origin gPackager )
				)
				( attribute "LOCATION" "R2P4"
					( Origin gFrontEnd )
				)
				( attribute "MATERIAL" "CHIP"
					( Origin gFrontEnd )
				)
				( attribute "PACK_TYPE" "0402"
					( Origin gFrontEnd )
				)
				( attribute "PART_NUMBER" "G21796-074"
					( Origin gFrontEnd )
				)
				( attribute "PHYS_PAGE" "170"
					( Origin gFrontEnd )
				)
				( attribute "ROT" "0"
					( Origin gFrontEnd )
				)
				( attribute "SEC" "1"
					( Origin gPackager )
				)
				( attribute "TOLERANCE" "1%"
					( Origin gFrontEnd )
				)
				( attribute "VALUE" "33.2"
					( Origin gFrontEnd )
				)
				( attribute "VER" "1"
					( Origin gFrontEnd )
				)
				( attribute "WATTAGE" "1/16W"
					( Origin gFrontEnd )
				)
				( attribute "XY" "(-1900,4775)"
					( Origin gFrontEnd )
				)
				( attribute "CHIPS_PART_NAME" "RES"
					( Origin gPackager )
				)
				( attribute "CDS_PART_NAME" "RES_0402-33.2,1%,1/16W,CHIP,G2A"
					( Origin gPackager )
				)
				( objectStatus "R2P4" )
				( pin "a"
					( attribute "PN" "1"
						( Origin gPackager )
					)
					( objectStatus "R2P4.1" )
				)
				( pin "b"
					( attribute "PN" "2"
						( Origin gPackager )
					)
					( objectStatus "R2P4.2" )
				)
			)
			( gate "@baseboard_fab2_lib.baseboard_fab2(sch_1):page172_i5"
				( attribute "CDS_LIB" "dev_discrete"
					( Origin gPackager )
				)
				( attribute "CDS_LOCATION" "C2L49"
					( Origin gPackager )
				)
				( attribute "CDS_SEC" "1"
					( Origin gPackager )
				)
				( attribute "LOCATION" "C2L49"
					( Origin gFrontEnd )
				)
				( attribute "MATERIAL" "X7R"
					( Origin gFrontEnd )
				)
				( attribute "PACK_TYPE" "0402V"
					( Origin gFrontEnd )
				)
				( attribute "PART_NUMBER" "A36096-045"
					( Origin gFrontEnd )
				)
				( attribute "PHYS_PAGE" "172"
					( Origin gFrontEnd )
				)
				( attribute "ROOM" "ST_SATA"
					( Origin gFrontEnd )
				)
				( attribute "ROT" "0"
					( Origin gFrontEnd )
				)
				( attribute "SEC" "1"
					( Origin gFrontEnd )
				)
				( attribute "SEC_TYPE" "0402V"
					( Origin gFrontEnd )
				)
				( attribute "TOLERANCE" "10%"
					( Origin gFrontEnd )
				)
				( attribute "VALUE" "0.01UF"
					( Origin gFrontEnd )
				)
				( attribute "VER" "2"
					( Origin gFrontEnd )
				)
				( attribute "VOLTAGE" "25V"
					( Units "uVoltage" "V" 1.000000)
					( Origin gFrontEnd )
				)
				( attribute "XY" "(575,0)"
					( Origin gFrontEnd )
				)
				( attribute "CHIPS_PART_NAME" "CAP_A"
					( Origin gPackager )
				)
				( attribute "CDS_PART_NAME" "CAP_A_0402V-0.01UF,25V,10%,X7RA"
					( Origin gPackager )
				)
				( objectStatus "C2L49" )
				( pin "a"
					( attribute "PN" "1"
						( Origin gPackager )
					)
					( objectStatus "C2L49.1" )
				)
				( pin "b"
					( attribute "PN" "2"
						( Origin gPackager )
					)
					( objectStatus "C2L49.2" )
				)
			)
			( gate "@baseboard_fab2_lib.baseboard_fab2(sch_1):page172_i6"
				( attribute "CDS_LIB" "dev_discrete"
					( Origin gPackager )
				)
				( attribute "CDS_LOCATION" "C2L52"
					( Origin gPackager )
				)
				( attribute "CDS_SEC" "1"
					( Origin gPackager )
				)
				( attribute "LOCATION" "C2L52"
					( Origin gFrontEnd )
				)
				( attribute "MATERIAL" "X7R"
					( Origin gFrontEnd )
				)
				( attribute "PACK_TYPE" "0402V"
					( Origin gFrontEnd )
				)
				( attribute "PART_NUMBER" "A36096-045"
					( Origin gFrontEnd )
				)
				( attribute "PHYS_PAGE" "172"
					( Origin gFrontEnd )
				)
				( attribute "ROOM" "ST_SATA"
					( Origin gFrontEnd )
				)
				( attribute "ROT" "0"
					( Origin gFrontEnd )
				)
				( attribute "SEC" "1"
					( Origin gFrontEnd )
				)
				( attribute "SEC_TYPE" "0402V"
					( Origin gFrontEnd )
				)
				( attribute "TOLERANCE" "10%"
					( Origin gFrontEnd )
				)
				( attribute "VALUE" "0.01UF"
					( Origin gFrontEnd )
				)
				( attribute "VER" "2"
					( Origin gFrontEnd )
				)
				( attribute "VOLTAGE" "25V"
					( Units "uVoltage" "V" 1.000000)
					( Origin gFrontEnd )
				)
				( attribute "XY" "(-650,150)"
					( Origin gFrontEnd )
				)
				( attribute "CHIPS_PART_NAME" "CAP_A"
					( Origin gPackager )
				)
				( attribute "CDS_PART_NAME" "CAP_A_0402V-0.01UF,25V,10%,X7RA"
					( Origin gPackager )
				)
				( objectStatus "C2L52" )
				( pin "a"
					( attribute "PN" "1"
						( Origin gPackager )
					)
					( objectStatus "C2L52.1" )
				)
				( pin "b"
					( attribute "PN" "2"
						( Origin gPackager )
					)
					( objectStatus "C2L52.2" )
				)
			)
			( gate "@baseboard_fab2_lib.baseboard_fab2(sch_1):page172_i7"
				( attribute "CDS_LIB" "dev_discrete"
					( Origin gPackager )
				)
				( attribute "CDS_LOCATION" "C2L50"
					( Origin gPackager )
				)
				( attribute "CDS_SEC" "1"
					( Origin gPackager )
				)
				( attribute "LOCATION" "C2L50"
					( Origin gFrontEnd )
				)
				( attribute "MATERIAL" "X7R"
					( Origin gFrontEnd )
				)
				( attribute "PACK_TYPE" "0402V"
					( Origin gFrontEnd )
				)
				( attribute "PART_NUMBER" "A36096-045"
					( Origin gFrontEnd )
				)
				( attribute "PHYS_PAGE" "172"
					( Origin gFrontEnd )
				)
				( attribute "ROOM" "ST_SATA"
					( Origin gFrontEnd )
				)
				( attribute "ROT" "0"
					( Origin gFrontEnd )
				)
				( attribute "SEC" "1"
					( Origin gFrontEnd )
				)
				( attribute "SEC_TYPE" "0402V"
					( Origin gFrontEnd )
				)
				( attribute "TOLERANCE" "10%"
					( Origin gFrontEnd )
				)
				( attribute "VALUE" "0.01UF"
					( Origin gFrontEnd )
				)
				( attribute "VER" "2"
					( Origin gFrontEnd )
				)
				( attribute "VOLTAGE" "25V"
					( Units "uVoltage" "V" 1.000000)
					( Origin gFrontEnd )
				)
				( attribute "XY" "(-300,-50)"
					( Origin gFrontEnd )
				)
				( attribute "CHIPS_PART_NAME" "CAP_A"
					( Origin gPackager )
				)
				( attribute "CDS_PART_NAME" "CAP_A_0402V-0.01UF,25V,10%,X7RA"
					( Origin gPackager )
				)
				( objectStatus "C2L50" )
				( pin "a"
					( attribute "PN" "1"
						( Origin gPackager )
					)
					( objectStatus "C2L50.1" )
				)
				( pin "b"
					( attribute "PN" "2"
						( Origin gPackager )
					)
					( objectStatus "C2L50.2" )
				)
			)
			( gate "@baseboard_fab2_lib.baseboard_fab2(sch_1):page172_i8"
				( attribute "CDS_LIB" "dev_discrete"
					( Origin gPackager )
				)
				( attribute "CDS_LOCATION" "C2L51"
					( Origin gPackager )
				)
				( attribute "CDS_SEC" "1"
					( Origin gPackager )
				)
				( attribute "LOCATION" "C2L51"
					( Origin gFrontEnd )
				)
				( attribute "MATERIAL" "X7R"
					( Origin gFrontEnd )
				)
				( attribute "PACK_TYPE" "0402V"
					( Origin gFrontEnd )
				)
				( attribute "PART_NUMBER" "A36096-045"
					( Origin gFrontEnd )
				)
				( attribute "PHYS_PAGE" "172"
					( Origin gFrontEnd )
				)
				( attribute "ROOM" "ST_SATA"
					( Origin gFrontEnd )
				)
				( attribute "ROT" "0"
					( Origin gFrontEnd )
				)
				( attribute "SEC" "1"
					( Origin gFrontEnd )
				)
				( attribute "SEC_TYPE" "0402V"
					( Origin gFrontEnd )
				)
				( attribute "TOLERANCE" "10%"
					( Origin gFrontEnd )
				)
				( attribute "VALUE" "0.01UF"
					( Origin gFrontEnd )
				)
				( attribute "VER" "2"
					( Origin gFrontEnd )
				)
				( attribute "VOLTAGE" "25V"
					( Units "uVoltage" "V" 1.000000)
					( Origin gFrontEnd )
				)
				( attribute "XY" "(100,100)"
					( Origin gFrontEnd )
				)
				( attribute "CHIPS_PART_NAME" "CAP_A"
					( Origin gPackager )
				)
				( attribute "CDS_PART_NAME" "CAP_A_0402V-0.01UF,25V,10%,X7RA"
					( Origin gPackager )
				)
				( objectStatus "C2L51" )
				( pin "a"
					( attribute "PN" "1"
						( Origin gPackager )
					)
					( objectStatus "C2L51.1" )
				)
				( pin "b"
					( attribute "PN" "2"
						( Origin gPackager )
					)
					( objectStatus "C2L51.2" )
				)
			)
			( gate "@baseboard_fab2_lib.baseboard_fab2(sch_1):page172_i17"
				( attribute "CDS_LIB" "mstr_conn"
					( Origin gPackager )
				)
				( attribute "CDS_LOCATION" "J8A3"
					( Origin gPackager )
				)
				( attribute "CDS_SEC" "1"
					( Origin gPackager )
				)
				( attribute "LOCATION" "J8A3"
					( Origin gFrontEnd )
				)
				( attribute "MATERIAL" "EMPTY"
					( Origin gFrontEnd )
				)
				( attribute "PACK_TYPE" "PIP_TH"
					( Origin gFrontEnd )
				)
				( attribute "PART_NUMBER" "E82125-014"
					( Origin gFrontEnd )
				)
				( attribute "PHYS_PAGE" "172"
					( Origin gFrontEnd )
				)
				( attribute "ROOM" "ST_SATA"
					( Origin gFrontEnd )
				)
				( attribute "ROT" "0"
					( Origin gFrontEnd )
				)
				( attribute "SEC" "1"
					( Origin gPackager )
				)
				( attribute "VER" "2"
					( Origin gFrontEnd )
				)
				( attribute "XY" "(-2000,50)"
					( Origin gFrontEnd )
				)
				( attribute "CHIPS_PART_NAME" "CONN7_E82125014"
					( Origin gPackager )
				)
				( attribute "CDS_PART_NAME" "CONN7_E82125014_PIP_TH-EMPTY,EA"
					( Origin gPackager )
				)
				( objectStatus "J8A3" )
				( pin "gnd(0)"
					( attribute "PN" "7"
						( Origin gPackager )
					)
					( objectStatus "J8A3.7" )
				)
				( pin "gnd(1)"
					( attribute "PN" "4"
						( Origin gPackager )
					)
					( objectStatus "J8A3.4" )
				)
				( pin "gnd(2)"
					( attribute "PN" "1"
						( Origin gPackager )
					)
					( objectStatus "J8A3.1" )
				)
				( pin "mh1"
					( attribute "PN" "MH1"
						( Origin gPackager )
					)
					( objectStatus "J8A3.MH1" )
				)
				( pin "mh2"
					( attribute "PN" "MH2"
						( Origin gPackager )
					)
					( objectStatus "J8A3.MH2" )
				)
				( pin "sata_rxn"
					( attribute "PN" "5"
						( Origin gPackager )
					)
					( objectStatus "J8A3.5" )
				)
				( pin "sata_rxp"
					( attribute "PN" "6"
						( Origin gPackager )
					)
					( objectStatus "J8A3.6" )
				)
				( pin "sata_txn"
					( attribute "PN" "3"
						( Origin gPackager )
					)
					( objectStatus "J8A3.3" )
				)
				( pin "sata_txp"
					( attribute "PN" "2"
						( Origin gPackager )
					)
					( objectStatus "J8A3.2" )
				)
			)
			( gate "@baseboard_fab2_lib.baseboard_fab2(sch_1):page172_i25"
				( attribute "CDS_LIB" "mstr_conn"
					( Origin gPackager )
				)
				( attribute "CDS_LOCATION" "J8A4"
					( Origin gPackager )
				)
				( attribute "CDS_SEC" "1"
					( Origin gPackager )
				)
				( attribute "LOCATION" "J8A4"
					( Origin gFrontEnd )
				)
				( attribute "MATERIAL" "EMPTY"
					( Origin gFrontEnd )
				)
				( attribute "PACK_TYPE" "PIP"
					( Origin gFrontEnd )
				)
				( attribute "PART_NUMBER" "H73295-001"
					( Origin gFrontEnd )
				)
				( attribute "PHYS_PAGE" "172"
					( Origin gFrontEnd )
				)
				( attribute "ROOM" "ST_SATA"
					( Origin gFrontEnd )
				)
				( attribute "ROT" "0"
					( Origin gFrontEnd )
				)
				( attribute "SEC" "1"
					( Origin gFrontEnd )
				)
				( attribute "SEC_TYPE" "PIP"
					( Origin gFrontEnd )
				)
				( attribute "VER" "1"
					( Origin gFrontEnd )
				)
				( attribute "XY" "(0,1900)"
					( Origin gFrontEnd )
				)
				( attribute "CHIPS_PART_NAME" "CONN4_H73295001"
					( Origin gPackager )
				)
				( attribute "CDS_PART_NAME" "CONN4_H73295001_PIP-EMPTY,H732A"
					( Origin gPackager )
				)
				( objectStatus "J8A4" )
				( pin "io1"
					( attribute "PN" "1"
						( Origin gPackager )
					)
					( objectStatus "J8A4.1" )
				)
				( pin "io2"
					( attribute "PN" "2"
						( Origin gPackager )
					)
					( objectStatus "J8A4.2" )
				)
				( pin "io3"
					( attribute "PN" "3"
						( Origin gPackager )
					)
					( objectStatus "J8A4.3" )
				)
				( pin "io4"
					( attribute "PN" "4"
						( Origin gPackager )
					)
					( objectStatus "J8A4.4" )
				)
			)
			( gate "@baseboard_fab2_lib.baseboard_fab2(sch_1):page172_i36"
				( attribute "CDS_LIB" "mstr_discrete"
					( Origin gPackager )
				)
				( attribute "CDS_LOCATION" "C9B2"
					( Origin gPackager )
				)
				( attribute "CDS_SEC" "1"
					( Origin gPackager )
				)
				( attribute "LOCATION" "C9B2"
					( Origin gFrontEnd )
				)
				( attribute "MATERIAL" "X6S"
					( Origin gFrontEnd )
				)
				( attribute "PACK_TYPE" "0805"
					( Origin gFrontEnd )
				)
				( attribute "PART_NUMBER" "C95333-007"
					( Origin gFrontEnd )
				)
				( attribute "PHYS_PAGE" "172"
					( Origin gFrontEnd )
				)
				( attribute "ROOM" "ST_SATA"
					( Origin gFrontEnd )
				)
				( attribute "ROT" "0"
					( Origin gFrontEnd )
				)
				( attribute "SEC" "1"
					( Origin gFrontEnd )
				)
				( attribute "SEC_TYPE" "0805"
					( Origin gFrontEnd )
				)
				( attribute "TOLERANCE" "10%"
					( Origin gFrontEnd )
				)
				( attribute "VALUE" "10UF"
					( Origin gFrontEnd )
				)
				( attribute "VER" "1"
					( Origin gFrontEnd )
				)
				( attribute "VOLTAGE" "16V"
					( Units "uVoltage" "V" 1.000000)
					( Origin gFrontEnd )
				)
				( attribute "XY" "(-1125,1575)"
					( Origin gFrontEnd )
				)
				( attribute "CHIPS_PART_NAME" "CAP"
					( Origin gPackager )
				)
				( attribute "CDS_PART_NAME" "CAP_0805-10UF,16V,10%,X6S,C953A"
					( Origin gPackager )
				)
				( objectStatus "C9B2" )
				( pin "a"
					( attribute "PN" "1"
						( Origin gPackager )
					)
					( objectStatus "C9B2.1" )
				)
				( pin "b"
					( attribute "PN" "2"
						( Origin gPackager )
					)
					( objectStatus "C9B2.2" )
				)
			)
			( gate "@baseboard_fab2_lib.baseboard_fab2(sch_1):page172_i38"
				( attribute "CDS_LIB" "mstr_discrete"
					( Origin gPackager )
				)
				( attribute "CDS_LOCATION" "F9B1"
					( Origin gPackager )
				)
				( attribute "CDS_SEC" "1"
					( Origin gPackager )
				)
				( attribute "LOCATION" "F9B1"
					( Origin gFrontEnd )
				)
				( attribute "MATERIAL" "IC"
					( Origin gFrontEnd )
				)
				( attribute "PACK_TYPE" "SM"
					( Origin gFrontEnd )
				)
				( attribute "PART_NUMBER" "C94311-016"
					( Origin gFrontEnd )
				)
				( attribute "PHYS_PAGE" "172"
					( Origin gFrontEnd )
				)
				( attribute "ROOM" "ST_SATA"
					( Origin gFrontEnd )
				)
				( attribute "ROT" "0"
					( Origin gFrontEnd )
				)
				( attribute "SEC" "1"
					( Origin gFrontEnd )
				)
				( attribute "SEC_TYPE" "SM"
					( Origin gFrontEnd )
				)
				( attribute "VER" "1"
					( Origin gFrontEnd )
				)
				( attribute "XY" "(-1825,1800)"
					( Origin gFrontEnd )
				)
				( attribute "CHIPS_PART_NAME" "FUSE"
					( Origin gPackager )
				)
				( attribute "CDS_PART_NAME" "FUSE_SM-IC,C94311-016"
					( Origin gPackager )
				)
				( objectStatus "F9B1" )
				( pin "a(0)"
					( attribute "PN" "1"
						( Origin gPackager )
					)
					( objectStatus "F9B1.1" )
				)
				( pin "b(0)"
					( attribute "PN" "2"
						( Origin gPackager )
					)
					( objectStatus "F9B1.2" )
				)
			)
			( gate "@baseboard_fab2_lib.baseboard_fab2(sch_1):page172_i39"
				( attribute "CDS_LIB" "mstr_discrete"
					( Origin gPackager )
				)
				( attribute "CDS_LOCATION" "C9B1"
					( Origin gPackager )
				)
				( attribute "CDS_SEC" "1"
					( Origin gPackager )
				)
				( attribute "LOCATION" "C9B1"
					( Origin gFrontEnd )
				)
				( attribute "MATERIAL" "X6S"
					( Origin gFrontEnd )
				)
				( attribute "PACK_TYPE" "0805"
					( Origin gFrontEnd )
				)
				( attribute "PART_NUMBER" "C95333-007"
					( Origin gFrontEnd )
				)
				( attribute "PHYS_PAGE" "172"
					( Origin gFrontEnd )
				)
				( attribute "ROOM" "ST_SATA"
					( Origin gFrontEnd )
				)
				( attribute "ROT" "0"
					( Origin gFrontEnd )
				)
				( attribute "SEC" "1"
					( Origin gFrontEnd )
				)
				( attribute "SEC_TYPE" "0805"
					( Origin gFrontEnd )
				)
				( attribute "TOLERANCE" "10%"
					( Origin gFrontEnd )
				)
				( attribute "VALUE" "10UF"
					( Origin gFrontEnd )
				)
				( attribute "VER" "1"
					( Origin gFrontEnd )
				)
				( attribute "VOLTAGE" "16V"
					( Units "uVoltage" "V" 1.000000)
					( Origin gFrontEnd )
				)
				( attribute "XY" "(-700,1575)"
					( Origin gFrontEnd )
				)
				( attribute "CHIPS_PART_NAME" "CAP"
					( Origin gPackager )
				)
				( attribute "CDS_PART_NAME" "CAP_0805-10UF,16V,10%,X6S,C953A"
					( Origin gPackager )
				)
				( objectStatus "C9B1" )
				( pin "a"
					( attribute "PN" "1"
						( Origin gPackager )
					)
					( objectStatus "C9B1.1" )
				)
				( pin "b"
					( attribute "PN" "2"
						( Origin gPackager )
					)
					( objectStatus "C9B1.2" )
				)
			)
			( gate "@baseboard_fab2_lib.baseboard_fab2(sch_1):page172_i41"
				( attribute "CDS_LIB" "mstr_discrete"
					( Origin gPackager )
				)
				( attribute "CDS_LOCATION" "F8B1"
					( Origin gPackager )
				)
				( attribute "CDS_SEC" "1"
					( Origin gPackager )
				)
				( attribute "LOCATION" "F8B1"
					( Origin gFrontEnd )
				)
				( attribute "MATERIAL" "IC"
					( Origin gFrontEnd )
				)
				( attribute "PACK_TYPE" "SMLF"
					( Origin gFrontEnd )
				)
				( attribute "PART_NUMBER" "C94311-006"
					( Origin gFrontEnd )
				)
				( attribute "PHYS_PAGE" "172"
					( Origin gFrontEnd )
				)
				( attribute "ROOM" "ST_SATA"
					( Origin gFrontEnd )
				)
				( attribute "ROT" "0"
					( Origin gFrontEnd )
				)
				( attribute "SEC" "1"
					( Origin gFrontEnd )
				)
				( attribute "SEC_TYPE" "SMLF"
					( Origin gFrontEnd )
				)
				( attribute "VER" "1"
					( Origin gFrontEnd )
				)
				( attribute "XY" "(-1175,1950)"
					( Origin gFrontEnd )
				)
				( attribute "CHIPS_PART_NAME" "FUSE"
					( Origin gPackager )
				)
				( attribute "CDS_PART_NAME" "FUSE_SMLF-IC,C94311-006"
					( Origin gPackager )
				)
				( objectStatus "F8B1" )
				( pin "a(0)"
					( attribute "PN" "1"
						( Origin gPackager )
					)
					( objectStatus "F8B1.1" )
				)
				( pin "b(0)"
					( attribute "PN" "2"
						( Origin gPackager )
					)
					( objectStatus "F8B1.2" )
				)
			)
			( gate "@baseboard_fab2_lib.baseboard_fab2(sch_1):page172_i52"
				( attribute "CDS_LIB" "mstr_conn"
					( Origin gPackager )
				)
				( attribute "CDS_LOCATION" "J2M1"
					( Origin gPackager )
				)
				( attribute "CDS_SEC" "1"
					( Origin gPackager )
				)
				( attribute "LOCATION" "J2M1"
					( Origin gFrontEnd )
				)
				( attribute "MATERIAL" "CONN"
					( Origin gFrontEnd )
				)
				( attribute "PACK_TYPE" "PIP_TH"
					( Origin gFrontEnd )
				)
				( attribute "PART_NUMBER" "E82125-014"
					( Origin gFrontEnd )
				)
				( attribute "PHYS_PAGE" "172"
					( Origin gFrontEnd )
				)
				( attribute "ROOM" "ST_SATA"
					( Origin gFrontEnd )
				)
				( attribute "ROT" "0"
					( Origin gFrontEnd )
				)
				( attribute "SEC" "1"
					( Origin gPackager )
				)
				( attribute "VER" "2"
					( Origin gFrontEnd )
				)
				( attribute "XY" "(-2025,-1075)"
					( Origin gFrontEnd )
				)
				( attribute "CHIPS_PART_NAME" "CONN7_E82125014"
					( Origin gPackager )
				)
				( attribute "CDS_PART_NAME" "CONN7_E82125014_PIP_TH-CONN,E8A"
					( Origin gPackager )
				)
				( objectStatus "J2M1" )
				( pin "gnd(0)"
					( attribute "PN" "7"
						( Origin gPackager )
					)
					( objectStatus "J2M1.7" )
				)
				( pin "gnd(1)"
					( attribute "PN" "4"
						( Origin gPackager )
					)
					( objectStatus "J2M1.4" )
				)
				( pin "gnd(2)"
					( attribute "PN" "1"
						( Origin gPackager )
					)
					( objectStatus "J2M1.1" )
				)
				( pin "mh1"
					( attribute "PN" "MH1"
						( Origin gPackager )
					)
					( objectStatus "J2M1.MH1" )
				)
				( pin "mh2"
					( attribute "PN" "MH2"
						( Origin gPackager )
					)
					( objectStatus "J2M1.MH2" )
				)
				( pin "sata_rxn"
					( attribute "PN" "5"
						( Origin gPackager )
					)
					( objectStatus "J2M1.5" )
				)
				( pin "sata_rxp"
					( attribute "PN" "6"
						( Origin gPackager )
					)
					( objectStatus "J2M1.6" )
				)
				( pin "sata_txn"
					( attribute "PN" "3"
						( Origin gPackager )
					)
					( objectStatus "J2M1.3" )
				)
				( pin "sata_txp"
					( attribute "PN" "2"
						( Origin gPackager )
					)
					( objectStatus "J2M1.2" )
				)
			)
			( gate "@baseboard_fab2_lib.baseboard_fab2(sch_1):page172_i53"
				( attribute "CDS_LIB" "mstr_conn"
					( Origin gPackager )
				)
				( attribute "CDS_LOCATION" "J2L1"
					( Origin gPackager )
				)
				( attribute "CDS_SEC" "1"
					( Origin gPackager )
				)
				( attribute "LOCATION" "J2L1"
					( Origin gFrontEnd )
				)
				( attribute "MATERIAL" "CONN"
					( Origin gFrontEnd )
				)
				( attribute "PACK_TYPE" "PIP"
					( Origin gFrontEnd )
				)
				( attribute "PART_NUMBER" "H73295-001"
					( Origin gFrontEnd )
				)
				( attribute "PHYS_PAGE" "172"
					( Origin gFrontEnd )
				)
				( attribute "ROOM" "ST_SATA"
					( Origin gFrontEnd )
				)
				( attribute "ROT" "0"
					( Origin gFrontEnd )
				)
				( attribute "SEC" "1"
					( Origin gFrontEnd )
				)
				( attribute "SEC_TYPE" "PIP"
					( Origin gFrontEnd )
				)
				( attribute "VER" "1"
					( Origin gFrontEnd )
				)
				( attribute "XY" "(25,925)"
					( Origin gFrontEnd )
				)
				( attribute "CHIPS_PART_NAME" "CONN4_H73295001"
					( Origin gPackager )
				)
				( attribute "CDS_PART_NAME" "CONN4_H73295001_PIP-CONN,H7329A"
					( Origin gPackager )
				)
				( objectStatus "J2L1" )
				( pin "io1"
					( attribute "PN" "1"
						( Origin gPackager )
					)
					( objectStatus "J2L1.1" )
				)
				( pin "io2"
					( attribute "PN" "2"
						( Origin gPackager )
					)
					( objectStatus "J2L1.2" )
				)
				( pin "io3"
					( attribute "PN" "3"
						( Origin gPackager )
					)
					( objectStatus "J2L1.3" )
				)
				( pin "io4"
					( attribute "PN" "4"
						( Origin gPackager )
					)
					( objectStatus "J2L1.4" )
				)
			)
			( gate "@baseboard_fab2_lib.baseboard_fab2(sch_1):page173_i163"
				( attribute "BOM_COST" "ST_SATA"
					( Origin gFrontEnd )
				)
				( attribute "CDS_LIB" "mstr_conn"
					( Origin gPackager )
				)
				( attribute "CDS_LOCATION" "J8A1"
					( Origin gPackager )
				)
				( attribute "CDS_SEC" "1"
					( Origin gPackager )
				)
				( attribute "LOCATION" "J8A1"
					( Origin gFrontEnd )
				)
				( attribute "MATERIAL" "CONN"
					( Origin gFrontEnd )
				)
				( attribute "PACK_TYPE" "CP"
					( Origin gFrontEnd )
				)
				( attribute "PART_NUMBER" "G97614-002"
					( Origin gFrontEnd )
				)
				( attribute "PHYS_PAGE" "173"
					( Origin gFrontEnd )
				)
				( attribute "ROOM" "ST_SATA"
					( Origin gFrontEnd )
				)
				( attribute "ROT" "0"
					( Origin gFrontEnd )
				)
				( attribute "SEC" "1"
					( Origin gFrontEnd )
				)
				( attribute "SEC_TYPE" "CP"
					( Origin gFrontEnd )
				)
				( attribute "VER" "1"
					( Origin gFrontEnd )
				)
				( attribute "XY" "(-2025,3100)"
					( Origin gFrontEnd )
				)
				( attribute "CHIPS_PART_NAME" "CONN72_G97614002_A"
					( Origin gPackager )
				)
				( attribute "CDS_PART_NAME" "CONN72_G97614002_A_CP-CONN,G97A"
					( Origin gPackager )
				)
				( objectStatus "J8A1" )
				( pin "gnd(0)"
					( attribute "PN" "2D9"
						( Origin gPackager )
					)
					( objectStatus "J8A1.2D9" )
				)
				( pin "gnd(1)"
					( attribute "PN" "2D6"
						( Origin gPackager )
					)
					( objectStatus "J8A1.2D6" )
				)
				( pin "gnd(2)"
					( attribute "PN" "2D3"
						( Origin gPackager )
					)
					( objectStatus "J8A1.2D3" )
				)
				( pin "gnd(3)"
					( attribute "PN" "2C9"
						( Origin gPackager )
					)
					( objectStatus "J8A1.2C9" )
				)
				( pin "gnd(4)"
					( attribute "PN" "2C6"
						( Origin gPackager )
					)
					( objectStatus "J8A1.2C6" )
				)
				( pin "gnd(5)"
					( attribute "PN" "2C3"
						( Origin gPackager )
					)
					( objectStatus "J8A1.2C3" )
				)
				( pin "gnd(6)"
					( attribute "PN" "2B9"
						( Origin gPackager )
					)
					( objectStatus "J8A1.2B9" )
				)
				( pin "gnd(7)"
					( attribute "PN" "2B6"
						( Origin gPackager )
					)
					( objectStatus "J8A1.2B6" )
				)
				( pin "gnd(8)"
					( attribute "PN" "2B3"
						( Origin gPackager )
					)
					( objectStatus "J8A1.2B3" )
				)
				( pin "gnd(9)"
					( attribute "PN" "2A9"
						( Origin gPackager )
					)
					( objectStatus "J8A1.2A9" )
				)
				( pin "gnd(10)"
					( attribute "PN" "2A6"
						( Origin gPackager )
					)
					( objectStatus "J8A1.2A6" )
				)
				( pin "gnd(11)"
					( attribute "PN" "2A3"
						( Origin gPackager )
					)
					( objectStatus "J8A1.2A3" )
				)
				( pin "gnd(12)"
					( attribute "PN" "1D9"
						( Origin gPackager )
					)
					( objectStatus "J8A1.1D9" )
				)
				( pin "gnd(13)"
					( attribute "PN" "1D6"
						( Origin gPackager )
					)
					( objectStatus "J8A1.1D6" )
				)
				( pin "gnd(14)"
					( attribute "PN" "1D3"
						( Origin gPackager )
					)
					( objectStatus "J8A1.1D3" )
				)
				( pin "gnd(15)"
					( attribute "PN" "1C9"
						( Origin gPackager )
					)
					( objectStatus "J8A1.1C9" )
				)
				( pin "gnd(16)"
					( attribute "PN" "1C6"
						( Origin gPackager )
					)
					( objectStatus "J8A1.1C6" )
				)
				( pin "gnd(17)"
					( attribute "PN" "1C3"
						( Origin gPackager )
					)
					( objectStatus "J8A1.1C3" )
				)
				( pin "gnd(18)"
					( attribute "PN" "1B9"
						( Origin gPackager )
					)
					( objectStatus "J8A1.1B9" )
				)
				( pin "gnd(19)"
					( attribute "PN" "1B6"
						( Origin gPackager )
					)
					( objectStatus "J8A1.1B6" )
				)
				( pin "gnd(20)"
					( attribute "PN" "1B3"
						( Origin gPackager )
					)
					( objectStatus "J8A1.1B3" )
				)
				( pin "gnd(21)"
					( attribute "PN" "1A9"
						( Origin gPackager )
					)
					( objectStatus "J8A1.1A9" )
				)
				( pin "gnd(22)"
					( attribute "PN" "1A6"
						( Origin gPackager )
					)
					( objectStatus "J8A1.1A6" )
				)
				( pin "gnd(23)"
					( attribute "PN" "1A3"
						( Origin gPackager )
					)
					( objectStatus "J8A1.1A3" )
				)
				( pin "rxa0_dn"
					( attribute "PN" "1B5"
						( Origin gPackager )
					)
					( objectStatus "J8A1.1B5" )
				)
				( pin "rxa0_dp"
					( attribute "PN" "1B4"
						( Origin gPackager )
					)
					( objectStatus "J8A1.1B4" )
				)
				( pin "rxa1_dn"
					( attribute "PN" "1A5"
						( Origin gPackager )
					)
					( objectStatus "J8A1.1A5" )
				)
				( pin "rxa1_dp"
					( attribute "PN" "1A4"
						( Origin gPackager )
					)
					( objectStatus "J8A1.1A4" )
				)
				( pin "rxa2_dn"
					( attribute "PN" "1B8"
						( Origin gPackager )
					)
					( objectStatus "J8A1.1B8" )
				)
				( pin "rxa2_dp"
					( attribute "PN" "1B7"
						( Origin gPackager )
					)
					( objectStatus "J8A1.1B7" )
				)
				( pin "rxa3_dn"
					( attribute "PN" "1A8"
						( Origin gPackager )
					)
					( objectStatus "J8A1.1A8" )
				)
				( pin "rxa3_dp"
					( attribute "PN" "1A7"
						( Origin gPackager )
					)
					( objectStatus "J8A1.1A7" )
				)
				( pin "rxb0_dn"
					( attribute "PN" "2B5"
						( Origin gPackager )
					)
					( objectStatus "J8A1.2B5" )
				)
				( pin "rxb0_dp"
					( attribute "PN" "2B4"
						( Origin gPackager )
					)
					( objectStatus "J8A1.2B4" )
				)
				( pin "rxb1_dn"
					( attribute "PN" "2A5"
						( Origin gPackager )
					)
					( objectStatus "J8A1.2A5" )
				)
				( pin "rxb1_dp"
					( attribute "PN" "2A4"
						( Origin gPackager )
					)
					( objectStatus "J8A1.2A4" )
				)
				( pin "rxb2_dn"
					( attribute "PN" "2B8"
						( Origin gPackager )
					)
					( objectStatus "J8A1.2B8" )
				)
				( pin "rxb2_dp"
					( attribute "PN" "2B7"
						( Origin gPackager )
					)
					( objectStatus "J8A1.2B7" )
				)
				( pin "rxb3_dn"
					( attribute "PN" "2A8"
						( Origin gPackager )
					)
					( objectStatus "J8A1.2A8" )
				)
				( pin "rxb3_dp"
					( attribute "PN" "2A7"
						( Origin gPackager )
					)
					( objectStatus "J8A1.2A7" )
				)
				( pin "sidebanda_0"
					( attribute "PN" "1A2"
						( Origin gPackager )
					)
					( objectStatus "J8A1.1A2" )
				)
				( pin "sidebanda_1"
					( attribute "PN" "1B2"
						( Origin gPackager )
					)
					( objectStatus "J8A1.1B2" )
				)
				( pin "sidebanda_2"
					( attribute "PN" "1C2"
						( Origin gPackager )
					)
					( objectStatus "J8A1.1C2" )
				)
				( pin "sidebanda_3"
					( attribute "PN" "1B1"
						( Origin gPackager )
					)
					( objectStatus "J8A1.1B1" )
				)
				( pin "sidebanda_4"
					( attribute "PN" "1C1"
						( Origin gPackager )
					)
					( objectStatus "J8A1.1C1" )
				)
				( pin "sidebanda_5"
					( attribute "PN" "1D1"
						( Origin gPackager )
					)
					( objectStatus "J8A1.1D1" )
				)
				( pin "sidebanda_6"
					( attribute "PN" "1D2"
						( Origin gPackager )
					)
					( objectStatus "J8A1.1D2" )
				)
				( pin "sidebanda_7"
					( attribute "PN" "1A1"
						( Origin gPackager )
					)
					( objectStatus "J8A1.1A1" )
				)
				( pin "sidebandb_0"
					( attribute "PN" "2A2"
						( Origin gPackager )
					)
					( objectStatus "J8A1.2A2" )
				)
				( pin "sidebandb_1"
					( attribute "PN" "2B2"
						( Origin gPackager )
					)
					( objectStatus "J8A1.2B2" )
				)
				( pin "sidebandb_2"
					( attribute "PN" "2C2"
						( Origin gPackager )
					)
					( objectStatus "J8A1.2C2" )
				)
				( pin "sidebandb_3"
					( attribute "PN" "2B1"
						( Origin gPackager )
					)
					( objectStatus "J8A1.2B1" )
				)
				( pin "sidebandb_4"
					( attribute "PN" "2C1"
						( Origin gPackager )
					)
					( objectStatus "J8A1.2C1" )
				)
				( pin "sidebandb_5"
					( attribute "PN" "2D1"
						( Origin gPackager )
					)
					( objectStatus "J8A1.2D1" )
				)
				( pin "sidebandb_6"
					( attribute "PN" "2D2"
						( Origin gPackager )
					)
					( objectStatus "J8A1.2D2" )
				)
				( pin "sidebandb_7"
					( attribute "PN" "2A1"
						( Origin gPackager )
					)
					( objectStatus "J8A1.2A1" )
				)
				( pin "txa0_dn"
					( attribute "PN" "1D5"
						( Origin gPackager )
					)
					( objectStatus "J8A1.1D5" )
				)
				( pin "txa0_dp"
					( attribute "PN" "1D4"
						( Origin gPackager )
					)
					( objectStatus "J8A1.1D4" )
				)
				( pin "txa1_dn"
					( attribute "PN" "1C5"
						( Origin gPackager )
					)
					( objectStatus "J8A1.1C5" )
				)
				( pin "txa1_dp"
					( attribute "PN" "1C4"
						( Origin gPackager )
					)
					( objectStatus "J8A1.1C4" )
				)
				( pin "txa2_dn"
					( attribute "PN" "1D8"
						( Origin gPackager )
					)
					( objectStatus "J8A1.1D8" )
				)
				( pin "txa2_dp"
					( attribute "PN" "1D7"
						( Origin gPackager )
					)
					( objectStatus "J8A1.1D7" )
				)
				( pin "txa3_dn"
					( attribute "PN" "1C8"
						( Origin gPackager )
					)
					( objectStatus "J8A1.1C8" )
				)
				( pin "txa3_dp"
					( attribute "PN" "1C7"
						( Origin gPackager )
					)
					( objectStatus "J8A1.1C7" )
				)
				( pin "txb0_dn"
					( attribute "PN" "2D5"
						( Origin gPackager )
					)
					( objectStatus "J8A1.2D5" )
				)
				( pin "txb0_dp"
					( attribute "PN" "2D4"
						( Origin gPackager )
					)
					( objectStatus "J8A1.2D4" )
				)
				( pin "txb1_dn"
					( attribute "PN" "2C5"
						( Origin gPackager )
					)
					( objectStatus "J8A1.2C5" )
				)
				( pin "txb1_dp"
					( attribute "PN" "2C4"
						( Origin gPackager )
					)
					( objectStatus "J8A1.2C4" )
				)
				( pin "txb2_dn"
					( attribute "PN" "2D8"
						( Origin gPackager )
					)
					( objectStatus "J8A1.2D8" )
				)
				( pin "txb2_dp"
					( attribute "PN" "2D7"
						( Origin gPackager )
					)
					( objectStatus "J8A1.2D7" )
				)
				( pin "txb3_dn"
					( attribute "PN" "2C8"
						( Origin gPackager )
					)
					( objectStatus "J8A1.2C8" )
				)
				( pin "txb3_dp"
					( attribute "PN" "2C7"
						( Origin gPackager )
					)
					( objectStatus "J8A1.2C7" )
				)
			)
			( gate "@baseboard_fab2_lib.baseboard_fab2(sch_1):page173_i165"
				( attribute "BOM_COST" "ST_SATA"
					( Origin gFrontEnd )
				)
				( attribute "CDS_LIB" "dev_discrete"
					( Origin gPackager )
				)
				( attribute "CDS_LOCATION" "C2L13"
					( Origin gPackager )
				)
				( attribute "CDS_SEC" "1"
					( Origin gPackager )
				)
				( attribute "LOCATION" "C2L13"
					( Origin gFrontEnd )
				)
				( attribute "MATERIAL" "X7R"
					( Origin gFrontEnd )
				)
				( attribute "PACK_TYPE" "0402V"
					( Origin gFrontEnd )
				)
				( attribute "PART_NUMBER" "A36096-045"
					( Origin gFrontEnd )
				)
				( attribute "PHYS_PAGE" "173"
					( Origin gFrontEnd )
				)
				( attribute "ROOM" "ST_SATA"
					( Origin gFrontEnd )
				)
				( attribute "ROT" "0"
					( Origin gFrontEnd )
				)
				( attribute "SEC" "1"
					( Origin gFrontEnd )
				)
				( attribute "SEC_TYPE" "0402V"
					( Origin gFrontEnd )
				)
				( attribute "TOLERANCE" "10%"
					( Origin gFrontEnd )
				)
				( attribute "VALUE" "0.01UF"
					( Origin gFrontEnd )
				)
				( attribute "VER" "2"
					( Origin gFrontEnd )
				)
				( attribute "VOLTAGE" "25V"
					( Units "uVoltage" "V" 1.000000)
					( Origin gFrontEnd )
				)
				( attribute "XY" "(-4900,3550)"
					( Origin gFrontEnd )
				)
				( attribute "CHIPS_PART_NAME" "CAP_A"
					( Origin gPackager )
				)
				( attribute "CDS_PART_NAME" "CAP_A_0402V-0.01UF,25V,10%,X7RA"
					( Origin gPackager )
				)
				( objectStatus "C2L13" )
				( pin "a"
					( attribute "PN" "1"
						( Origin gPackager )
					)
					( objectStatus "C2L13.1" )
				)
				( pin "b"
					( attribute "PN" "2"
						( Origin gPackager )
					)
					( objectStatus "C2L13.2" )
				)
			)
			( gate "@baseboard_fab2_lib.baseboard_fab2(sch_1):page173_i166"
				( attribute "BOM_COST" "ST_SATA"
					( Origin gFrontEnd )
				)
				( attribute "CDS_LIB" "dev_discrete"
					( Origin gPackager )
				)
				( attribute "CDS_LOCATION" "C2L6"
					( Origin gPackager )
				)
				( attribute "CDS_SEC" "1"
					( Origin gPackager )
				)
				( attribute "LOCATION" "C2L6"
					( Origin gFrontEnd )
				)
				( attribute "MATERIAL" "X7R"
					( Origin gFrontEnd )
				)
				( attribute "PACK_TYPE" "0402V"
					( Origin gFrontEnd )
				)
				( attribute "PART_NUMBER" "A36096-045"
					( Origin gFrontEnd )
				)
				( attribute "PHYS_PAGE" "173"
					( Origin gFrontEnd )
				)
				( attribute "ROOM" "ST_SATA"
					( Origin gFrontEnd )
				)
				( attribute "ROT" "0"
					( Origin gFrontEnd )
				)
				( attribute "SEC" "1"
					( Origin gFrontEnd )
				)
				( attribute "SEC_TYPE" "0402V"
					( Origin gFrontEnd )
				)
				( attribute "TOLERANCE" "10%"
					( Origin gFrontEnd )
				)
				( attribute "VALUE" "0.01UF"
					( Origin gFrontEnd )
				)
				( attribute "VER" "2"
					( Origin gFrontEnd )
				)
				( attribute "VOLTAGE" "25V"
					( Units "uVoltage" "V" 1.000000)
					( Origin gFrontEnd )
				)
				( attribute "XY" "(-4850,4050)"
					( Origin gFrontEnd )
				)
				( attribute "CHIPS_PART_NAME" "CAP_A"
					( Origin gPackager )
				)
				( attribute "CDS_PART_NAME" "CAP_A_0402V-0.01UF,25V,10%,X7RA"
					( Origin gPackager )
				)
				( objectStatus "C2L6" )
				( pin "a"
					( attribute "PN" "1"
						( Origin gPackager )
					)
					( objectStatus "C2L6.1" )
				)
				( pin "b"
					( attribute "PN" "2"
						( Origin gPackager )
					)
					( objectStatus "C2L6.2" )
				)
			)
			( gate "@baseboard_fab2_lib.baseboard_fab2(sch_1):page173_i172"
				( attribute "BOM_COST" "ST_SATA"
					( Origin gFrontEnd )
				)
				( attribute "CDS_LIB" "dev_discrete"
					( Origin gPackager )
				)
				( attribute "CDS_LOCATION" "C2L19"
					( Origin gPackager )
				)
				( attribute "CDS_SEC" "1"
					( Origin gPackager )
				)
				( attribute "LOCATION" "C2L19"
					( Origin gFrontEnd )
				)
				( attribute "MATERIAL" "X7R"
					( Origin gFrontEnd )
				)
				( attribute "PACK_TYPE" "0402V"
					( Origin gFrontEnd )
				)
				( attribute "PART_NUMBER" "A36096-045"
					( Origin gFrontEnd )
				)
				( attribute "PHYS_PAGE" "173"
					( Origin gFrontEnd )
				)
				( attribute "ROOM" "ST_SATA"
					( Origin gFrontEnd )
				)
				( attribute "ROT" "0"
					( Origin gFrontEnd )
				)
				( attribute "SEC" "1"
					( Origin gFrontEnd )
				)
				( attribute "SEC_TYPE" "0402V"
					( Origin gFrontEnd )
				)
				( attribute "TOLERANCE" "10%"
					( Origin gFrontEnd )
				)
				( attribute "VALUE" "0.01UF"
					( Origin gFrontEnd )
				)
				( attribute "VER" "2"
					( Origin gFrontEnd )
				)
				( attribute "VOLTAGE" "25V"
					( Units "uVoltage" "V" 1.000000)
					( Origin gFrontEnd )
				)
				( attribute "XY" "(-4575,4550)"
					( Origin gFrontEnd )
				)
				( attribute "CHIPS_PART_NAME" "CAP_A"
					( Origin gPackager )
				)
				( attribute "CDS_PART_NAME" "CAP_A_0402V-0.01UF,25V,10%,X7RA"
					( Origin gPackager )
				)
				( objectStatus "C2L19" )
				( pin "a"
					( attribute "PN" "1"
						( Origin gPackager )
					)
					( objectStatus "C2L19.1" )
				)
				( pin "b"
					( attribute "PN" "2"
						( Origin gPackager )
					)
					( objectStatus "C2L19.2" )
				)
			)
			( gate "@baseboard_fab2_lib.baseboard_fab2(sch_1):page173_i173"
				( attribute "BOM_COST" "ST_SATA"
					( Origin gFrontEnd )
				)
				( attribute "CDS_LIB" "dev_discrete"
					( Origin gPackager )
				)
				( attribute "CDS_LOCATION" "C2L10"
					( Origin gPackager )
				)
				( attribute "CDS_SEC" "1"
					( Origin gPackager )
				)
				( attribute "LOCATION" "C2L10"
					( Origin gFrontEnd )
				)
				( attribute "MATERIAL" "X7R"
					( Origin gFrontEnd )
				)
				( attribute "PACK_TYPE" "0402V"
					( Origin gFrontEnd )
				)
				( attribute "PART_NUMBER" "A36096-045"
					( Origin gFrontEnd )
				)
				( attribute "PHYS_PAGE" "173"
					( Origin gFrontEnd )
				)
				( attribute "ROOM" "ST_SATA"
					( Origin gFrontEnd )
				)
				( attribute "ROT" "0"
					( Origin gFrontEnd )
				)
				( attribute "SEC" "1"
					( Origin gFrontEnd )
				)
				( attribute "SEC_TYPE" "0402V"
					( Origin gFrontEnd )
				)
				( attribute "TOLERANCE" "10%"
					( Origin gFrontEnd )
				)
				( attribute "VALUE" "0.01UF"
					( Origin gFrontEnd )
				)
				( attribute "VER" "2"
					( Origin gFrontEnd )
				)
				( attribute "VOLTAGE" "25V"
					( Units "uVoltage" "V" 1.000000)
					( Origin gFrontEnd )
				)
				( attribute "XY" "(-4575,4200)"
					( Origin gFrontEnd )
				)
				( attribute "CHIPS_PART_NAME" "CAP_A"
					( Origin gPackager )
				)
				( attribute "CDS_PART_NAME" "CAP_A_0402V-0.01UF,25V,10%,X7RA"
					( Origin gPackager )
				)
				( objectStatus "C2L10" )
				( pin "a"
					( attribute "PN" "1"
						( Origin gPackager )
					)
					( objectStatus "C2L10.1" )
				)
				( pin "b"
					( attribute "PN" "2"
						( Origin gPackager )
					)
					( objectStatus "C2L10.2" )
				)
			)
			( gate "@baseboard_fab2_lib.baseboard_fab2(sch_1):page173_i174"
				( attribute "BOM_COST" "ST_SATA"
					( Origin gFrontEnd )
				)
				( attribute "CDS_LIB" "dev_discrete"
					( Origin gPackager )
				)
				( attribute "CDS_LOCATION" "C2L17"
					( Origin gPackager )
				)
				( attribute "CDS_SEC" "1"
					( Origin gPackager )
				)
				( attribute "LOCATION" "C2L17"
					( Origin gFrontEnd )
				)
				( attribute "MATERIAL" "X7R"
					( Origin gFrontEnd )
				)
				( attribute "PACK_TYPE" "0402V"
					( Origin gFrontEnd )
				)
				( attribute "PART_NUMBER" "A36096-045"
					( Origin gFrontEnd )
				)
				( attribute "PHYS_PAGE" "173"
					( Origin gFrontEnd )
				)
				( attribute "ROOM" "ST_SATA"
					( Origin gFrontEnd )
				)
				( attribute "ROT" "0"
					( Origin gFrontEnd )
				)
				( attribute "SEC" "1"
					( Origin gFrontEnd )
				)
				( attribute "SEC_TYPE" "0402V"
					( Origin gFrontEnd )
				)
				( attribute "TOLERANCE" "10%"
					( Origin gFrontEnd )
				)
				( attribute "VALUE" "0.01UF"
					( Origin gFrontEnd )
				)
				( attribute "VER" "2"
					( Origin gFrontEnd )
				)
				( attribute "VOLTAGE" "25V"
					( Units "uVoltage" "V" 1.000000)
					( Origin gFrontEnd )
				)
				( attribute "XY" "(-4850,4400)"
					( Origin gFrontEnd )
				)
				( attribute "CHIPS_PART_NAME" "CAP_A"
					( Origin gPackager )
				)
				( attribute "CDS_PART_NAME" "CAP_A_0402V-0.01UF,25V,10%,X7RA"
					( Origin gPackager )
				)
				( objectStatus "C2L17" )
				( pin "a"
					( attribute "PN" "1"
						( Origin gPackager )
					)
					( objectStatus "C2L17.1" )
				)
				( pin "b"
					( attribute "PN" "2"
						( Origin gPackager )
					)
					( objectStatus "C2L17.2" )
				)
			)
			( gate "@baseboard_fab2_lib.baseboard_fab2(sch_1):page173_i191"
				( attribute "BOM_COST" "ST_SATA"
					( Origin gFrontEnd )
				)
				( attribute "CDS_LIB" "dev_discrete"
					( Origin gPackager )
				)
				( attribute "CDS_LOCATION" "C2L15"
					( Origin gPackager )
				)
				( attribute "CDS_SEC" "1"
					( Origin gPackager )
				)
				( attribute "LOCATION" "C2L15"
					( Origin gFrontEnd )
				)
				( attribute "MATERIAL" "X7R"
					( Origin gFrontEnd )
				)
				( attribute "PACK_TYPE" "0402V"
					( Origin gFrontEnd )
				)
				( attribute "PART_NUMBER" "A36096-045"
					( Origin gFrontEnd )
				)
				( attribute "PHYS_PAGE" "173"
					( Origin gFrontEnd )
				)
				( attribute "ROOM" "ST_SATA"
					( Origin gFrontEnd )
				)
				( attribute "ROT" "0"
					( Origin gFrontEnd )
				)
				( attribute "SEC" "1"
					( Origin gFrontEnd )
				)
				( attribute "SEC_TYPE" "0402V"
					( Origin gFrontEnd )
				)
				( attribute "TOLERANCE" "10%"
					( Origin gFrontEnd )
				)
				( attribute "VALUE" "0.01UF"
					( Origin gFrontEnd )
				)
				( attribute "VER" "2"
					( Origin gFrontEnd )
				)
				( attribute "VOLTAGE" "25V"
					( Units "uVoltage" "V" 1.000000)
					( Origin gFrontEnd )
				)
				( attribute "XY" "(-4575,3700)"
					( Origin gFrontEnd )
				)
				( attribute "CHIPS_PART_NAME" "CAP_A"
					( Origin gPackager )
				)
				( attribute "CDS_PART_NAME" "CAP_A_0402V-0.01UF,25V,10%,X7RA"
					( Origin gPackager )
				)
				( objectStatus "C2L15" )
				( pin "a"
					( attribute "PN" "1"
						( Origin gPackager )
					)
					( objectStatus "C2L15.1" )
				)
				( pin "b"
					( attribute "PN" "2"
						( Origin gPackager )
					)
					( objectStatus "C2L15.2" )
				)
			)
			( gate "@baseboard_fab2_lib.baseboard_fab2(sch_1):page173_i192"
				( attribute "BOM_COST" "ST_SATA"
					( Origin gFrontEnd )
				)
				( attribute "CDS_LIB" "dev_discrete"
					( Origin gPackager )
				)
				( attribute "CDS_LOCATION" "C2L4"
					( Origin gPackager )
				)
				( attribute "CDS_SEC" "1"
					( Origin gPackager )
				)
				( attribute "LOCATION" "C2L4"
					( Origin gFrontEnd )
				)
				( attribute "MATERIAL" "X7R"
					( Origin gFrontEnd )
				)
				( attribute "PACK_TYPE" "0402V"
					( Origin gFrontEnd )
				)
				( attribute "PART_NUMBER" "A36096-045"
					( Origin gFrontEnd )
				)
				( attribute "PHYS_PAGE" "173"
					( Origin gFrontEnd )
				)
				( attribute "ROOM" "ST_SATA"
					( Origin gFrontEnd )
				)
				( attribute "ROT" "0"
					( Origin gFrontEnd )
				)
				( attribute "SEC" "1"
					( Origin gFrontEnd )
				)
				( attribute "SEC_TYPE" "0402V"
					( Origin gFrontEnd )
				)
				( attribute "TOLERANCE" "10%"
					( Origin gFrontEnd )
				)
				( attribute "VALUE" "0.01UF"
					( Origin gFrontEnd )
				)
				( attribute "VER" "2"
					( Origin gFrontEnd )
				)
				( attribute "VOLTAGE" "25V"
					( Units "uVoltage" "V" 1.000000)
					( Origin gFrontEnd )
				)
				( attribute "XY" "(-4575,3350)"
					( Origin gFrontEnd )
				)
				( attribute "CHIPS_PART_NAME" "CAP_A"
					( Origin gPackager )
				)
				( attribute "CDS_PART_NAME" "CAP_A_0402V-0.01UF,25V,10%,X7RA"
					( Origin gPackager )
				)
				( objectStatus "C2L4" )
				( pin "a"
					( attribute "PN" "1"
						( Origin gPackager )
					)
					( objectStatus "C2L4.1" )
				)
				( pin "b"
					( attribute "PN" "2"
						( Origin gPackager )
					)
					( objectStatus "C2L4.2" )
				)
			)
			( gate "@baseboard_fab2_lib.baseboard_fab2(sch_1):page173_i194"
				( attribute "BOM_COST" "ST_SATA"
					( Origin gFrontEnd )
				)
				( attribute "CDS_LIB" "dev_discrete"
					( Origin gPackager )
				)
				( attribute "CDS_LOCATION" "C2L3"
					( Origin gPackager )
				)
				( attribute "CDS_SEC" "1"
					( Origin gPackager )
				)
				( attribute "LOCATION" "C2L3"
					( Origin gFrontEnd )
				)
				( attribute "MATERIAL" "X7R"
					( Origin gFrontEnd )
				)
				( attribute "PACK_TYPE" "0402V"
					( Origin gFrontEnd )
				)
				( attribute "PART_NUMBER" "A36096-045"
					( Origin gFrontEnd )
				)
				( attribute "PHYS_PAGE" "173"
					( Origin gFrontEnd )
				)
				( attribute "ROOM" "ST_SATA"
					( Origin gFrontEnd )
				)
				( attribute "ROT" "0"
					( Origin gFrontEnd )
				)
				( attribute "SEC" "1"
					( Origin gFrontEnd )
				)
				( attribute "SEC_TYPE" "0402V"
					( Origin gFrontEnd )
				)
				( attribute "TOLERANCE" "10%"
					( Origin gFrontEnd )
				)
				( attribute "VALUE" "0.01UF"
					( Origin gFrontEnd )
				)
				( attribute "VER" "2"
					( Origin gFrontEnd )
				)
				( attribute "VOLTAGE" "25V"
					( Units "uVoltage" "V" 1.000000)
					( Origin gFrontEnd )
				)
				( attribute "XY" "(-4900,3200)"
					( Origin gFrontEnd )
				)
				( attribute "CHIPS_PART_NAME" "CAP_A"
					( Origin gPackager )
				)
				( attribute "CDS_PART_NAME" "CAP_A_0402V-0.01UF,25V,10%,X7RA"
					( Origin gPackager )
				)
				( objectStatus "C2L3" )
				( pin "a"
					( attribute "PN" "1"
						( Origin gPackager )
					)
					( objectStatus "C2L3.1" )
				)
				( pin "b"
					( attribute "PN" "2"
						( Origin gPackager )
					)
					( objectStatus "C2L3.2" )
				)
			)
			( gate "@baseboard_fab2_lib.baseboard_fab2(sch_1):page173_i195"
				( attribute "BOM_COST" "ST_SATA"
					( Origin gFrontEnd )
				)
				( attribute "CDS_LIB" "dev_discrete"
					( Origin gPackager )
				)
				( attribute "CDS_LOCATION" "C2L20"
					( Origin gPackager )
				)
				( attribute "CDS_SEC" "1"
					( Origin gPackager )
				)
				( attribute "LOCATION" "C2L20"
					( Origin gFrontEnd )
				)
				( attribute "MATERIAL" "X7R"
					( Origin gFrontEnd )
				)
				( attribute "PACK_TYPE" "0402V"
					( Origin gFrontEnd )
				)
				( attribute "PART_NUMBER" "A36096-045"
					( Origin gFrontEnd )
				)
				( attribute "PHYS_PAGE" "173"
					( Origin gFrontEnd )
				)
				( attribute "ROOM" "ST_SATA"
					( Origin gFrontEnd )
				)
				( attribute "ROT" "0"
					( Origin gFrontEnd )
				)
				( attribute "SEC" "1"
					( Origin gFrontEnd )
				)
				( attribute "SEC_TYPE" "0402V"
					( Origin gFrontEnd )
				)
				( attribute "TOLERANCE" "10%"
					( Origin gFrontEnd )
				)
				( attribute "VALUE" "0.01UF"
					( Origin gFrontEnd )
				)
				( attribute "VER" "2"
					( Origin gFrontEnd )
				)
				( attribute "VOLTAGE" "25V"
					( Units "uVoltage" "V" 1.000000)
					( Origin gFrontEnd )
				)
				( attribute "XY" "(-4600,2900)"
					( Origin gFrontEnd )
				)
				( attribute "CHIPS_PART_NAME" "CAP_A"
					( Origin gPackager )
				)
				( attribute "CDS_PART_NAME" "CAP_A_0402V-0.01UF,25V,10%,X7RA"
					( Origin gPackager )
				)
				( objectStatus "C2L20" )
				( pin "a"
					( attribute "PN" "1"
						( Origin gPackager )
					)
					( objectStatus "C2L20.1" )
				)
				( pin "b"
					( attribute "PN" "2"
						( Origin gPackager )
					)
					( objectStatus "C2L20.2" )
				)
			)
			( gate "@baseboard_fab2_lib.baseboard_fab2(sch_1):page173_i196"
				( attribute "BOM_COST" "ST_SATA"
					( Origin gFrontEnd )
				)
				( attribute "CDS_LIB" "dev_discrete"
					( Origin gPackager )
				)
				( attribute "CDS_LOCATION" "C2L12"
					( Origin gPackager )
				)
				( attribute "CDS_SEC" "1"
					( Origin gPackager )
				)
				( attribute "LOCATION" "C2L12"
					( Origin gFrontEnd )
				)
				( attribute "MATERIAL" "X7R"
					( Origin gFrontEnd )
				)
				( attribute "PACK_TYPE" "0402V"
					( Origin gFrontEnd )
				)
				( attribute "PART_NUMBER" "A36096-045"
					( Origin gFrontEnd )
				)
				( attribute "PHYS_PAGE" "173"
					( Origin gFrontEnd )
				)
				( attribute "ROOM" "ST_SATA"
					( Origin gFrontEnd )
				)
				( attribute "ROT" "0"
					( Origin gFrontEnd )
				)
				( attribute "SEC" "1"
					( Origin gFrontEnd )
				)
				( attribute "SEC_TYPE" "0402V"
					( Origin gFrontEnd )
				)
				( attribute "TOLERANCE" "10%"
					( Origin gFrontEnd )
				)
				( attribute "VALUE" "0.01UF"
					( Origin gFrontEnd )
				)
				( attribute "VER" "2"
					( Origin gFrontEnd )
				)
				( attribute "VOLTAGE" "25V"
					( Units "uVoltage" "V" 1.000000)
					( Origin gFrontEnd )
				)
				( attribute "XY" "(-4575,2550)"
					( Origin gFrontEnd )
				)
				( attribute "CHIPS_PART_NAME" "CAP_A"
					( Origin gPackager )
				)
				( attribute "CDS_PART_NAME" "CAP_A_0402V-0.01UF,25V,10%,X7RA"
					( Origin gPackager )
				)
				( objectStatus "C2L12" )
				( pin "a"
					( attribute "PN" "1"
						( Origin gPackager )
					)
					( objectStatus "C2L12.1" )
				)
				( pin "b"
					( attribute "PN" "2"
						( Origin gPackager )
					)
					( objectStatus "C2L12.2" )
				)
			)
			( gate "@baseboard_fab2_lib.baseboard_fab2(sch_1):page173_i197"
				( attribute "BOM_COST" "ST_SATA"
					( Origin gFrontEnd )
				)
				( attribute "CDS_LIB" "dev_discrete"
					( Origin gPackager )
				)
				( attribute "CDS_LOCATION" "C2L18"
					( Origin gPackager )
				)
				( attribute "CDS_SEC" "1"
					( Origin gPackager )
				)
				( attribute "LOCATION" "C2L18"
					( Origin gFrontEnd )
				)
				( attribute "MATERIAL" "X7R"
					( Origin gFrontEnd )
				)
				( attribute "PACK_TYPE" "0402V"
					( Origin gFrontEnd )
				)
				( attribute "PART_NUMBER" "A36096-045"
					( Origin gFrontEnd )
				)
				( attribute "PHYS_PAGE" "173"
					( Origin gFrontEnd )
				)
				( attribute "ROOM" "ST_SATA"
					( Origin gFrontEnd )
				)
				( attribute "ROT" "0"
					( Origin gFrontEnd )
				)
				( attribute "SEC" "1"
					( Origin gFrontEnd )
				)
				( attribute "SEC_TYPE" "0402V"
					( Origin gFrontEnd )
				)
				( attribute "TOLERANCE" "10%"
					( Origin gFrontEnd )
				)
				( attribute "VALUE" "0.01UF"
					( Origin gFrontEnd )
				)
				( attribute "VER" "2"
					( Origin gFrontEnd )
				)
				( attribute "VOLTAGE" "25V"
					( Units "uVoltage" "V" 1.000000)
					( Origin gFrontEnd )
				)
				( attribute "XY" "(-4950,2750)"
					( Origin gFrontEnd )
				)
				( attribute "CHIPS_PART_NAME" "CAP_A"
					( Origin gPackager )
				)
				( attribute "CDS_PART_NAME" "CAP_A_0402V-0.01UF,25V,10%,X7RA"
					( Origin gPackager )
				)
				( objectStatus "C2L18" )
				( pin "a"
					( attribute "PN" "1"
						( Origin gPackager )
					)
					( objectStatus "C2L18.1" )
				)
				( pin "b"
					( attribute "PN" "2"
						( Origin gPackager )
					)
					( objectStatus "C2L18.2" )
				)
			)
			( gate "@baseboard_fab2_lib.baseboard_fab2(sch_1):page173_i205"
				( attribute "BOM_COST" "ST_SATA"
					( Origin gFrontEnd )
				)
				( attribute "CDS_LIB" "dev_discrete"
					( Origin gPackager )
				)
				( attribute "CDS_LOCATION" "C2L16"
					( Origin gPackager )
				)
				( attribute "CDS_SEC" "1"
					( Origin gPackager )
				)
				( attribute "LOCATION" "C2L16"
					( Origin gFrontEnd )
				)
				( attribute "MATERIAL" "X7R"
					( Origin gFrontEnd )
				)
				( attribute "PACK_TYPE" "0402V"
					( Origin gFrontEnd )
				)
				( attribute "PART_NUMBER" "A36096-045"
					( Origin gFrontEnd )
				)
				( attribute "PHYS_PAGE" "173"
					( Origin gFrontEnd )
				)
				( attribute "ROOM" "ST_SATA"
					( Origin gFrontEnd )
				)
				( attribute "ROT" "0"
					( Origin gFrontEnd )
				)
				( attribute "SEC" "1"
					( Origin gFrontEnd )
				)
				( attribute "SEC_TYPE" "0402V"
					( Origin gFrontEnd )
				)
				( attribute "TOLERANCE" "10%"
					( Origin gFrontEnd )
				)
				( attribute "VALUE" "0.01UF"
					( Origin gFrontEnd )
				)
				( attribute "VER" "2"
					( Origin gFrontEnd )
				)
				( attribute "VOLTAGE" "25V"
					( Units "uVoltage" "V" 1.000000)
					( Origin gFrontEnd )
				)
				( attribute "XY" "(-4575,2050)"
					( Origin gFrontEnd )
				)
				( attribute "CHIPS_PART_NAME" "CAP_A"
					( Origin gPackager )
				)
				( attribute "CDS_PART_NAME" "CAP_A_0402V-0.01UF,25V,10%,X7RA"
					( Origin gPackager )
				)
				( objectStatus "C2L16" )
				( pin "a"
					( attribute "PN" "1"
						( Origin gPackager )
					)
					( objectStatus "C2L16.1" )
				)
				( pin "b"
					( attribute "PN" "2"
						( Origin gPackager )
					)
					( objectStatus "C2L16.2" )
				)
			)
			( gate "@baseboard_fab2_lib.baseboard_fab2(sch_1):page173_i206"
				( attribute "BOM_COST" "ST_SATA"
					( Origin gFrontEnd )
				)
				( attribute "CDS_LIB" "dev_discrete"
					( Origin gPackager )
				)
				( attribute "CDS_LOCATION" "C2L7"
					( Origin gPackager )
				)
				( attribute "CDS_SEC" "1"
					( Origin gPackager )
				)
				( attribute "LOCATION" "C2L7"
					( Origin gFrontEnd )
				)
				( attribute "MATERIAL" "X7R"
					( Origin gFrontEnd )
				)
				( attribute "PACK_TYPE" "0402V"
					( Origin gFrontEnd )
				)
				( attribute "PART_NUMBER" "A36096-045"
					( Origin gFrontEnd )
				)
				( attribute "PHYS_PAGE" "173"
					( Origin gFrontEnd )
				)
				( attribute "ROOM" "ST_SATA"
					( Origin gFrontEnd )
				)
				( attribute "ROT" "0"
					( Origin gFrontEnd )
				)
				( attribute "SEC" "1"
					( Origin gFrontEnd )
				)
				( attribute "SEC_TYPE" "0402V"
					( Origin gFrontEnd )
				)
				( attribute "TOLERANCE" "10%"
					( Origin gFrontEnd )
				)
				( attribute "VALUE" "0.01UF"
					( Origin gFrontEnd )
				)
				( attribute "VER" "2"
					( Origin gFrontEnd )
				)
				( attribute "VOLTAGE" "25V"
					( Units "uVoltage" "V" 1.000000)
					( Origin gFrontEnd )
				)
				( attribute "XY" "(-4575,1700)"
					( Origin gFrontEnd )
				)
				( attribute "CHIPS_PART_NAME" "CAP_A"
					( Origin gPackager )
				)
				( attribute "CDS_PART_NAME" "CAP_A_0402V-0.01UF,25V,10%,X7RA"
					( Origin gPackager )
				)
				( objectStatus "C2L7" )
				( pin "a"
					( attribute "PN" "1"
						( Origin gPackager )
					)
					( objectStatus "C2L7.1" )
				)
				( pin "b"
					( attribute "PN" "2"
						( Origin gPackager )
					)
					( objectStatus "C2L7.2" )
				)
			)
			( gate "@baseboard_fab2_lib.baseboard_fab2(sch_1):page173_i207"
				( attribute "BOM_COST" "ST_SATA"
					( Origin gFrontEnd )
				)
				( attribute "CDS_LIB" "dev_discrete"
					( Origin gPackager )
				)
				( attribute "CDS_LOCATION" "C2L9"
					( Origin gPackager )
				)
				( attribute "CDS_SEC" "1"
					( Origin gPackager )
				)
				( attribute "LOCATION" "C2L9"
					( Origin gFrontEnd )
				)
				( attribute "MATERIAL" "X7R"
					( Origin gFrontEnd )
				)
				( attribute "PACK_TYPE" "0402V"
					( Origin gFrontEnd )
				)
				( attribute "PART_NUMBER" "A36096-045"
					( Origin gFrontEnd )
				)
				( attribute "PHYS_PAGE" "173"
					( Origin gFrontEnd )
				)
				( attribute "ROOM" "ST_SATA"
					( Origin gFrontEnd )
				)
				( attribute "ROT" "0"
					( Origin gFrontEnd )
				)
				( attribute "SEC" "1"
					( Origin gFrontEnd )
				)
				( attribute "SEC_TYPE" "0402V"
					( Origin gFrontEnd )
				)
				( attribute "TOLERANCE" "10%"
					( Origin gFrontEnd )
				)
				( attribute "VALUE" "0.01UF"
					( Origin gFrontEnd )
				)
				( attribute "VER" "2"
					( Origin gFrontEnd )
				)
				( attribute "VOLTAGE" "25V"
					( Units "uVoltage" "V" 1.000000)
					( Origin gFrontEnd )
				)
				( attribute "XY" "(-4950,2400)"
					( Origin gFrontEnd )
				)
				( attribute "CHIPS_PART_NAME" "CAP_A"
					( Origin gPackager )
				)
				( attribute "CDS_PART_NAME" "CAP_A_0402V-0.01UF,25V,10%,X7RA"
					( Origin gPackager )
				)
				( objectStatus "C2L9" )
				( pin "a"
					( attribute "PN" "1"
						( Origin gPackager )
					)
					( objectStatus "C2L9.1" )
				)
				( pin "b"
					( attribute "PN" "2"
						( Origin gPackager )
					)
					( objectStatus "C2L9.2" )
				)
			)
			( gate "@baseboard_fab2_lib.baseboard_fab2(sch_1):page173_i208"
				( attribute "BOM_COST" "ST_SATA"
					( Origin gFrontEnd )
				)
				( attribute "CDS_LIB" "dev_discrete"
					( Origin gPackager )
				)
				( attribute "CDS_LOCATION" "C2L14"
					( Origin gPackager )
				)
				( attribute "CDS_SEC" "1"
					( Origin gPackager )
				)
				( attribute "LOCATION" "C2L14"
					( Origin gFrontEnd )
				)
				( attribute "MATERIAL" "X7R"
					( Origin gFrontEnd )
				)
				( attribute "PACK_TYPE" "0402V"
					( Origin gFrontEnd )
				)
				( attribute "PART_NUMBER" "A36096-045"
					( Origin gFrontEnd )
				)
				( attribute "PHYS_PAGE" "173"
					( Origin gFrontEnd )
				)
				( attribute "ROOM" "ST_SATA"
					( Origin gFrontEnd )
				)
				( attribute "ROT" "0"
					( Origin gFrontEnd )
				)
				( attribute "SEC" "1"
					( Origin gFrontEnd )
				)
				( attribute "SEC_TYPE" "0402V"
					( Origin gFrontEnd )
				)
				( attribute "TOLERANCE" "10%"
					( Origin gFrontEnd )
				)
				( attribute "VALUE" "0.01UF"
					( Origin gFrontEnd )
				)
				( attribute "VER" "2"
					( Origin gFrontEnd )
				)
				( attribute "VOLTAGE" "25V"
					( Units "uVoltage" "V" 1.000000)
					( Origin gFrontEnd )
				)
				( attribute "XY" "(-4975,1850)"
					( Origin gFrontEnd )
				)
				( attribute "CHIPS_PART_NAME" "CAP_A"
					( Origin gPackager )
				)
				( attribute "CDS_PART_NAME" "CAP_A_0402V-0.01UF,25V,10%,X7RA"
					( Origin gPackager )
				)
				( objectStatus "C2L14" )
				( pin "a"
					( attribute "PN" "1"
						( Origin gPackager )
					)
					( objectStatus "C2L14.1" )
				)
				( pin "b"
					( attribute "PN" "2"
						( Origin gPackager )
					)
					( objectStatus "C2L14.2" )
				)
			)
			( gate "@baseboard_fab2_lib.baseboard_fab2(sch_1):page173_i209"
				( attribute "BOM_COST" "ST_SATA"
					( Origin gFrontEnd )
				)
				( attribute "CDS_LIB" "dev_discrete"
					( Origin gPackager )
				)
				( attribute "CDS_LOCATION" "C2L5"
					( Origin gPackager )
				)
				( attribute "CDS_SEC" "1"
					( Origin gPackager )
				)
				( attribute "LOCATION" "C2L5"
					( Origin gFrontEnd )
				)
				( attribute "MATERIAL" "X7R"
					( Origin gFrontEnd )
				)
				( attribute "PACK_TYPE" "0402V"
					( Origin gFrontEnd )
				)
				( attribute "PART_NUMBER" "A36096-045"
					( Origin gFrontEnd )
				)
				( attribute "PHYS_PAGE" "173"
					( Origin gFrontEnd )
				)
				( attribute "ROOM" "ST_SATA"
					( Origin gFrontEnd )
				)
				( attribute "ROT" "0"
					( Origin gFrontEnd )
				)
				( attribute "SEC" "1"
					( Origin gFrontEnd )
				)
				( attribute "SEC_TYPE" "0402V"
					( Origin gFrontEnd )
				)
				( attribute "TOLERANCE" "10%"
					( Origin gFrontEnd )
				)
				( attribute "VALUE" "0.01UF"
					( Origin gFrontEnd )
				)
				( attribute "VER" "2"
					( Origin gFrontEnd )
				)
				( attribute "VOLTAGE" "25V"
					( Units "uVoltage" "V" 1.000000)
					( Origin gFrontEnd )
				)
				( attribute "XY" "(-4975,1500)"
					( Origin gFrontEnd )
				)
				( attribute "CHIPS_PART_NAME" "CAP_A"
					( Origin gPackager )
				)
				( attribute "CDS_PART_NAME" "CAP_A_0402V-0.01UF,25V,10%,X7RA"
					( Origin gPackager )
				)
				( objectStatus "C2L5" )
				( pin "a"
					( attribute "PN" "1"
						( Origin gPackager )
					)
					( objectStatus "C2L5.1" )
				)
				( pin "b"
					( attribute "PN" "2"
						( Origin gPackager )
					)
					( objectStatus "C2L5.2" )
				)
			)
			( gate "@baseboard_fab2_lib.baseboard_fab2(sch_1):page173_i220"
				( attribute "BOM_COST" "ST_SATA"
					( Origin gFrontEnd )
				)
				( attribute "CDS_LIB" "dev_discrete"
					( Origin gPackager )
				)
				( attribute "CDS_LOCATION" "C2L40"
					( Origin gPackager )
				)
				( attribute "CDS_SEC" "1"
					( Origin gPackager )
				)
				( attribute "LOCATION" "C2L40"
					( Origin gFrontEnd )
				)
				( attribute "MATERIAL" "X7R"
					( Origin gFrontEnd )
				)
				( attribute "PACK_TYPE" "0402V"
					( Origin gFrontEnd )
				)
				( attribute "PART_NUMBER" "A36096-045"
					( Origin gFrontEnd )
				)
				( attribute "PHYS_PAGE" "173"
					( Origin gFrontEnd )
				)
				( attribute "ROOM" "ST_SATA"
					( Origin gFrontEnd )
				)
				( attribute "ROT" "0"
					( Origin gFrontEnd )
				)
				( attribute "SEC" "1"
					( Origin gFrontEnd )
				)
				( attribute "SEC_TYPE" "0402V"
					( Origin gFrontEnd )
				)
				( attribute "TOLERANCE" "10%"
					( Origin gFrontEnd )
				)
				( attribute "VALUE" "0.01UF"
					( Origin gFrontEnd )
				)
				( attribute "VER" "2"
					( Origin gFrontEnd )
				)
				( attribute "VOLTAGE" "25V"
					( Units "uVoltage" "V" 1.000000)
					( Origin gFrontEnd )
				)
				( attribute "XY" "(1025,4525)"
					( Origin gFrontEnd )
				)
				( attribute "CHIPS_PART_NAME" "CAP_A"
					( Origin gPackager )
				)
				( attribute "CDS_PART_NAME" "CAP_A_0402V-0.01UF,25V,10%,X7RA"
					( Origin gPackager )
				)
				( objectStatus "C2L40" )
				( pin "a"
					( attribute "PN" "1"
						( Origin gPackager )
					)
					( objectStatus "C2L40.1" )
				)
				( pin "b"
					( attribute "PN" "2"
						( Origin gPackager )
					)
					( objectStatus "C2L40.2" )
				)
			)
			( gate "@baseboard_fab2_lib.baseboard_fab2(sch_1):page173_i221"
				( attribute "BOM_COST" "ST_SATA"
					( Origin gFrontEnd )
				)
				( attribute "CDS_LIB" "dev_discrete"
					( Origin gPackager )
				)
				( attribute "CDS_LOCATION" "C2L39"
					( Origin gPackager )
				)
				( attribute "CDS_SEC" "1"
					( Origin gPackager )
				)
				( attribute "LOCATION" "C2L39"
					( Origin gFrontEnd )
				)
				( attribute "MATERIAL" "X7R"
					( Origin gFrontEnd )
				)
				( attribute "PACK_TYPE" "0402V"
					( Origin gFrontEnd )
				)
				( attribute "PART_NUMBER" "A36096-045"
					( Origin gFrontEnd )
				)
				( attribute "PHYS_PAGE" "173"
					( Origin gFrontEnd )
				)
				( attribute "ROOM" "ST_SATA"
					( Origin gFrontEnd )
				)
				( attribute "ROT" "0"
					( Origin gFrontEnd )
				)
				( attribute "SEC" "1"
					( Origin gFrontEnd )
				)
				( attribute "SEC_TYPE" "0402V"
					( Origin gFrontEnd )
				)
				( attribute "TOLERANCE" "10%"
					( Origin gFrontEnd )
				)
				( attribute "VALUE" "0.01UF"
					( Origin gFrontEnd )
				)
				( attribute "VER" "2"
					( Origin gFrontEnd )
				)
				( attribute "VOLTAGE" "25V"
					( Units "uVoltage" "V" 1.000000)
					( Origin gFrontEnd )
				)
				( attribute "XY" "(650,4675)"
					( Origin gFrontEnd )
				)
				( attribute "CHIPS_PART_NAME" "CAP_A"
					( Origin gPackager )
				)
				( attribute "CDS_PART_NAME" "CAP_A_0402V-0.01UF,25V,10%,X7RA"
					( Origin gPackager )
				)
				( objectStatus "C2L39" )
				( pin "a"
					( attribute "PN" "1"
						( Origin gPackager )
					)
					( objectStatus "C2L39.1" )
				)
				( pin "b"
					( attribute "PN" "2"
						( Origin gPackager )
					)
					( objectStatus "C2L39.2" )
				)
			)
			( gate "@baseboard_fab2_lib.baseboard_fab2(sch_1):page173_i222"
				( attribute "BOM_COST" "ST_SATA"
					( Origin gFrontEnd )
				)
				( attribute "CDS_LIB" "dev_discrete"
					( Origin gPackager )
				)
				( attribute "CDS_LOCATION" "C2L43"
					( Origin gPackager )
				)
				( attribute "CDS_SEC" "1"
					( Origin gPackager )
				)
				( attribute "LOCATION" "C2L43"
					( Origin gFrontEnd )
				)
				( attribute "MATERIAL" "X7R"
					( Origin gFrontEnd )
				)
				( attribute "PACK_TYPE" "0402V"
					( Origin gFrontEnd )
				)
				( attribute "PART_NUMBER" "A36096-045"
					( Origin gFrontEnd )
				)
				( attribute "PHYS_PAGE" "173"
					( Origin gFrontEnd )
				)
				( attribute "ROOM" "ST_SATA"
					( Origin gFrontEnd )
				)
				( attribute "ROT" "0"
					( Origin gFrontEnd )
				)
				( attribute "SEC" "1"
					( Origin gFrontEnd )
				)
				( attribute "SEC_TYPE" "0402V"
					( Origin gFrontEnd )
				)
				( attribute "TOLERANCE" "10%"
					( Origin gFrontEnd )
				)
				( attribute "VALUE" "0.01UF"
					( Origin gFrontEnd )
				)
				( attribute "VER" "2"
					( Origin gFrontEnd )
				)
				( attribute "VOLTAGE" "25V"
					( Units "uVoltage" "V" 1.000000)
					( Origin gFrontEnd )
				)
				( attribute "XY" "(650,4325)"
					( Origin gFrontEnd )
				)
				( attribute "CHIPS_PART_NAME" "CAP_A"
					( Origin gPackager )
				)
				( attribute "CDS_PART_NAME" "CAP_A_0402V-0.01UF,25V,10%,X7RA"
					( Origin gPackager )
				)
				( objectStatus "C2L43" )
				( pin "a"
					( attribute "PN" "1"
						( Origin gPackager )
					)
					( objectStatus "C2L43.1" )
				)
				( pin "b"
					( attribute "PN" "2"
						( Origin gPackager )
					)
					( objectStatus "C2L43.2" )
				)
			)
			( gate "@baseboard_fab2_lib.baseboard_fab2(sch_1):page173_i228"
				( attribute "BOM_COST" "ST_SATA"
					( Origin gFrontEnd )
				)
				( attribute "CDS_LIB" "dev_discrete"
					( Origin gPackager )
				)
				( attribute "CDS_LOCATION" "C2L44"
					( Origin gPackager )
				)
				( attribute "CDS_SEC" "1"
					( Origin gPackager )
				)
				( attribute "LOCATION" "C2L44"
					( Origin gFrontEnd )
				)
				( attribute "MATERIAL" "X7R"
					( Origin gFrontEnd )
				)
				( attribute "PACK_TYPE" "0402V"
					( Origin gFrontEnd )
				)
				( attribute "PART_NUMBER" "A36096-045"
					( Origin gFrontEnd )
				)
				( attribute "PHYS_PAGE" "173"
					( Origin gFrontEnd )
				)
				( attribute "ROOM" "ST_SATA"
					( Origin gFrontEnd )
				)
				( attribute "ROT" "0"
					( Origin gFrontEnd )
				)
				( attribute "SEC" "1"
					( Origin gFrontEnd )
				)
				( attribute "SEC_TYPE" "0402V"
					( Origin gFrontEnd )
				)
				( attribute "TOLERANCE" "10%"
					( Origin gFrontEnd )
				)
				( attribute "VALUE" "0.01UF"
					( Origin gFrontEnd )
				)
				( attribute "VER" "2"
					( Origin gFrontEnd )
				)
				( attribute "VOLTAGE" "25V"
					( Units "uVoltage" "V" 1.000000)
					( Origin gFrontEnd )
				)
				( attribute "XY" "(1025,4175)"
					( Origin gFrontEnd )
				)
				( attribute "CHIPS_PART_NAME" "CAP_A"
					( Origin gPackager )
				)
				( attribute "CDS_PART_NAME" "CAP_A_0402V-0.01UF,25V,10%,X7RA"
					( Origin gPackager )
				)
				( objectStatus "C2L44" )
				( pin "a"
					( attribute "PN" "1"
						( Origin gPackager )
					)
					( objectStatus "C2L44.1" )
				)
				( pin "b"
					( attribute "PN" "2"
						( Origin gPackager )
					)
					( objectStatus "C2L44.2" )
				)
			)
			( gate "@baseboard_fab2_lib.baseboard_fab2(sch_1):page173_i233"
				( attribute "BOM_COST" "ST_SATA"
					( Origin gFrontEnd )
				)
				( attribute "CDS_LIB" "dev_discrete"
					( Origin gPackager )
				)
				( attribute "CDS_LOCATION" "C2L42"
					( Origin gPackager )
				)
				( attribute "CDS_SEC" "1"
					( Origin gPackager )
				)
				( attribute "LOCATION" "C2L42"
					( Origin gFrontEnd )
				)
				( attribute "MATERIAL" "X7R"
					( Origin gFrontEnd )
				)
				( attribute "PACK_TYPE" "0402V"
					( Origin gFrontEnd )
				)
				( attribute "PART_NUMBER" "A36096-045"
					( Origin gFrontEnd )
				)
				( attribute "PHYS_PAGE" "173"
					( Origin gFrontEnd )
				)
				( attribute "ROOM" "ST_SATA"
					( Origin gFrontEnd )
				)
				( attribute "ROT" "0"
					( Origin gFrontEnd )
				)
				( attribute "SEC" "1"
					( Origin gFrontEnd )
				)
				( attribute "SEC_TYPE" "0402V"
					( Origin gFrontEnd )
				)
				( attribute "TOLERANCE" "10%"
					( Origin gFrontEnd )
				)
				( attribute "VALUE" "0.01UF"
					( Origin gFrontEnd )
				)
				( attribute "VER" "2"
					( Origin gFrontEnd )
				)
				( attribute "VOLTAGE" "25V"
					( Units "uVoltage" "V" 1.000000)
					( Origin gFrontEnd )
				)
				( attribute "XY" "(1000,3500)"
					( Origin gFrontEnd )
				)
				( attribute "CHIPS_PART_NAME" "CAP_A"
					( Origin gPackager )
				)
				( attribute "CDS_PART_NAME" "CAP_A_0402V-0.01UF,25V,10%,X7RA"
					( Origin gPackager )
				)
				( objectStatus "C2L42" )
				( pin "a"
					( attribute "PN" "1"
						( Origin gPackager )
					)
					( objectStatus "C2L42.1" )
				)
				( pin "b"
					( attribute "PN" "2"
						( Origin gPackager )
					)
					( objectStatus "C2L42.2" )
				)
			)
			( gate "@baseboard_fab2_lib.baseboard_fab2(sch_1):page173_i234"
				( attribute "BOM_COST" "ST_SATA"
					( Origin gFrontEnd )
				)
				( attribute "CDS_LIB" "dev_discrete"
					( Origin gPackager )
				)
				( attribute "CDS_LOCATION" "C2L22"
					( Origin gPackager )
				)
				( attribute "CDS_SEC" "1"
					( Origin gPackager )
				)
				( attribute "LOCATION" "C2L22"
					( Origin gFrontEnd )
				)
				( attribute "MATERIAL" "X7R"
					( Origin gFrontEnd )
				)
				( attribute "PACK_TYPE" "0402V"
					( Origin gFrontEnd )
				)
				( attribute "PART_NUMBER" "A36096-045"
					( Origin gFrontEnd )
				)
				( attribute "PHYS_PAGE" "173"
					( Origin gFrontEnd )
				)
				( attribute "ROOM" "ST_SATA"
					( Origin gFrontEnd )
				)
				( attribute "ROT" "0"
					( Origin gFrontEnd )
				)
				( attribute "SEC" "1"
					( Origin gFrontEnd )
				)
				( attribute "SEC_TYPE" "0402V"
					( Origin gFrontEnd )
				)
				( attribute "TOLERANCE" "10%"
					( Origin gFrontEnd )
				)
				( attribute "VALUE" "0.01UF"
					( Origin gFrontEnd )
				)
				( attribute "VER" "2"
					( Origin gFrontEnd )
				)
				( attribute "VOLTAGE" "25V"
					( Units "uVoltage" "V" 1.000000)
					( Origin gFrontEnd )
				)
				( attribute "XY" "(1025,3075)"
					( Origin gFrontEnd )
				)
				( attribute "CHIPS_PART_NAME" "CAP_A"
					( Origin gPackager )
				)
				( attribute "CDS_PART_NAME" "CAP_A_0402V-0.01UF,25V,10%,X7RA"
					( Origin gPackager )
				)
				( objectStatus "C2L22" )
				( pin "a"
					( attribute "PN" "1"
						( Origin gPackager )
					)
					( objectStatus "C2L22.1" )
				)
				( pin "b"
					( attribute "PN" "2"
						( Origin gPackager )
					)
					( objectStatus "C2L22.2" )
				)
			)
			( gate "@baseboard_fab2_lib.baseboard_fab2(sch_1):page173_i238"
				( attribute "BOM_COST" "ST_SATA"
					( Origin gFrontEnd )
				)
				( attribute "CDS_LIB" "dev_discrete"
					( Origin gPackager )
				)
				( attribute "CDS_LOCATION" "C2L37"
					( Origin gPackager )
				)
				( attribute "CDS_SEC" "1"
					( Origin gPackager )
				)
				( attribute "LOCATION" "C2L37"
					( Origin gFrontEnd )
				)
				( attribute "MATERIAL" "X7R"
					( Origin gFrontEnd )
				)
				( attribute "PACK_TYPE" "0402V"
					( Origin gFrontEnd )
				)
				( attribute "PART_NUMBER" "A36096-045"
					( Origin gFrontEnd )
				)
				( attribute "PHYS_PAGE" "173"
					( Origin gFrontEnd )
				)
				( attribute "ROOM" "ST_SATA"
					( Origin gFrontEnd )
				)
				( attribute "ROT" "0"
					( Origin gFrontEnd )
				)
				( attribute "SEC" "1"
					( Origin gFrontEnd )
				)
				( attribute "SEC_TYPE" "0402V"
					( Origin gFrontEnd )
				)
				( attribute "TOLERANCE" "10%"
					( Origin gFrontEnd )
				)
				( attribute "VALUE" "0.01UF"
					( Origin gFrontEnd )
				)
				( attribute "VER" "2"
					( Origin gFrontEnd )
				)
				( attribute "VOLTAGE" "25V"
					( Units "uVoltage" "V" 1.000000)
					( Origin gFrontEnd )
				)
				( attribute "XY" "(1025,2725)"
					( Origin gFrontEnd )
				)
				( attribute "CHIPS_PART_NAME" "CAP_A"
					( Origin gPackager )
				)
				( attribute "CDS_PART_NAME" "CAP_A_0402V-0.01UF,25V,10%,X7RA"
					( Origin gPackager )
				)
				( objectStatus "C2L37" )
				( pin "a"
					( attribute "PN" "1"
						( Origin gPackager )
					)
					( objectStatus "C2L37.1" )
				)
				( pin "b"
					( attribute "PN" "2"
						( Origin gPackager )
					)
					( objectStatus "C2L37.2" )
				)
			)
			( gate "@baseboard_fab2_lib.baseboard_fab2(sch_1):page173_i239"
				( attribute "BOM_COST" "ST_SATA"
					( Origin gFrontEnd )
				)
				( attribute "CDS_LIB" "dev_discrete"
					( Origin gPackager )
				)
				( attribute "CDS_LOCATION" "C2L47"
					( Origin gPackager )
				)
				( attribute "CDS_SEC" "1"
					( Origin gPackager )
				)
				( attribute "LOCATION" "C2L47"
					( Origin gFrontEnd )
				)
				( attribute "MATERIAL" "X7R"
					( Origin gFrontEnd )
				)
				( attribute "PACK_TYPE" "0402V"
					( Origin gFrontEnd )
				)
				( attribute "PART_NUMBER" "A36096-045"
					( Origin gFrontEnd )
				)
				( attribute "PHYS_PAGE" "173"
					( Origin gFrontEnd )
				)
				( attribute "ROOM" "ST_SATA"
					( Origin gFrontEnd )
				)
				( attribute "ROT" "0"
					( Origin gFrontEnd )
				)
				( attribute "SEC" "1"
					( Origin gFrontEnd )
				)
				( attribute "SEC_TYPE" "0402V"
					( Origin gFrontEnd )
				)
				( attribute "TOLERANCE" "10%"
					( Origin gFrontEnd )
				)
				( attribute "VALUE" "0.01UF"
					( Origin gFrontEnd )
				)
				( attribute "VER" "2"
					( Origin gFrontEnd )
				)
				( attribute "VOLTAGE" "25V"
					( Units "uVoltage" "V" 1.000000)
					( Origin gFrontEnd )
				)
				( attribute "XY" "(650,2925)"
					( Origin gFrontEnd )
				)
				( attribute "CHIPS_PART_NAME" "CAP_A"
					( Origin gPackager )
				)
				( attribute "CDS_PART_NAME" "CAP_A_0402V-0.01UF,25V,10%,X7RA"
					( Origin gPackager )
				)
				( objectStatus "C2L47" )
				( pin "a"
					( attribute "PN" "1"
						( Origin gPackager )
					)
					( objectStatus "C2L47.1" )
				)
				( pin "b"
					( attribute "PN" "2"
						( Origin gPackager )
					)
					( objectStatus "C2L47.2" )
				)
			)
			( gate "@baseboard_fab2_lib.baseboard_fab2(sch_1):page173_i240"
				( attribute "BOM_COST" "ST_SATA"
					( Origin gFrontEnd )
				)
				( attribute "CDS_LIB" "dev_discrete"
					( Origin gPackager )
				)
				( attribute "CDS_LOCATION" "C2L27"
					( Origin gPackager )
				)
				( attribute "CDS_SEC" "1"
					( Origin gPackager )
				)
				( attribute "LOCATION" "C2L27"
					( Origin gFrontEnd )
				)
				( attribute "MATERIAL" "X7R"
					( Origin gFrontEnd )
				)
				( attribute "PACK_TYPE" "0402V"
					( Origin gFrontEnd )
				)
				( attribute "PART_NUMBER" "A36096-045"
					( Origin gFrontEnd )
				)
				( attribute "PHYS_PAGE" "173"
					( Origin gFrontEnd )
				)
				( attribute "ROOM" "ST_SATA"
					( Origin gFrontEnd )
				)
				( attribute "ROT" "0"
					( Origin gFrontEnd )
				)
				( attribute "SEC" "1"
					( Origin gFrontEnd )
				)
				( attribute "SEC_TYPE" "0402V"
					( Origin gFrontEnd )
				)
				( attribute "TOLERANCE" "10%"
					( Origin gFrontEnd )
				)
				( attribute "VALUE" "0.01UF"
					( Origin gFrontEnd )
				)
				( attribute "VER" "2"
					( Origin gFrontEnd )
				)
				( attribute "VOLTAGE" "25V"
					( Units "uVoltage" "V" 1.000000)
					( Origin gFrontEnd )
				)
				( attribute "XY" "(650,2500)"
					( Origin gFrontEnd )
				)
				( attribute "CHIPS_PART_NAME" "CAP_A"
					( Origin gPackager )
				)
				( attribute "CDS_PART_NAME" "CAP_A_0402V-0.01UF,25V,10%,X7RA"
					( Origin gPackager )
				)
				( objectStatus "C2L27" )
				( pin "a"
					( attribute "PN" "1"
						( Origin gPackager )
					)
					( objectStatus "C2L27.1" )
				)
				( pin "b"
					( attribute "PN" "2"
						( Origin gPackager )
					)
					( objectStatus "C2L27.2" )
				)
			)
			( gate "@baseboard_fab2_lib.baseboard_fab2(sch_1):page173_i241"
				( attribute "BOM_COST" "ST_SATA"
					( Origin gFrontEnd )
				)
				( attribute "CDS_LIB" "dev_discrete"
					( Origin gPackager )
				)
				( attribute "CDS_LOCATION" "C2L23"
					( Origin gPackager )
				)
				( attribute "CDS_SEC" "1"
					( Origin gPackager )
				)
				( attribute "LOCATION" "C2L23"
					( Origin gFrontEnd )
				)
				( attribute "MATERIAL" "X7R"
					( Origin gFrontEnd )
				)
				( attribute "PACK_TYPE" "0402V"
					( Origin gFrontEnd )
				)
				( attribute "PART_NUMBER" "A36096-045"
					( Origin gFrontEnd )
				)
				( attribute "PHYS_PAGE" "173"
					( Origin gFrontEnd )
				)
				( attribute "ROOM" "ST_SATA"
					( Origin gFrontEnd )
				)
				( attribute "ROT" "0"
					( Origin gFrontEnd )
				)
				( attribute "SEC" "1"
					( Origin gFrontEnd )
				)
				( attribute "SEC_TYPE" "0402V"
					( Origin gFrontEnd )
				)
				( attribute "TOLERANCE" "10%"
					( Origin gFrontEnd )
				)
				( attribute "VALUE" "0.01UF"
					( Origin gFrontEnd )
				)
				( attribute "VER" "2"
					( Origin gFrontEnd )
				)
				( attribute "VOLTAGE" "25V"
					( Units "uVoltage" "V" 1.000000)
					( Origin gFrontEnd )
				)
				( attribute "XY" "(625,3300)"
					( Origin gFrontEnd )
				)
				( attribute "CHIPS_PART_NAME" "CAP_A"
					( Origin gPackager )
				)
				( attribute "CDS_PART_NAME" "CAP_A_0402V-0.01UF,25V,10%,X7RA"
					( Origin gPackager )
				)
				( objectStatus "C2L23" )
				( pin "a"
					( attribute "PN" "1"
						( Origin gPackager )
					)
					( objectStatus "C2L23.1" )
				)
				( pin "b"
					( attribute "PN" "2"
						( Origin gPackager )
					)
					( objectStatus "C2L23.2" )
				)
			)
			( gate "@baseboard_fab2_lib.baseboard_fab2(sch_1):page173_i242"
				( attribute "BOM_COST" "ST_SATA"
					( Origin gFrontEnd )
				)
				( attribute "CDS_LIB" "dev_discrete"
					( Origin gPackager )
				)
				( attribute "CDS_LOCATION" "C2L41"
					( Origin gPackager )
				)
				( attribute "CDS_SEC" "1"
					( Origin gPackager )
				)
				( attribute "LOCATION" "C2L41"
					( Origin gFrontEnd )
				)
				( attribute "MATERIAL" "X7R"
					( Origin gFrontEnd )
				)
				( attribute "PACK_TYPE" "0402V"
					( Origin gFrontEnd )
				)
				( attribute "PART_NUMBER" "A36096-045"
					( Origin gFrontEnd )
				)
				( attribute "PHYS_PAGE" "173"
					( Origin gFrontEnd )
				)
				( attribute "ROOM" "ST_SATA"
					( Origin gFrontEnd )
				)
				( attribute "ROT" "0"
					( Origin gFrontEnd )
				)
				( attribute "SEC" "1"
					( Origin gFrontEnd )
				)
				( attribute "SEC_TYPE" "0402V"
					( Origin gFrontEnd )
				)
				( attribute "TOLERANCE" "10%"
					( Origin gFrontEnd )
				)
				( attribute "VALUE" "0.01UF"
					( Origin gFrontEnd )
				)
				( attribute "VER" "2"
					( Origin gFrontEnd )
				)
				( attribute "VOLTAGE" "25V"
					( Units "uVoltage" "V" 1.000000)
					( Origin gFrontEnd )
				)
				( attribute "XY" "(625,3650)"
					( Origin gFrontEnd )
				)
				( attribute "CHIPS_PART_NAME" "CAP_A"
					( Origin gPackager )
				)
				( attribute "CDS_PART_NAME" "CAP_A_0402V-0.01UF,25V,10%,X7RA"
					( Origin gPackager )
				)
				( objectStatus "C2L41" )
				( pin "a"
					( attribute "PN" "1"
						( Origin gPackager )
					)
					( objectStatus "C2L41.1" )
				)
				( pin "b"
					( attribute "PN" "2"
						( Origin gPackager )
					)
					( objectStatus "C2L41.2" )
				)
			)
			( gate "@baseboard_fab2_lib.baseboard_fab2(sch_1):page173_i255"
				( attribute "BOM_COST" "ST_SATA"
					( Origin gFrontEnd )
				)
				( attribute "CDS_LIB" "dev_discrete"
					( Origin gPackager )
				)
				( attribute "CDS_LOCATION" "C2L26"
					( Origin gPackager )
				)
				( attribute "CDS_SEC" "1"
					( Origin gPackager )
				)
				( attribute "LOCATION" "C2L26"
					( Origin gFrontEnd )
				)
				( attribute "MATERIAL" "X7R"
					( Origin gFrontEnd )
				)
				( attribute "PACK_TYPE" "0402V"
					( Origin gFrontEnd )
				)
				( attribute "PART_NUMBER" "A36096-045"
					( Origin gFrontEnd )
				)
				( attribute "PHYS_PAGE" "173"
					( Origin gFrontEnd )
				)
				( attribute "ROOM" "ST_SATA"
					( Origin gFrontEnd )
				)
				( attribute "ROT" "0"
					( Origin gFrontEnd )
				)
				( attribute "SEC" "1"
					( Origin gFrontEnd )
				)
				( attribute "SEC_TYPE" "0402V"
					( Origin gFrontEnd )
				)
				( attribute "TOLERANCE" "10%"
					( Origin gFrontEnd )
				)
				( attribute "VALUE" "0.01UF"
					( Origin gFrontEnd )
				)
				( attribute "VER" "2"
					( Origin gFrontEnd )
				)
				( attribute "VOLTAGE" "25V"
					( Units "uVoltage" "V" 1.000000)
					( Origin gFrontEnd )
				)
				( attribute "XY" "(1025,2350)"
					( Origin gFrontEnd )
				)
				( attribute "CHIPS_PART_NAME" "CAP_A"
					( Origin gPackager )
				)
				( attribute "CDS_PART_NAME" "CAP_A_0402V-0.01UF,25V,10%,X7RA"
					( Origin gPackager )
				)
				( objectStatus "C2L26" )
				( pin "a"
					( attribute "PN" "1"
						( Origin gPackager )
					)
					( objectStatus "C2L26.1" )
				)
				( pin "b"
					( attribute "PN" "2"
						( Origin gPackager )
					)
					( objectStatus "C2L26.2" )
				)
			)
			( gate "@baseboard_fab2_lib.baseboard_fab2(sch_1):page173_i256"
				( attribute "BOM_COST" "ST_SATA"
					( Origin gFrontEnd )
				)
				( attribute "CDS_LIB" "dev_discrete"
					( Origin gPackager )
				)
				( attribute "CDS_LOCATION" "C2L38"
					( Origin gPackager )
				)
				( attribute "CDS_SEC" "1"
					( Origin gPackager )
				)
				( attribute "LOCATION" "C2L38"
					( Origin gFrontEnd )
				)
				( attribute "MATERIAL" "X7R"
					( Origin gFrontEnd )
				)
				( attribute "PACK_TYPE" "0402V"
					( Origin gFrontEnd )
				)
				( attribute "PART_NUMBER" "A36096-045"
					( Origin gFrontEnd )
				)
				( attribute "PHYS_PAGE" "173"
					( Origin gFrontEnd )
				)
				( attribute "ROOM" "ST_SATA"
					( Origin gFrontEnd )
				)
				( attribute "ROT" "0"
					( Origin gFrontEnd )
				)
				( attribute "SEC" "1"
					( Origin gFrontEnd )
				)
				( attribute "SEC_TYPE" "0402V"
					( Origin gFrontEnd )
				)
				( attribute "TOLERANCE" "10%"
					( Origin gFrontEnd )
				)
				( attribute "VALUE" "0.01UF"
					( Origin gFrontEnd )
				)
				( attribute "VER" "2"
					( Origin gFrontEnd )
				)
				( attribute "VOLTAGE" "25V"
					( Units "uVoltage" "V" 1.000000)
					( Origin gFrontEnd )
				)
				( attribute "XY" "(1050,1900)"
					( Origin gFrontEnd )
				)
				( attribute "CHIPS_PART_NAME" "CAP_A"
					( Origin gPackager )
				)
				( attribute "CDS_PART_NAME" "CAP_A_0402V-0.01UF,25V,10%,X7RA"
					( Origin gPackager )
				)
				( objectStatus "C2L38" )
				( pin "a"
					( attribute "PN" "1"
						( Origin gPackager )
					)
					( objectStatus "C2L38.1" )
				)
				( pin "b"
					( attribute "PN" "2"
						( Origin gPackager )
					)
					( objectStatus "C2L38.2" )
				)
			)
			( gate "@baseboard_fab2_lib.baseboard_fab2(sch_1):page173_i257"
				( attribute "BOM_COST" "ST_SATA"
					( Origin gFrontEnd )
				)
				( attribute "CDS_LIB" "dev_discrete"
					( Origin gPackager )
				)
				( attribute "CDS_LOCATION" "C2L48"
					( Origin gPackager )
				)
				( attribute "CDS_SEC" "1"
					( Origin gPackager )
				)
				( attribute "LOCATION" "C2L48"
					( Origin gFrontEnd )
				)
				( attribute "MATERIAL" "X7R"
					( Origin gFrontEnd )
				)
				( attribute "PACK_TYPE" "0402V"
					( Origin gFrontEnd )
				)
				( attribute "PART_NUMBER" "A36096-045"
					( Origin gFrontEnd )
				)
				( attribute "PHYS_PAGE" "173"
					( Origin gFrontEnd )
				)
				( attribute "ROOM" "ST_SATA"
					( Origin gFrontEnd )
				)
				( attribute "ROT" "0"
					( Origin gFrontEnd )
				)
				( attribute "SEC" "1"
					( Origin gFrontEnd )
				)
				( attribute "SEC_TYPE" "0402V"
					( Origin gFrontEnd )
				)
				( attribute "TOLERANCE" "10%"
					( Origin gFrontEnd )
				)
				( attribute "VALUE" "0.01UF"
					( Origin gFrontEnd )
				)
				( attribute "VER" "2"
					( Origin gFrontEnd )
				)
				( attribute "VOLTAGE" "25V"
					( Units "uVoltage" "V" 1.000000)
					( Origin gFrontEnd )
				)
				( attribute "XY" "(650,2050)"
					( Origin gFrontEnd )
				)
				( attribute "CHIPS_PART_NAME" "CAP_A"
					( Origin gPackager )
				)
				( attribute "CDS_PART_NAME" "CAP_A_0402V-0.01UF,25V,10%,X7RA"
					( Origin gPackager )
				)
				( objectStatus "C2L48" )
				( pin "a"
					( attribute "PN" "1"
						( Origin gPackager )
					)
					( objectStatus "C2L48.1" )
				)
				( pin "b"
					( attribute "PN" "2"
						( Origin gPackager )
					)
					( objectStatus "C2L48.2" )
				)
			)
			( gate "@baseboard_fab2_lib.baseboard_fab2(sch_1):page173_i258"
				( attribute "BOM_COST" "ST_SATA"
					( Origin gFrontEnd )
				)
				( attribute "CDS_LIB" "dev_discrete"
					( Origin gPackager )
				)
				( attribute "CDS_LOCATION" "C2L24"
					( Origin gPackager )
				)
				( attribute "CDS_SEC" "1"
					( Origin gPackager )
				)
				( attribute "LOCATION" "C2L24"
					( Origin gFrontEnd )
				)
				( attribute "MATERIAL" "X7R"
					( Origin gFrontEnd )
				)
				( attribute "PACK_TYPE" "0402V"
					( Origin gFrontEnd )
				)
				( attribute "PART_NUMBER" "A36096-045"
					( Origin gFrontEnd )
				)
				( attribute "PHYS_PAGE" "173"
					( Origin gFrontEnd )
				)
				( attribute "ROOM" "ST_SATA"
					( Origin gFrontEnd )
				)
				( attribute "ROT" "0"
					( Origin gFrontEnd )
				)
				( attribute "SEC" "1"
					( Origin gFrontEnd )
				)
				( attribute "SEC_TYPE" "0402V"
					( Origin gFrontEnd )
				)
				( attribute "TOLERANCE" "10%"
					( Origin gFrontEnd )
				)
				( attribute "VALUE" "0.01UF"
					( Origin gFrontEnd )
				)
				( attribute "VER" "2"
					( Origin gFrontEnd )
				)
				( attribute "VOLTAGE" "25V"
					( Units "uVoltage" "V" 1.000000)
					( Origin gFrontEnd )
				)
				( attribute "XY" "(650,1700)"
					( Origin gFrontEnd )
				)
				( attribute "CHIPS_PART_NAME" "CAP_A"
					( Origin gPackager )
				)
				( attribute "CDS_PART_NAME" "CAP_A_0402V-0.01UF,25V,10%,X7RA"
					( Origin gPackager )
				)
				( objectStatus "C2L24" )
				( pin "a"
					( attribute "PN" "1"
						( Origin gPackager )
					)
					( objectStatus "C2L24.1" )
				)
				( pin "b"
					( attribute "PN" "2"
						( Origin gPackager )
					)
					( objectStatus "C2L24.2" )
				)
			)
			( gate "@baseboard_fab2_lib.baseboard_fab2(sch_1):page173_i259"
				( attribute "BOM_COST" "ST_SATA"
					( Origin gFrontEnd )
				)
				( attribute "CDS_LIB" "dev_discrete"
					( Origin gPackager )
				)
				( attribute "CDS_LOCATION" "C2L21"
					( Origin gPackager )
				)
				( attribute "CDS_SEC" "1"
					( Origin gPackager )
				)
				( attribute "LOCATION" "C2L21"
					( Origin gFrontEnd )
				)
				( attribute "MATERIAL" "X7R"
					( Origin gFrontEnd )
				)
				( attribute "PACK_TYPE" "0402V"
					( Origin gFrontEnd )
				)
				( attribute "PART_NUMBER" "A36096-045"
					( Origin gFrontEnd )
				)
				( attribute "PHYS_PAGE" "173"
					( Origin gFrontEnd )
				)
				( attribute "ROOM" "ST_SATA"
					( Origin gFrontEnd )
				)
				( attribute "ROT" "0"
					( Origin gFrontEnd )
				)
				( attribute "SEC" "1"
					( Origin gFrontEnd )
				)
				( attribute "SEC_TYPE" "0402V"
					( Origin gFrontEnd )
				)
				( attribute "TOLERANCE" "10%"
					( Origin gFrontEnd )
				)
				( attribute "VALUE" "0.01UF"
					( Origin gFrontEnd )
				)
				( attribute "VER" "2"
					( Origin gFrontEnd )
				)
				( attribute "VOLTAGE" "25V"
					( Units "uVoltage" "V" 1.000000)
					( Origin gFrontEnd )
				)
				( attribute "XY" "(1050,1550)"
					( Origin gFrontEnd )
				)
				( attribute "CHIPS_PART_NAME" "CAP_A"
					( Origin gPackager )
				)
				( attribute "CDS_PART_NAME" "CAP_A_0402V-0.01UF,25V,10%,X7RA"
					( Origin gPackager )
				)
				( objectStatus "C2L21" )
				( pin "a"
					( attribute "PN" "1"
						( Origin gPackager )
					)
					( objectStatus "C2L21.1" )
				)
				( pin "b"
					( attribute "PN" "2"
						( Origin gPackager )
					)
					( objectStatus "C2L21.2" )
				)
			)
			( gate "@baseboard_fab2_lib.baseboard_fab2(sch_1):page173_i261"
				( attribute "BOM_COST" "ST_SATA"
					( Origin gFrontEnd )
				)
				( attribute "CDS_LIB" "mstr_discrete"
					( Origin gPackager )
				)
				( attribute "CDS_LOCATION" "R2L23"
					( Origin gPackager )
				)
				( attribute "CDS_SEC" "1"
					( Origin gPackager )
				)
				( attribute "LOCATION" "R2L23"
					( Origin gFrontEnd )
				)
				( attribute "MATERIAL" "CHIP"
					( Origin gFrontEnd )
				)
				( attribute "PACK_TYPE" "0402"
					( Origin gFrontEnd )
				)
				( attribute "PART_NUMBER" "G21796-001"
					( Origin gFrontEnd )
				)
				( attribute "PHYS_PAGE" "173"
					( Origin gFrontEnd )
				)
				( attribute "ROOM" "ST_SATA"
					( Origin gFrontEnd )
				)
				( attribute "ROT" "0"
					( Origin gFrontEnd )
				)
				( attribute "SEC" "1"
					( Origin gFrontEnd )
				)
				( attribute "SEC_TYPE" "0402"
					( Origin gFrontEnd )
				)
				( attribute "TOLERANCE" "1%"
					( Origin gFrontEnd )
				)
				( attribute "VALUE" "2.0K"
					( Origin gFrontEnd )
				)
				( attribute "VER" "1"
					( Origin gFrontEnd )
				)
				( attribute "WATTAGE" "1/16W"
					( Origin gFrontEnd )
				)
				( attribute "XY" "(-3900,2200)"
					( Origin gFrontEnd )
				)
				( attribute "CHIPS_PART_NAME" "RES"
					( Origin gPackager )
				)
				( attribute "CDS_PART_NAME" "RES_0402-2.0K,1%,1/16W,CHIP,G2A"
					( Origin gPackager )
				)
				( objectStatus "R2L23" )
				( pin "a"
					( attribute "PN" "1"
						( Origin gPackager )
					)
					( objectStatus "R2L23.1" )
				)
				( pin "b"
					( attribute "PN" "2"
						( Origin gPackager )
					)
					( objectStatus "R2L23.2" )
				)
			)
			( gate "@baseboard_fab2_lib.baseboard_fab2(sch_1):page173_i263"
				( attribute "BOM_COST" "ST_SATA"
					( Origin gFrontEnd )
				)
				( attribute "CDS_LIB" "mstr_discrete"
					( Origin gPackager )
				)
				( attribute "CDS_LOCATION" "R2L21"
					( Origin gPackager )
				)
				( attribute "CDS_SEC" "1"
					( Origin gPackager )
				)
				( attribute "LOCATION" "R2L21"
					( Origin gFrontEnd )
				)
				( attribute "MATERIAL" "CHIP"
					( Origin gFrontEnd )
				)
				( attribute "PACK_TYPE" "0402"
					( Origin gFrontEnd )
				)
				( attribute "PART_NUMBER" "G21796-001"
					( Origin gFrontEnd )
				)
				( attribute "PHYS_PAGE" "173"
					( Origin gFrontEnd )
				)
				( attribute "ROOM" "ST_SATA"
					( Origin gFrontEnd )
				)
				( attribute "ROT" "0"
					( Origin gFrontEnd )
				)
				( attribute "SEC" "1"
					( Origin gFrontEnd )
				)
				( attribute "SEC_TYPE" "0402"
					( Origin gFrontEnd )
				)
				( attribute "TOLERANCE" "1%"
					( Origin gFrontEnd )
				)
				( attribute "VALUE" "2.0K"
					( Origin gFrontEnd )
				)
				( attribute "VER" "2"
					( Origin gFrontEnd )
				)
				( attribute "WATTAGE" "1/16W"
					( Origin gFrontEnd )
				)
				( attribute "XY" "(-3900,4675)"
					( Origin gFrontEnd )
				)
				( attribute "CHIPS_PART_NAME" "RES"
					( Origin gPackager )
				)
				( attribute "CDS_PART_NAME" "RES_0402-2.0K,1%,1/16W,CHIP,G2A"
					( Origin gPackager )
				)
				( objectStatus "R2L21" )
				( pin "a"
					( attribute "PN" "1"
						( Origin gPackager )
					)
					( objectStatus "R2L21.1" )
				)
				( pin "b"
					( attribute "PN" "2"
						( Origin gPackager )
					)
					( objectStatus "R2L21.2" )
				)
			)
			( gate "@baseboard_fab2_lib.baseboard_fab2(sch_1):page173_i264"
				( attribute "BOM_COST" "ST_SATA"
					( Origin gFrontEnd )
				)
				( attribute "CDS_LIB" "mstr_discrete"
					( Origin gPackager )
				)
				( attribute "CDS_LOCATION" "R2L22"
					( Origin gPackager )
				)
				( attribute "CDS_SEC" "1"
					( Origin gPackager )
				)
				( attribute "LOCATION" "R2L22"
					( Origin gFrontEnd )
				)
				( attribute "MATERIAL" "CHIP"
					( Origin gFrontEnd )
				)
				( attribute "PACK_TYPE" "0402"
					( Origin gFrontEnd )
				)
				( attribute "PART_NUMBER" "G21796-026"
					( Origin gFrontEnd )
				)
				( attribute "PHYS_PAGE" "173"
					( Origin gFrontEnd )
				)
				( attribute "ROOM" "ST_SATA"
					( Origin gFrontEnd )
				)
				( attribute "ROT" "0"
					( Origin gFrontEnd )
				)
				( attribute "SEC" "1"
					( Origin gFrontEnd )
				)
				( attribute "SEC_TYPE" "0402"
					( Origin gFrontEnd )
				)
				( attribute "TOLERANCE" "1%"
					( Origin gFrontEnd )
				)
				( attribute "VALUE" "1.00K"
					( Origin gFrontEnd )
				)
				( attribute "VER" "2"
					( Origin gFrontEnd )
				)
				( attribute "WATTAGE" "1/16W"
					( Origin gFrontEnd )
				)
				( attribute "XY" "(1625,2000)"
					( Origin gFrontEnd )
				)
				( attribute "CHIPS_PART_NAME" "RES"
					( Origin gPackager )
				)
				( attribute "CDS_PART_NAME" "RES_0402-1.00K,1%,1/16W,CHIP,GA"
					( Origin gPackager )
				)
				( objectStatus "R2L22" )
				( pin "a"
					( attribute "PN" "1"
						( Origin gPackager )
					)
					( objectStatus "R2L22.1" )
				)
				( pin "b"
					( attribute "PN" "2"
						( Origin gPackager )
					)
					( objectStatus "R2L22.2" )
				)
			)
			( gate "@baseboard_fab2_lib.baseboard_fab2(sch_1):page173_i266"
				( attribute "BOM_COST" "ST_SATA"
					( Origin gFrontEnd )
				)
				( attribute "CDS_LIB" "mstr_discrete"
					( Origin gPackager )
				)
				( attribute "CDS_LOCATION" "R2L18"
					( Origin gPackager )
				)
				( attribute "CDS_SEC" "1"
					( Origin gPackager )
				)
				( attribute "LOCATION" "R2L18"
					( Origin gFrontEnd )
				)
				( attribute "MATERIAL" "CHIP"
					( Origin gFrontEnd )
				)
				( attribute "PACK_TYPE" "0402"
					( Origin gFrontEnd )
				)
				( attribute "PART_NUMBER" "G21796-026"
					( Origin gFrontEnd )
				)
				( attribute "PHYS_PAGE" "173"
					( Origin gFrontEnd )
				)
				( attribute "ROOM" "ST_SATA"
					( Origin gFrontEnd )
				)
				( attribute "ROT" "0"
					( Origin gFrontEnd )
				)
				( attribute "SEC" "1"
					( Origin gFrontEnd )
				)
				( attribute "SEC_TYPE" "0402"
					( Origin gFrontEnd )
				)
				( attribute "TOLERANCE" "1%"
					( Origin gFrontEnd )
				)
				( attribute "VALUE" "1.00K"
					( Origin gFrontEnd )
				)
				( attribute "VER" "2"
					( Origin gFrontEnd )
				)
				( attribute "WATTAGE" "1/16W"
					( Origin gFrontEnd )
				)
				( attribute "XY" "(1675,3500)"
					( Origin gFrontEnd )
				)
				( attribute "CHIPS_PART_NAME" "RES"
					( Origin gPackager )
				)
				( attribute "CDS_PART_NAME" "RES_0402-1.00K,1%,1/16W,CHIP,GA"
					( Origin gPackager )
				)
				( objectStatus "R2L18" )
				( pin "a"
					( attribute "PN" "1"
						( Origin gPackager )
					)
					( objectStatus "R2L18.1" )
				)
				( pin "b"
					( attribute "PN" "2"
						( Origin gPackager )
					)
					( objectStatus "R2L18.2" )
				)
			)
			( gate "@baseboard_fab2_lib.baseboard_fab2(sch_1):page174_i5"
				( attribute "BOM_COST" "ST_SATA"
					( Origin gFrontEnd )
				)
				( attribute "CDS_LIB" "mstr_discrete"
					( Origin gPackager )
				)
				( attribute "CDS_LOCATION" "R1L3"
					( Origin gPackager )
				)
				( attribute "CDS_SEC" "1"
					( Origin gPackager )
				)
				( attribute "LOCATION" "R1L3"
					( Origin gFrontEnd )
				)
				( attribute "MATERIAL" "CHIP"
					( Origin gFrontEnd )
				)
				( attribute "PACK_TYPE" "0402"
					( Origin gFrontEnd )
				)
				( attribute "PART_NUMBER" "G21796-026"
					( Origin gFrontEnd )
				)
				( attribute "PHYS_PAGE" "174"
					( Origin gFrontEnd )
				)
				( attribute "ROOM" "ST_SATA"
					( Origin gFrontEnd )
				)
				( attribute "ROT" "0"
					( Origin gFrontEnd )
				)
				( attribute "SEC" "1"
					( Origin gPackager )
				)
				( attribute "TOLERANCE" "1%"
					( Origin gFrontEnd )
				)
				( attribute "VALUE" "1.00K"
					( Origin gFrontEnd )
				)
				( attribute "VER" "2"
					( Origin gFrontEnd )
				)
				( attribute "WATTAGE" "1/16W"
					( Origin gFrontEnd )
				)
				( attribute "XY" "(12250,2425)"
					( Origin gFrontEnd )
				)
				( attribute "CHIPS_PART_NAME" "RES"
					( Origin gPackager )
				)
				( attribute "CDS_PART_NAME" "RES_0402-1.00K,1%,1/16W,CHIP,GA"
					( Origin gPackager )
				)
				( objectStatus "R1L3" )
				( pin "a"
					( attribute "PN" "1"
						( Origin gPackager )
					)
					( objectStatus "R1L3.1" )
				)
				( pin "b"
					( attribute "PN" "2"
						( Origin gPackager )
					)
					( objectStatus "R1L3.2" )
				)
			)
			( gate "@baseboard_fab2_lib.baseboard_fab2(sch_1):page174_i8"
				( attribute "BOM_COST" "ST_SATA"
					( Origin gFrontEnd )
				)
				( attribute "CDS_LIB" "dev_discrete"
					( Origin gPackager )
				)
				( attribute "CDS_LOCATION" "C1L3"
					( Origin gPackager )
				)
				( attribute "CDS_SEC" "1"
					( Origin gPackager )
				)
				( attribute "LOCATION" "C1L3"
					( Origin gFrontEnd )
				)
				( attribute "MATERIAL" "X7R"
					( Origin gFrontEnd )
				)
				( attribute "PACK_TYPE" "0402V"
					( Origin gFrontEnd )
				)
				( attribute "PART_NUMBER" "A36096-045"
					( Origin gFrontEnd )
				)
				( attribute "PHYS_PAGE" "174"
					( Origin gFrontEnd )
				)
				( attribute "ROOM" "ST_SATA"
					( Origin gFrontEnd )
				)
				( attribute "ROT" "0"
					( Origin gFrontEnd )
				)
				( attribute "SEC" "1"
					( Origin gPackager )
				)
				( attribute "TOLERANCE" "10%"
					( Origin gFrontEnd )
				)
				( attribute "VALUE" "0.01UF"
					( Origin gFrontEnd )
				)
				( attribute "VER" "2"
					( Origin gFrontEnd )
				)
				( attribute "VOLTAGE" "25V"
					( Units "uVoltage" "V" 1.000000)
					( Origin gFrontEnd )
				)
				( attribute "XY" "(11225,3475)"
					( Origin gFrontEnd )
				)
				( attribute "CHIPS_PART_NAME" "CAP_A"
					( Origin gPackager )
				)
				( attribute "CDS_PART_NAME" "CAP_A_0402V-0.01UF,25V,10%,X7RA"
					( Origin gPackager )
				)
				( objectStatus "C1L3" )
				( pin "a"
					( attribute "PN" "1"
						( Origin gPackager )
					)
					( objectStatus "C1L3.1" )
				)
				( pin "b"
					( attribute "PN" "2"
						( Origin gPackager )
					)
					( objectStatus "C1L3.2" )
				)
			)
			( gate "@baseboard_fab2_lib.baseboard_fab2(sch_1):page174_i9"
				( attribute "BOM_COST" "ST_SATA"
					( Origin gFrontEnd )
				)
				( attribute "CDS_LIB" "dev_discrete"
					( Origin gPackager )
				)
				( attribute "CDS_LOCATION" "C1L2"
					( Origin gPackager )
				)
				( attribute "CDS_SEC" "1"
					( Origin gPackager )
				)
				( attribute "LOCATION" "C1L2"
					( Origin gFrontEnd )
				)
				( attribute "MATERIAL" "X7R"
					( Origin gFrontEnd )
				)
				( attribute "PACK_TYPE" "0402V"
					( Origin gFrontEnd )
				)
				( attribute "PART_NUMBER" "A36096-045"
					( Origin gFrontEnd )
				)
				( attribute "PHYS_PAGE" "174"
					( Origin gFrontEnd )
				)
				( attribute "ROOM" "ST_SATA"
					( Origin gFrontEnd )
				)
				( attribute "ROT" "0"
					( Origin gFrontEnd )
				)
				( attribute "SEC" "1"
					( Origin gPackager )
				)
				( attribute "TOLERANCE" "10%"
					( Origin gFrontEnd )
				)
				( attribute "VALUE" "0.01UF"
					( Origin gFrontEnd )
				)
				( attribute "VER" "2"
					( Origin gFrontEnd )
				)
				( attribute "VOLTAGE" "25V"
					( Units "uVoltage" "V" 1.000000)
					( Origin gFrontEnd )
				)
				( attribute "XY" "(10925,3725)"
					( Origin gFrontEnd )
				)
				( attribute "CHIPS_PART_NAME" "CAP_A"
					( Origin gPackager )
				)
				( attribute "CDS_PART_NAME" "CAP_A_0402V-0.01UF,25V,10%,X7RA"
					( Origin gPackager )
				)
				( objectStatus "C1L2" )
				( pin "a"
					( attribute "PN" "1"
						( Origin gPackager )
					)
					( objectStatus "C1L2.1" )
				)
				( pin "b"
					( attribute "PN" "2"
						( Origin gPackager )
					)
					( objectStatus "C1L2.2" )
				)
			)
			( gate "@baseboard_fab2_lib.baseboard_fab2(sch_1):page174_i12"
				( attribute "BOM_COST" "ST_SATA"
					( Origin gFrontEnd )
				)
				( attribute "CDS_LIB" "dev_discrete"
					( Origin gPackager )
				)
				( attribute "CDS_LOCATION" "C1L7"
					( Origin gPackager )
				)
				( attribute "CDS_SEC" "1"
					( Origin gPackager )
				)
				( attribute "LOCATION" "C1L7"
					( Origin gFrontEnd )
				)
				( attribute "MATERIAL" "X7R"
					( Origin gFrontEnd )
				)
				( attribute "PACK_TYPE" "0402V"
					( Origin gFrontEnd )
				)
				( attribute "PART_NUMBER" "A36096-045"
					( Origin gFrontEnd )
				)
				( attribute "PHYS_PAGE" "174"
					( Origin gFrontEnd )
				)
				( attribute "ROOM" "ST_SATA"
					( Origin gFrontEnd )
				)
				( attribute "ROT" "0"
					( Origin gFrontEnd )
				)
				( attribute "SEC" "1"
					( Origin gPackager )
				)
				( attribute "TOLERANCE" "10%"
					( Origin gFrontEnd )
				)
				( attribute "VALUE" "0.01UF"
					( Origin gFrontEnd )
				)
				( attribute "VER" "2"
					( Origin gFrontEnd )
				)
				( attribute "VOLTAGE" "25V"
					( Units "uVoltage" "V" 1.000000)
					( Origin gFrontEnd )
				)
				( attribute "XY" "(11225,3025)"
					( Origin gFrontEnd )
				)
				( attribute "CHIPS_PART_NAME" "CAP_A"
					( Origin gPackager )
				)
				( attribute "CDS_PART_NAME" "CAP_A_0402V-0.01UF,25V,10%,X7RA"
					( Origin gPackager )
				)
				( objectStatus "C1L7" )
				( pin "a"
					( attribute "PN" "1"
						( Origin gPackager )
					)
					( objectStatus "C1L7.1" )
				)
				( pin "b"
					( attribute "PN" "2"
						( Origin gPackager )
					)
					( objectStatus "C1L7.2" )
				)
			)
			( gate "@baseboard_fab2_lib.baseboard_fab2(sch_1):page174_i13"
				( attribute "BOM_COST" "ST_SATA"
					( Origin gFrontEnd )
				)
				( attribute "CDS_LIB" "dev_discrete"
					( Origin gPackager )
				)
				( attribute "CDS_LOCATION" "C1L6"
					( Origin gPackager )
				)
				( attribute "CDS_SEC" "1"
					( Origin gPackager )
				)
				( attribute "LOCATION" "C1L6"
					( Origin gFrontEnd )
				)
				( attribute "MATERIAL" "X7R"
					( Origin gFrontEnd )
				)
				( attribute "PACK_TYPE" "0402V"
					( Origin gFrontEnd )
				)
				( attribute "PART_NUMBER" "A36096-045"
					( Origin gFrontEnd )
				)
				( attribute "PHYS_PAGE" "174"
					( Origin gFrontEnd )
				)
				( attribute "ROOM" "ST_SATA"
					( Origin gFrontEnd )
				)
				( attribute "ROT" "0"
					( Origin gFrontEnd )
				)
				( attribute "SEC" "1"
					( Origin gPackager )
				)
				( attribute "TOLERANCE" "10%"
					( Origin gFrontEnd )
				)
				( attribute "VALUE" "0.01UF"
					( Origin gFrontEnd )
				)
				( attribute "VER" "2"
					( Origin gFrontEnd )
				)
				( attribute "VOLTAGE" "25V"
					( Units "uVoltage" "V" 1.000000)
					( Origin gFrontEnd )
				)
				( attribute "XY" "(10925,3250)"
					( Origin gFrontEnd )
				)
				( attribute "CHIPS_PART_NAME" "CAP_A"
					( Origin gPackager )
				)
				( attribute "CDS_PART_NAME" "CAP_A_0402V-0.01UF,25V,10%,X7RA"
					( Origin gPackager )
				)
				( objectStatus "C1L6" )
				( pin "a"
					( attribute "PN" "1"
						( Origin gPackager )
					)
					( objectStatus "C1L6.1" )
				)
				( pin "b"
					( attribute "PN" "2"
						( Origin gPackager )
					)
					( objectStatus "C1L6.2" )
				)
			)
			( gate "@baseboard_fab2_lib.baseboard_fab2(sch_1):page174_i14"
				( attribute "BOM_COST" "ST_SATA"
					( Origin gFrontEnd )
				)
				( attribute "CDS_LIB" "dev_discrete"
					( Origin gPackager )
				)
				( attribute "CDS_LOCATION" "C1L13"
					( Origin gPackager )
				)
				( attribute "CDS_SEC" "1"
					( Origin gPackager )
				)
				( attribute "LOCATION" "C1L13"
					( Origin gFrontEnd )
				)
				( attribute "MATERIAL" "X7R"
					( Origin gFrontEnd )
				)
				( attribute "PACK_TYPE" "0402V"
					( Origin gFrontEnd )
				)
				( attribute "PART_NUMBER" "A36096-045"
					( Origin gFrontEnd )
				)
				( attribute "PHYS_PAGE" "174"
					( Origin gFrontEnd )
				)
				( attribute "ROOM" "ST_SATA"
					( Origin gFrontEnd )
				)
				( attribute "ROT" "0"
					( Origin gFrontEnd )
				)
				( attribute "SEC" "1"
					( Origin gPackager )
				)
				( attribute "TOLERANCE" "10%"
					( Origin gFrontEnd )
				)
				( attribute "VALUE" "0.01UF"
					( Origin gFrontEnd )
				)
				( attribute "VER" "2"
					( Origin gFrontEnd )
				)
				( attribute "VOLTAGE" "25V"
					( Units "uVoltage" "V" 1.000000)
					( Origin gFrontEnd )
				)
				( attribute "XY" "(11025,2250)"
					( Origin gFrontEnd )
				)
				( attribute "CHIPS_PART_NAME" "CAP_A"
					( Origin gPackager )
				)
				( attribute "CDS_PART_NAME" "CAP_A_0402V-0.01UF,25V,10%,X7RA"
					( Origin gPackager )
				)
				( objectStatus "C1L13" )
				( pin "a"
					( attribute "PN" "1"
						( Origin gPackager )
					)
					( objectStatus "C1L13.1" )
				)
				( pin "b"
					( attribute "PN" "2"
						( Origin gPackager )
					)
					( objectStatus "C1L13.2" )
				)
			)
			( gate "@baseboard_fab2_lib.baseboard_fab2(sch_1):page174_i18"
				( attribute "BOM_COST" "ST_SATA"
					( Origin gFrontEnd )
				)
				( attribute "CDS_LIB" "dev_discrete"
					( Origin gPackager )
				)
				( attribute "CDS_LOCATION" "C1L15"
					( Origin gPackager )
				)
				( attribute "CDS_SEC" "1"
					( Origin gPackager )
				)
				( attribute "LOCATION" "C1L15"
					( Origin gFrontEnd )
				)
				( attribute "MATERIAL" "X7R"
					( Origin gFrontEnd )
				)
				( attribute "PACK_TYPE" "0402V"
					( Origin gFrontEnd )
				)
				( attribute "PART_NUMBER" "A36096-045"
					( Origin gFrontEnd )
				)
				( attribute "PHYS_PAGE" "174"
					( Origin gFrontEnd )
				)
				( attribute "ROOM" "ST_SATA"
					( Origin gFrontEnd )
				)
				( attribute "ROT" "0"
					( Origin gFrontEnd )
				)
				( attribute "SEC" "1"
					( Origin gPackager )
				)
				( attribute "TOLERANCE" "10%"
					( Origin gFrontEnd )
				)
				( attribute "VALUE" "0.01UF"
					( Origin gFrontEnd )
				)
				( attribute "VER" "2"
					( Origin gFrontEnd )
				)
				( attribute "VOLTAGE" "25V"
					( Units "uVoltage" "V" 1.000000)
					( Origin gFrontEnd )
				)
				( attribute "XY" "(11025,1825)"
					( Origin gFrontEnd )
				)
				( attribute "CHIPS_PART_NAME" "CAP_A"
					( Origin gPackager )
				)
				( attribute "CDS_PART_NAME" "CAP_A_0402V-0.01UF,25V,10%,X7RA"
					( Origin gPackager )
				)
				( objectStatus "C1L15" )
				( pin "a"
					( attribute "PN" "1"
						( Origin gPackager )
					)
					( objectStatus "C1L15.1" )
				)
				( pin "b"
					( attribute "PN" "2"
						( Origin gPackager )
					)
					( objectStatus "C1L15.2" )
				)
			)
			( gate "@baseboard_fab2_lib.baseboard_fab2(sch_1):page174_i19"
				( attribute "BOM_COST" "ST_SATA"
					( Origin gFrontEnd )
				)
				( attribute "CDS_LIB" "dev_discrete"
					( Origin gPackager )
				)
				( attribute "CDS_LOCATION" "C1L12"
					( Origin gPackager )
				)
				( attribute "CDS_SEC" "1"
					( Origin gPackager )
				)
				( attribute "LOCATION" "C1L12"
					( Origin gFrontEnd )
				)
				( attribute "MATERIAL" "X7R"
					( Origin gFrontEnd )
				)
				( attribute "PACK_TYPE" "0402V"
					( Origin gFrontEnd )
				)
				( attribute "PART_NUMBER" "A36096-045"
					( Origin gFrontEnd )
				)
				( attribute "PHYS_PAGE" "174"
					( Origin gFrontEnd )
				)
				( attribute "ROOM" "ST_SATA"
					( Origin gFrontEnd )
				)
				( attribute "ROT" "0"
					( Origin gFrontEnd )
				)
				( attribute "SEC" "1"
					( Origin gPackager )
				)
				( attribute "TOLERANCE" "10%"
					( Origin gFrontEnd )
				)
				( attribute "VALUE" "0.01UF"
					( Origin gFrontEnd )
				)
				( attribute "VER" "2"
					( Origin gFrontEnd )
				)
				( attribute "VOLTAGE" "25V"
					( Units "uVoltage" "V" 1.000000)
					( Origin gFrontEnd )
				)
				( attribute "XY" "(10750,2475)"
					( Origin gFrontEnd )
				)
				( attribute "CHIPS_PART_NAME" "CAP_A"
					( Origin gPackager )
				)
				( attribute "CDS_PART_NAME" "CAP_A_0402V-0.01UF,25V,10%,X7RA"
					( Origin gPackager )
				)
				( objectStatus "C1L12" )
				( pin "a"
					( attribute "PN" "1"
						( Origin gPackager )
					)
					( objectStatus "C1L12.1" )
				)
				( pin "b"
					( attribute "PN" "2"
						( Origin gPackager )
					)
					( objectStatus "C1L12.2" )
				)
			)
			( gate "@baseboard_fab2_lib.baseboard_fab2(sch_1):page174_i20"
				( attribute "BOM_COST" "ST_SATA"
					( Origin gFrontEnd )
				)
				( attribute "CDS_LIB" "dev_discrete"
					( Origin gPackager )
				)
				( attribute "CDS_LOCATION" "C1L14"
					( Origin gPackager )
				)
				( attribute "CDS_SEC" "1"
					( Origin gPackager )
				)
				( attribute "LOCATION" "C1L14"
					( Origin gFrontEnd )
				)
				( attribute "MATERIAL" "X7R"
					( Origin gFrontEnd )
				)
				( attribute "PACK_TYPE" "0402V"
					( Origin gFrontEnd )
				)
				( attribute "PART_NUMBER" "A36096-045"
					( Origin gFrontEnd )
				)
				( attribute "PHYS_PAGE" "174"
					( Origin gFrontEnd )
				)
				( attribute "ROOM" "ST_SATA"
					( Origin gFrontEnd )
				)
				( attribute "ROT" "0"
					( Origin gFrontEnd )
				)
				( attribute "SEC" "1"
					( Origin gPackager )
				)
				( attribute "TOLERANCE" "10%"
					( Origin gFrontEnd )
				)
				( attribute "VALUE" "0.01UF"
					( Origin gFrontEnd )
				)
				( attribute "VER" "2"
					( Origin gFrontEnd )
				)
				( attribute "VOLTAGE" "25V"
					( Units "uVoltage" "V" 1.000000)
					( Origin gFrontEnd )
				)
				( attribute "XY" "(10750,2025)"
					( Origin gFrontEnd )
				)
				( attribute "CHIPS_PART_NAME" "CAP_A"
					( Origin gPackager )
				)
				( attribute "CDS_PART_NAME" "CAP_A_0402V-0.01UF,25V,10%,X7RA"
					( Origin gPackager )
				)
				( objectStatus "C1L14" )
				( pin "a"
					( attribute "PN" "1"
						( Origin gPackager )
					)
					( objectStatus "C1L14.1" )
				)
				( pin "b"
					( attribute "PN" "2"
						( Origin gPackager )
					)
					( objectStatus "C1L14.2" )
				)
			)
			( gate "@baseboard_fab2_lib.baseboard_fab2(sch_1):page174_i25"
				( attribute "BOM_COST" "ST_SATA"
					( Origin gFrontEnd )
				)
				( attribute "CDS_LIB" "mstr_discrete"
					( Origin gPackager )
				)
				( attribute "CDS_LOCATION" "R1L1"
					( Origin gPackager )
				)
				( attribute "CDS_SEC" "1"
					( Origin gPackager )
				)
				( attribute "LOCATION" "R1L1"
					( Origin gFrontEnd )
				)
				( attribute "MATERIAL" "CHIP"
					( Origin gFrontEnd )
				)
				( attribute "PACK_TYPE" "0402"
					( Origin gFrontEnd )
				)
				( attribute "PART_NUMBER" "G21796-001"
					( Origin gFrontEnd )
				)
				( attribute "PHYS_PAGE" "174"
					( Origin gFrontEnd )
				)
				( attribute "ROOM" "ST_SATA"
					( Origin gFrontEnd )
				)
				( attribute "ROT" "0"
					( Origin gFrontEnd )
				)
				( attribute "SEC" "1"
					( Origin gPackager )
				)
				( attribute "TOLERANCE" "1%"
					( Origin gFrontEnd )
				)
				( attribute "VALUE" "2.0K"
					( Origin gFrontEnd )
				)
				( attribute "VER" "2"
					( Origin gFrontEnd )
				)
				( attribute "WATTAGE" "1/16W"
					( Origin gFrontEnd )
				)
				( attribute "XY" "(7250,3600)"
					( Origin gFrontEnd )
				)
				( attribute "CHIPS_PART_NAME" "RES"
					( Origin gPackager )
				)
				( attribute "CDS_PART_NAME" "RES_0402-2.0K,1%,1/16W,CHIP,G2A"
					( Origin gPackager )
				)
				( objectStatus "R1L1" )
				( pin "a"
					( attribute "PN" "1"
						( Origin gPackager )
					)
					( objectStatus "R1L1.1" )
				)
				( pin "b"
					( attribute "PN" "2"
						( Origin gPackager )
					)
					( objectStatus "R1L1.2" )
				)
			)
			( gate "@baseboard_fab2_lib.baseboard_fab2(sch_1):page174_i26"
				( attribute "BOM_COST" "ST_SATA"
					( Origin gFrontEnd )
				)
				( attribute "CDS_LIB" "mstr_conn"
					( Origin gPackager )
				)
				( attribute "CDS_LOCATION" "J8A2"
					( Origin gPackager )
				)
				( attribute "CDS_SEC" "1"
					( Origin gPackager )
				)
				( attribute "LOCATION" "J8A2"
					( Origin gFrontEnd )
				)
				( attribute "MATERIAL" "CONN"
					( Origin gFrontEnd )
				)
				( attribute "PACK_TYPE" "CP"
					( Origin gFrontEnd )
				)
				( attribute "PART_NUMBER" "G97614-001"
					( Origin gFrontEnd )
				)
				( attribute "PHYS_PAGE" "174"
					( Origin gFrontEnd )
				)
				( attribute "ROOM" "ST_SATA"
					( Origin gFrontEnd )
				)
				( attribute "ROT" "0"
					( Origin gFrontEnd )
				)
				( attribute "SEC" "1"
					( Origin gPackager )
				)
				( attribute "VER" "1"
					( Origin gFrontEnd )
				)
				( attribute "XY" "(8650,2725)"
					( Origin gFrontEnd )
				)
				( attribute "CHIPS_PART_NAME" "CONN36_G97614001"
					( Origin gPackager )
				)
				( attribute "CDS_PART_NAME" "CONN36_G97614001_CP-CONN,G9761A"
					( Origin gPackager )
				)
				( objectStatus "J8A2" )
				( pin "gnd1"
					( attribute "PN" "A3"
						( Origin gPackager )
					)
					( objectStatus "J8A2.A3" )
				)
				( pin "gnd2"
					( attribute "PN" "A6"
						( Origin gPackager )
					)
					( objectStatus "J8A2.A6" )
				)
				( pin "gnd3"
					( attribute "PN" "A9"
						( Origin gPackager )
					)
					( objectStatus "J8A2.A9" )
				)
				( pin "gnd4"
					( attribute "PN" "B3"
						( Origin gPackager )
					)
					( objectStatus "J8A2.B3" )
				)
				( pin "gnd5"
					( attribute "PN" "B6"
						( Origin gPackager )
					)
					( objectStatus "J8A2.B6" )
				)
				( pin "gnd6"
					( attribute "PN" "B9"
						( Origin gPackager )
					)
					( objectStatus "J8A2.B9" )
				)
				( pin "gnd7"
					( attribute "PN" "C3"
						( Origin gPackager )
					)
					( objectStatus "J8A2.C3" )
				)
				( pin "gnd8"
					( attribute "PN" "C6"
						( Origin gPackager )
					)
					( objectStatus "J8A2.C6" )
				)
				( pin "gnd9"
					( attribute "PN" "C9"
						( Origin gPackager )
					)
					( objectStatus "J8A2.C9" )
				)
				( pin "gnd10"
					( attribute "PN" "D3"
						( Origin gPackager )
					)
					( objectStatus "J8A2.D3" )
				)
				( pin "gnd11"
					( attribute "PN" "D6"
						( Origin gPackager )
					)
					( objectStatus "J8A2.D6" )
				)
				( pin "gnd12"
					( attribute "PN" "D9"
						( Origin gPackager )
					)
					( objectStatus "J8A2.D9" )
				)
				( pin "rxa0_dn"
					( attribute "PN" "B5"
						( Origin gPackager )
					)
					( objectStatus "J8A2.B5" )
				)
				( pin "rxa0_dp"
					( attribute "PN" "B4"
						( Origin gPackager )
					)
					( objectStatus "J8A2.B4" )
				)
				( pin "rxa1_dn"
					( attribute "PN" "A5"
						( Origin gPackager )
					)
					( objectStatus "J8A2.A5" )
				)
				( pin "rxa1_dp"
					( attribute "PN" "A4"
						( Origin gPackager )
					)
					( objectStatus "J8A2.A4" )
				)
				( pin "rxa2_dn"
					( attribute "PN" "B8"
						( Origin gPackager )
					)
					( objectStatus "J8A2.B8" )
				)
				( pin "rxa2_dp"
					( attribute "PN" "B7"
						( Origin gPackager )
					)
					( objectStatus "J8A2.B7" )
				)
				( pin "rxa3_dn"
					( attribute "PN" "A8"
						( Origin gPackager )
					)
					( objectStatus "J8A2.A8" )
				)
				( pin "rxa3_dp"
					( attribute "PN" "A7"
						( Origin gPackager )
					)
					( objectStatus "J8A2.A7" )
				)
				( pin "sideband0"
					( attribute "PN" "A2"
						( Origin gPackager )
					)
					( objectStatus "J8A2.A2" )
				)
				( pin "sideband1"
					( attribute "PN" "B2"
						( Origin gPackager )
					)
					( objectStatus "J8A2.B2" )
				)
				( pin "sideband2"
					( attribute "PN" "C2"
						( Origin gPackager )
					)
					( objectStatus "J8A2.C2" )
				)
				( pin "sideband3"
					( attribute "PN" "B1"
						( Origin gPackager )
					)
					( objectStatus "J8A2.B1" )
				)
				( pin "sideband4"
					( attribute "PN" "C1"
						( Origin gPackager )
					)
					( objectStatus "J8A2.C1" )
				)
				( pin "sideband5"
					( attribute "PN" "D1"
						( Origin gPackager )
					)
					( objectStatus "J8A2.D1" )
				)
				( pin "sideband6"
					( attribute "PN" "D2"
						( Origin gPackager )
					)
					( objectStatus "J8A2.D2" )
				)
				( pin "sideband7"
					( attribute "PN" "A1"
						( Origin gPackager )
					)
					( objectStatus "J8A2.A1" )
				)
				( pin "txa0_dn"
					( attribute "PN" "D5"
						( Origin gPackager )
					)
					( objectStatus "J8A2.D5" )
				)
				( pin "txa0_dp"
					( attribute "PN" "D4"
						( Origin gPackager )
					)
					( objectStatus "J8A2.D4" )
				)
				( pin "txa1_dn"
					( attribute "PN" "C5"
						( Origin gPackager )
					)
					( objectStatus "J8A2.C5" )
				)
				( pin "txa1_dp"
					( attribute "PN" "C4"
						( Origin gPackager )
					)
					( objectStatus "J8A2.C4" )
				)
				( pin "txa2_dn"
					( attribute "PN" "D8"
						( Origin gPackager )
					)
					( objectStatus "J8A2.D8" )
				)
				( pin "txa2_dp"
					( attribute "PN" "D7"
						( Origin gPackager )
					)
					( objectStatus "J8A2.D7" )
				)
				( pin "txa3_dn"
					( attribute "PN" "C8"
						( Origin gPackager )
					)
					( objectStatus "J8A2.C8" )
				)
				( pin "txa3_dp"
					( attribute "PN" "C7"
						( Origin gPackager )
					)
					( objectStatus "J8A2.C7" )
				)
			)
			( gate "@baseboard_fab2_lib.baseboard_fab2(sch_1):page174_i28"
				( attribute "BOM_COST" "ST_SATA"
					( Origin gFrontEnd )
				)
				( attribute "CDS_LIB" "dev_discrete"
					( Origin gPackager )
				)
				( attribute "CDS_LOCATION" "C2L30"
					( Origin gPackager )
				)
				( attribute "CDS_SEC" "1"
					( Origin gPackager )
				)
				( attribute "LOCATION" "C2L30"
					( Origin gFrontEnd )
				)
				( attribute "MATERIAL" "X7R"
					( Origin gFrontEnd )
				)
				( attribute "PACK_TYPE" "0402V"
					( Origin gFrontEnd )
				)
				( attribute "PART_NUMBER" "A36096-045"
					( Origin gFrontEnd )
				)
				( attribute "PHYS_PAGE" "174"
					( Origin gFrontEnd )
				)
				( attribute "ROOM" "ST_SATA"
					( Origin gFrontEnd )
				)
				( attribute "ROT" "0"
					( Origin gFrontEnd )
				)
				( attribute "SEC" "1"
					( Origin gPackager )
				)
				( attribute "TOLERANCE" "10%"
					( Origin gFrontEnd )
				)
				( attribute "VALUE" "0.01UF"
					( Origin gFrontEnd )
				)
				( attribute "VER" "2"
					( Origin gFrontEnd )
				)
				( attribute "VOLTAGE" "25V"
					( Units "uVoltage" "V" 1.000000)
					( Origin gFrontEnd )
				)
				( attribute "XY" "(6525,3675)"
					( Origin gFrontEnd )
				)
				( attribute "CHIPS_PART_NAME" "CAP_A"
					( Origin gPackager )
				)
				( attribute "CDS_PART_NAME" "CAP_A_0402V-0.01UF,25V,10%,X7RA"
					( Origin gPackager )
				)
				( objectStatus "C2L30" )
				( pin "a"
					( attribute "PN" "1"
						( Origin gPackager )
					)
					( objectStatus "C2L30.1" )
				)
				( pin "b"
					( attribute "PN" "2"
						( Origin gPackager )
					)
					( objectStatus "C2L30.2" )
				)
			)
			( gate "@baseboard_fab2_lib.baseboard_fab2(sch_1):page174_i29"
				( attribute "BOM_COST" "ST_SATA"
					( Origin gFrontEnd )
				)
				( attribute "CDS_LIB" "dev_discrete"
					( Origin gPackager )
				)
				( attribute "CDS_LOCATION" "C2L31"
					( Origin gPackager )
				)
				( attribute "CDS_SEC" "1"
					( Origin gPackager )
				)
				( attribute "LOCATION" "C2L31"
					( Origin gFrontEnd )
				)
				( attribute "MATERIAL" "X7R"
					( Origin gFrontEnd )
				)
				( attribute "PACK_TYPE" "0402V"
					( Origin gFrontEnd )
				)
				( attribute "PART_NUMBER" "A36096-045"
					( Origin gFrontEnd )
				)
				( attribute "PHYS_PAGE" "174"
					( Origin gFrontEnd )
				)
				( attribute "ROOM" "ST_SATA"
					( Origin gFrontEnd )
				)
				( attribute "ROT" "0"
					( Origin gFrontEnd )
				)
				( attribute "SEC" "1"
					( Origin gPackager )
				)
				( attribute "TOLERANCE" "10%"
					( Origin gFrontEnd )
				)
				( attribute "VALUE" "0.01UF"
					( Origin gFrontEnd )
				)
				( attribute "VER" "2"
					( Origin gFrontEnd )
				)
				( attribute "VOLTAGE" "25V"
					( Units "uVoltage" "V" 1.000000)
					( Origin gFrontEnd )
				)
				( attribute "XY" "(6225,3450)"
					( Origin gFrontEnd )
				)
				( attribute "CHIPS_PART_NAME" "CAP_A"
					( Origin gPackager )
				)
				( attribute "CDS_PART_NAME" "CAP_A_0402V-0.01UF,25V,10%,X7RA"
					( Origin gPackager )
				)
				( objectStatus "C2L31" )
				( pin "a"
					( attribute "PN" "1"
						( Origin gPackager )
					)
					( objectStatus "C2L31.1" )
				)
				( pin "b"
					( attribute "PN" "2"
						( Origin gPackager )
					)
					( objectStatus "C2L31.2" )
				)
			)
			( gate "@baseboard_fab2_lib.baseboard_fab2(sch_1):page174_i30"
				( attribute "BOM_COST" "ST_SATA"
					( Origin gFrontEnd )
				)
				( attribute "CDS_LIB" "dev_discrete"
					( Origin gPackager )
				)
				( attribute "CDS_LOCATION" "C2L28"
					( Origin gPackager )
				)
				( attribute "CDS_SEC" "1"
					( Origin gPackager )
				)
				( attribute "LOCATION" "C2L28"
					( Origin gFrontEnd )
				)
				( attribute "MATERIAL" "X7R"
					( Origin gFrontEnd )
				)
				( attribute "PACK_TYPE" "0402V"
					( Origin gFrontEnd )
				)
				( attribute "PART_NUMBER" "A36096-045"
					( Origin gFrontEnd )
				)
				( attribute "PHYS_PAGE" "174"
					( Origin gFrontEnd )
				)
				( attribute "ROOM" "ST_SATA"
					( Origin gFrontEnd )
				)
				( attribute "ROT" "0"
					( Origin gFrontEnd )
				)
				( attribute "SEC" "1"
					( Origin gPackager )
				)
				( attribute "TOLERANCE" "10%"
					( Origin gFrontEnd )
				)
				( attribute "VALUE" "0.01UF"
					( Origin gFrontEnd )
				)
				( attribute "VER" "2"
					( Origin gFrontEnd )
				)
				( attribute "VOLTAGE" "25V"
					( Units "uVoltage" "V" 1.000000)
					( Origin gFrontEnd )
				)
				( attribute "XY" "(6525,3225)"
					( Origin gFrontEnd )
				)
				( attribute "CHIPS_PART_NAME" "CAP_A"
					( Origin gPackager )
				)
				( attribute "CDS_PART_NAME" "CAP_A_0402V-0.01UF,25V,10%,X7RA"
					( Origin gPackager )
				)
				( objectStatus "C2L28" )
				( pin "a"
					( attribute "PN" "1"
						( Origin gPackager )
					)
					( objectStatus "C2L28.1" )
				)
				( pin "b"
					( attribute "PN" "2"
						( Origin gPackager )
					)
					( objectStatus "C2L28.2" )
				)
			)
			( gate "@baseboard_fab2_lib.baseboard_fab2(sch_1):page174_i31"
				( attribute "BOM_COST" "ST_SATA"
					( Origin gFrontEnd )
				)
				( attribute "CDS_LIB" "dev_discrete"
					( Origin gPackager )
				)
				( attribute "CDS_LOCATION" "C2L35"
					( Origin gPackager )
				)
				( attribute "CDS_SEC" "1"
					( Origin gPackager )
				)
				( attribute "LOCATION" "C2L35"
					( Origin gFrontEnd )
				)
				( attribute "MATERIAL" "X7R"
					( Origin gFrontEnd )
				)
				( attribute "PACK_TYPE" "0402V"
					( Origin gFrontEnd )
				)
				( attribute "PART_NUMBER" "A36096-045"
					( Origin gFrontEnd )
				)
				( attribute "PHYS_PAGE" "174"
					( Origin gFrontEnd )
				)
				( attribute "ROOM" "ST_SATA"
					( Origin gFrontEnd )
				)
				( attribute "ROT" "0"
					( Origin gFrontEnd )
				)
				( attribute "SEC" "1"
					( Origin gPackager )
				)
				( attribute "TOLERANCE" "10%"
					( Origin gFrontEnd )
				)
				( attribute "VALUE" "0.01UF"
					( Origin gFrontEnd )
				)
				( attribute "VER" "2"
					( Origin gFrontEnd )
				)
				( attribute "VOLTAGE" "25V"
					( Units "uVoltage" "V" 1.000000)
					( Origin gFrontEnd )
				)
				( attribute "XY" "(6600,2475)"
					( Origin gFrontEnd )
				)
				( attribute "CHIPS_PART_NAME" "CAP_A"
					( Origin gPackager )
				)
				( attribute "CDS_PART_NAME" "CAP_A_0402V-0.01UF,25V,10%,X7RA"
					( Origin gPackager )
				)
				( objectStatus "C2L35" )
				( pin "a"
					( attribute "PN" "1"
						( Origin gPackager )
					)
					( objectStatus "C2L35.1" )
				)
				( pin "b"
					( attribute "PN" "2"
						( Origin gPackager )
					)
					( objectStatus "C2L35.2" )
				)
			)
			( gate "@baseboard_fab2_lib.baseboard_fab2(sch_1):page174_i32"
				( attribute "BOM_COST" "ST_SATA"
					( Origin gFrontEnd )
				)
				( attribute "CDS_LIB" "dev_discrete"
					( Origin gPackager )
				)
				( attribute "CDS_LOCATION" "C2L29"
					( Origin gPackager )
				)
				( attribute "CDS_SEC" "1"
					( Origin gPackager )
				)
				( attribute "LOCATION" "C2L29"
					( Origin gFrontEnd )
				)
				( attribute "MATERIAL" "X7R"
					( Origin gFrontEnd )
				)
				( attribute "PACK_TYPE" "0402V"
					( Origin gFrontEnd )
				)
				( attribute "PART_NUMBER" "A36096-045"
					( Origin gFrontEnd )
				)
				( attribute "PHYS_PAGE" "174"
					( Origin gFrontEnd )
				)
				( attribute "ROOM" "ST_SATA"
					( Origin gFrontEnd )
				)
				( attribute "ROT" "0"
					( Origin gFrontEnd )
				)
				( attribute "SEC" "1"
					( Origin gPackager )
				)
				( attribute "TOLERANCE" "10%"
					( Origin gFrontEnd )
				)
				( attribute "VALUE" "0.01UF"
					( Origin gFrontEnd )
				)
				( attribute "VER" "2"
					( Origin gFrontEnd )
				)
				( attribute "VOLTAGE" "25V"
					( Units "uVoltage" "V" 1.000000)
					( Origin gFrontEnd )
				)
				( attribute "XY" "(6225,3025)"
					( Origin gFrontEnd )
				)
				( attribute "CHIPS_PART_NAME" "CAP_A"
					( Origin gPackager )
				)
				( attribute "CDS_PART_NAME" "CAP_A_0402V-0.01UF,25V,10%,X7RA"
					( Origin gPackager )
				)
				( objectStatus "C2L29" )
				( pin "a"
					( attribute "PN" "1"
						( Origin gPackager )
					)
					( objectStatus "C2L29.1" )
				)
				( pin "b"
					( attribute "PN" "2"
						( Origin gPackager )
					)
					( objectStatus "C2L29.2" )
				)
			)
			( gate "@baseboard_fab2_lib.baseboard_fab2(sch_1):page174_i39"
				( attribute "BOM_COST" "ST_SATA"
					( Origin gFrontEnd )
				)
				( attribute "CDS_LIB" "dev_discrete"
					( Origin gPackager )
				)
				( attribute "CDS_LOCATION" "C2L36"
					( Origin gPackager )
				)
				( attribute "CDS_SEC" "1"
					( Origin gPackager )
				)
				( attribute "LOCATION" "C2L36"
					( Origin gFrontEnd )
				)
				( attribute "MATERIAL" "X7R"
					( Origin gFrontEnd )
				)
				( attribute "PACK_TYPE" "0402V"
					( Origin gFrontEnd )
				)
				( attribute "PART_NUMBER" "A36096-045"
					( Origin gFrontEnd )
				)
				( attribute "PHYS_PAGE" "174"
					( Origin gFrontEnd )
				)
				( attribute "ROOM" "ST_SATA"
					( Origin gFrontEnd )
				)
				( attribute "ROT" "0"
					( Origin gFrontEnd )
				)
				( attribute "SEC" "1"
					( Origin gPackager )
				)
				( attribute "TOLERANCE" "10%"
					( Origin gFrontEnd )
				)
				( attribute "VALUE" "0.01UF"
					( Origin gFrontEnd )
				)
				( attribute "VER" "2"
					( Origin gFrontEnd )
				)
				( attribute "VOLTAGE" "25V"
					( Units "uVoltage" "V" 1.000000)
					( Origin gFrontEnd )
				)
				( attribute "XY" "(6300,2250)"
					( Origin gFrontEnd )
				)
				( attribute "CHIPS_PART_NAME" "CAP_A"
					( Origin gPackager )
				)
				( attribute "CDS_PART_NAME" "CAP_A_0402V-0.01UF,25V,10%,X7RA"
					( Origin gPackager )
				)
				( objectStatus "C2L36" )
				( pin "a"
					( attribute "PN" "1"
						( Origin gPackager )
					)
					( objectStatus "C2L36.1" )
				)
				( pin "b"
					( attribute "PN" "2"
						( Origin gPackager )
					)
					( objectStatus "C2L36.2" )
				)
			)
			( gate "@baseboard_fab2_lib.baseboard_fab2(sch_1):page174_i40"
				( attribute "BOM_COST" "ST_SATA"
					( Origin gFrontEnd )
				)
				( attribute "CDS_LIB" "dev_discrete"
					( Origin gPackager )
				)
				( attribute "CDS_LOCATION" "C2L33"
					( Origin gPackager )
				)
				( attribute "CDS_SEC" "1"
					( Origin gPackager )
				)
				( attribute "LOCATION" "C2L33"
					( Origin gFrontEnd )
				)
				( attribute "MATERIAL" "X7R"
					( Origin gFrontEnd )
				)
				( attribute "PACK_TYPE" "0402V"
					( Origin gFrontEnd )
				)
				( attribute "PART_NUMBER" "A36096-045"
					( Origin gFrontEnd )
				)
				( attribute "PHYS_PAGE" "174"
					( Origin gFrontEnd )
				)
				( attribute "ROOM" "ST_SATA"
					( Origin gFrontEnd )
				)
				( attribute "ROT" "0"
					( Origin gFrontEnd )
				)
				( attribute "SEC" "1"
					( Origin gPackager )
				)
				( attribute "TOLERANCE" "10%"
					( Origin gFrontEnd )
				)
				( attribute "VALUE" "0.01UF"
					( Origin gFrontEnd )
				)
				( attribute "VER" "2"
					( Origin gFrontEnd )
				)
				( attribute "VOLTAGE" "25V"
					( Units "uVoltage" "V" 1.000000)
					( Origin gFrontEnd )
				)
				( attribute "XY" "(6600,2025)"
					( Origin gFrontEnd )
				)
				( attribute "CHIPS_PART_NAME" "CAP_A"
					( Origin gPackager )
				)
				( attribute "CDS_PART_NAME" "CAP_A_0402V-0.01UF,25V,10%,X7RA"
					( Origin gPackager )
				)
				( objectStatus "C2L33" )
				( pin "a"
					( attribute "PN" "1"
						( Origin gPackager )
					)
					( objectStatus "C2L33.1" )
				)
				( pin "b"
					( attribute "PN" "2"
						( Origin gPackager )
					)
					( objectStatus "C2L33.2" )
				)
			)
			( gate "@baseboard_fab2_lib.baseboard_fab2(sch_1):page174_i41"
				( attribute "BOM_COST" "ST_SATA"
					( Origin gFrontEnd )
				)
				( attribute "CDS_LIB" "dev_discrete"
					( Origin gPackager )
				)
				( attribute "CDS_LOCATION" "C2L34"
					( Origin gPackager )
				)
				( attribute "CDS_SEC" "1"
					( Origin gPackager )
				)
				( attribute "LOCATION" "C2L34"
					( Origin gFrontEnd )
				)
				( attribute "MATERIAL" "X7R"
					( Origin gFrontEnd )
				)
				( attribute "PACK_TYPE" "0402V"
					( Origin gFrontEnd )
				)
				( attribute "PART_NUMBER" "A36096-045"
					( Origin gFrontEnd )
				)
				( attribute "PHYS_PAGE" "174"
					( Origin gFrontEnd )
				)
				( attribute "ROOM" "ST_SATA"
					( Origin gFrontEnd )
				)
				( attribute "ROT" "0"
					( Origin gFrontEnd )
				)
				( attribute "SEC" "1"
					( Origin gPackager )
				)
				( attribute "TOLERANCE" "10%"
					( Origin gFrontEnd )
				)
				( attribute "VALUE" "0.01UF"
					( Origin gFrontEnd )
				)
				( attribute "VER" "2"
					( Origin gFrontEnd )
				)
				( attribute "VOLTAGE" "25V"
					( Units "uVoltage" "V" 1.000000)
					( Origin gFrontEnd )
				)
				( attribute "XY" "(6300,1825)"
					( Origin gFrontEnd )
				)
				( attribute "CHIPS_PART_NAME" "CAP_A"
					( Origin gPackager )
				)
				( attribute "CDS_PART_NAME" "CAP_A_0402V-0.01UF,25V,10%,X7RA"
					( Origin gPackager )
				)
				( objectStatus "C2L34" )
				( pin "a"
					( attribute "PN" "1"
						( Origin gPackager )
					)
					( objectStatus "C2L34.1" )
				)
				( pin "b"
					( attribute "PN" "2"
						( Origin gPackager )
					)
					( objectStatus "C2L34.2" )
				)
			)
			( gate "@baseboard_fab2_lib.baseboard_fab2(sch_1):page175_i4"
				( attribute "BOM_COST" "MIO_CHASSIS"
					( Origin gFrontEnd )
				)
				( attribute "CDS_LIB" "mstr_discrete"
					( Origin gPackager )
				)
				( attribute "CDS_LOCATION" "R1L31"
					( Origin gPackager )
				)
				( attribute "CDS_SEC" "1"
					( Origin gPackager )
				)
				( attribute "LOCATION" "R1L31"
					( Origin gFrontEnd )
				)
				( attribute "MATERIAL" "CHIP"
					( Origin gFrontEnd )
				)
				( attribute "PACK_TYPE" "0402"
					( Origin gFrontEnd )
				)
				( attribute "PART_NUMBER" "G21796-004"
					( Origin gFrontEnd )
				)
				( attribute "PHYS_PAGE" "175"
					( Origin gFrontEnd )
				)
				( attribute "ROOM" "MIO_CHASSIS"
					( Origin gFrontEnd )
				)
				( attribute "ROT" "0"
					( Origin gFrontEnd )
				)
				( attribute "SEC" "1"
					( Origin gFrontEnd )
				)
				( attribute "SEC_TYPE" "0402"
					( Origin gFrontEnd )
				)
				( attribute "TOLERANCE" "1%"
					( Origin gFrontEnd )
				)
				( attribute "VALUE" "200.0"
					( Origin gFrontEnd )
				)
				( attribute "VER" "1"
					( Origin gFrontEnd )
				)
				( attribute "WATTAGE" "1/16W"
					( Origin gFrontEnd )
				)
				( attribute "XY" "(-5650,4175)"
					( Origin gFrontEnd )
				)
				( attribute "CHIPS_PART_NAME" "RES"
					( Origin gPackager )
				)
				( attribute "CDS_PART_NAME" "RES_0402-200.0,1%,1/16W,CHIP,GA"
					( Origin gPackager )
				)
				( objectStatus "R1L31" )
				( pin "a"
					( attribute "PN" "1"
						( Origin gPackager )
					)
					( objectStatus "R1L31.1" )
				)
				( pin "b"
					( attribute "PN" "2"
						( Origin gPackager )
					)
					( objectStatus "R1L31.2" )
				)
			)
			( gate "@baseboard_fab2_lib.baseboard_fab2(sch_1):page175_i5"
				( attribute "BOM_COST" "MIO_CHASSIS"
					( Origin gFrontEnd )
				)
				( attribute "CDS_LIB" "mstr_discrete"
					( Origin gPackager )
				)
				( attribute "CDS_LOCATION" "R1L27"
					( Origin gPackager )
				)
				( attribute "CDS_SEC" "1"
					( Origin gPackager )
				)
				( attribute "LOCATION" "R1L27"
					( Origin gFrontEnd )
				)
				( attribute "MATERIAL" "CHIP"
					( Origin gFrontEnd )
				)
				( attribute "PACK_TYPE" "0402"
					( Origin gFrontEnd )
				)
				( attribute "PART_NUMBER" "G21796-072"
					( Origin gFrontEnd )
				)
				( attribute "PHYS_PAGE" "175"
					( Origin gFrontEnd )
				)
				( attribute "ROOM" "MIO_CHASSIS"
					( Origin gFrontEnd )
				)
				( attribute "ROT" "0"
					( Origin gFrontEnd )
				)
				( attribute "SEC" "1"
					( Origin gFrontEnd )
				)
				( attribute "SEC_TYPE" "0402"
					( Origin gFrontEnd )
				)
				( attribute "TOLERANCE" "1%"
					( Origin gFrontEnd )
				)
				( attribute "VALUE" "4.75K"
					( Origin gFrontEnd )
				)
				( attribute "VER" "2"
					( Origin gFrontEnd )
				)
				( attribute "WATTAGE" "1/16W"
					( Origin gFrontEnd )
				)
				( attribute "XY" "(-5925,4475)"
					( Origin gFrontEnd )
				)
				( attribute "CHIPS_PART_NAME" "RES"
					( Origin gPackager )
				)
				( attribute "CDS_PART_NAME" "RES_0402-4.75K,1%,1/16W,CHIP,GA"
					( Origin gPackager )
				)
				( objectStatus "R1L27" )
				( pin "a"
					( attribute "PN" "1"
						( Origin gPackager )
					)
					( objectStatus "R1L27.1" )
				)
				( pin "b"
					( attribute "PN" "2"
						( Origin gPackager )
					)
					( objectStatus "R1L27.2" )
				)
			)
			( gate "@baseboard_fab2_lib.baseboard_fab2(sch_1):page175_i9"
				( attribute "BOM_COST" "MIO_CHASSIS"
					( Origin gFrontEnd )
				)
				( attribute "CDS_LIB" "mstr_ttl"
					( Origin gPackager )
				)
				( attribute "CDS_LOCATION" "U9A4"
					( Origin gPackager )
				)
				( attribute "CDS_SEC" "1"
					( Origin gPackager )
				)
				( attribute "LOCATION" "U9A4"
					( Origin gFrontEnd )
				)
				( attribute "MATERIAL" "IC"
					( Origin gFrontEnd )
				)
				( attribute "PACK_TYPE" "SMLF"
					( Origin gFrontEnd )
				)
				( attribute "PART_NUMBER" "D18476-001"
					( Origin gFrontEnd )
				)
				( attribute "PHYS_PAGE" "175"
					( Origin gFrontEnd )
				)
				( attribute "ROOM" "MIO_CHASSIS"
					( Origin gFrontEnd )
				)
				( attribute "ROT" "0"
					( Origin gFrontEnd )
				)
				( attribute "SEC" "1"
					( Origin gFrontEnd )
				)
				( attribute "SEC_TYPE" "SMLF"
					( Origin gFrontEnd )
				)
				( attribute "VALUE" "74LVC2G14"
					( Origin gFrontEnd )
				)
				( attribute "VER" "1"
					( Origin gFrontEnd )
				)
				( attribute "XY" "(-4675,4175)"
					( Origin gFrontEnd )
				)
				( attribute "CHIPS_PART_NAME" "TTL2G14"
					( Origin gPackager )
				)
				( attribute "CDS_PART_NAME" "TTL2G14_SMLF-74LVC2G14,IC,D184B"
					( Origin gPackager )
				)
				( objectStatus "U9A4" )
				( pin "a(0)"
					( attribute "PN" "1"
						( Origin gPackager )
					)
					( objectStatus "U9A4.1" )
				)
				( pin "y(0)"
					( attribute "PN" "6"
						( Origin gPackager )
					)
					( objectStatus "U9A4.6" )
				)
			)
			( gate "@baseboard_fab2_lib.baseboard_fab2(sch_1):page175_i10"
				( attribute "BOM_COST" "MIO_CHASSIS"
					( Origin gFrontEnd )
				)
				( attribute "CDS_LIB" "mstr_ttl"
					( Origin gPackager )
				)
				( attribute "CDS_LOCATION" "U9A4"
					( Origin gPackager )
				)
				( attribute "CDS_SEC" "2"
					( Origin gPackager )
				)
				( attribute "LOCATION" "U9A4"
					( Origin gFrontEnd )
				)
				( attribute "MATERIAL" "IC"
					( Origin gFrontEnd )
				)
				( attribute "PACK_TYPE" "SMLF"
					( Origin gFrontEnd )
				)
				( attribute "PART_NUMBER" "D18476-001"
					( Origin gFrontEnd )
				)
				( attribute "PHYS_PAGE" "175"
					( Origin gFrontEnd )
				)
				( attribute "ROOM" "MIO_CHASSIS"
					( Origin gFrontEnd )
				)
				( attribute "ROT" "0"
					( Origin gFrontEnd )
				)
				( attribute "SEC" "2"
					( Origin gFrontEnd )
				)
				( attribute "SEC_TYPE" "SMLF"
					( Origin gFrontEnd )
				)
				( attribute "VALUE" "74LVC2G14"
					( Origin gFrontEnd )
				)
				( attribute "VER" "1"
					( Origin gFrontEnd )
				)
				( attribute "XY" "(-3725,4175)"
					( Origin gFrontEnd )
				)
				( attribute "CHIPS_PART_NAME" "TTL2G14"
					( Origin gPackager )
				)
				( attribute "CDS_PART_NAME" "TTL2G14_SMLF-74LVC2G14,IC,D184B"
					( Origin gPackager )
				)
				( objectStatus "U9A4" )
				( pin "a(0)"
					( attribute "PN" "3"
						( Origin gPackager )
					)
					( objectStatus "U9A4.3" )
				)
				( pin "y(0)"
					( attribute "PN" "4"
						( Origin gPackager )
					)
					( objectStatus "U9A4.4" )
				)
			)
			( gate "@baseboard_fab2_lib.baseboard_fab2(sch_1):page175_i11"
				( attribute "BOM_COST" "MIO_CHASSIS"
					( Origin gFrontEnd )
				)
				( attribute "CDS_LIB" "dev_discrete"
					( Origin gPackager )
				)
				( attribute "CDS_LOCATION" "C1L18"
					( Origin gPackager )
				)
				( attribute "CDS_SEC" "1"
					( Origin gPackager )
				)
				( attribute "LOCATION" "C1L18"
					( Origin gFrontEnd )
				)
				( attribute "MATERIAL" "X6S"
					( Origin gFrontEnd )
				)
				( attribute "PACK_TYPE" "0402V"
					( Origin gFrontEnd )
				)
				( attribute "PART_NUMBER" "D97712-004"
					( Origin gFrontEnd )
				)
				( attribute "PHYS_PAGE" "175"
					( Origin gFrontEnd )
				)
				( attribute "ROOM" "MIO_CHASSIS"
					( Origin gFrontEnd )
				)
				( attribute "ROT" "0"
					( Origin gFrontEnd )
				)
				( attribute "SEC" "1"
					( Origin gFrontEnd )
				)
				( attribute "SEC_TYPE" "0402V"
					( Origin gFrontEnd )
				)
				( attribute "TOLERANCE" "10%"
					( Origin gFrontEnd )
				)
				( attribute "VALUE" "1.0UF"
					( Origin gFrontEnd )
				)
				( attribute "VER" "1"
					( Origin gFrontEnd )
				)
				( attribute "VOLTAGE" "6.3V"
					( Units "uVoltage" "V" 1.000000)
					( Origin gFrontEnd )
				)
				( attribute "XY" "(-4975,3950)"
					( Origin gFrontEnd )
				)
				( attribute "CHIPS_PART_NAME" "CAP_A"
					( Origin gPackager )
				)
				( attribute "CDS_PART_NAME" "CAP_A_0402V-1.0UF,6.3V,10%,X6SA"
					( Origin gPackager )
				)
				( objectStatus "C1L18" )
				( pin "a"
					( attribute "PN" "1"
						( Origin gPackager )
					)
					( objectStatus "C1L18.1" )
				)
				( pin "b"
					( attribute "PN" "2"
						( Origin gPackager )
					)
					( objectStatus "C1L18.2" )
				)
			)
			( gate "@baseboard_fab2_lib.baseboard_fab2(sch_1):page175_i13"
				( attribute "BOM_COST" "MIO_CHASSIS"
					( Origin gFrontEnd )
				)
				( attribute "CDS_LIB" "mstr_discrete"
					( Origin gPackager )
				)
				( attribute "CDS_LOCATION" "R1L26"
					( Origin gPackager )
				)
				( attribute "CDS_SEC" "1"
					( Origin gPackager )
				)
				( attribute "LOCATION" "R1L26"
					( Origin gFrontEnd )
				)
				( attribute "MATERIAL" "CHIP"
					( Origin gFrontEnd )
				)
				( attribute "PACK_TYPE" "0402"
					( Origin gFrontEnd )
				)
				( attribute "PART_NUMBER" "G21796-074"
					( Origin gFrontEnd )
				)
				( attribute "PHYS_PAGE" "175"
					( Origin gFrontEnd )
				)
				( attribute "ROOM" "MIO_CHASSIS"
					( Origin gFrontEnd )
				)
				( attribute "ROT" "0"
					( Origin gFrontEnd )
				)
				( attribute "SEC" "1"
					( Origin gFrontEnd )
				)
				( attribute "SEC_TYPE" "0402"
					( Origin gFrontEnd )
				)
				( attribute "TOLERANCE" "1%"
					( Origin gFrontEnd )
				)
				( attribute "VALUE" "33.2"
					( Origin gFrontEnd )
				)
				( attribute "VER" "1"
					( Origin gFrontEnd )
				)
				( attribute "WATTAGE" "1/16W"
					( Origin gFrontEnd )
				)
				( attribute "XY" "(-2750,4175)"
					( Origin gFrontEnd )
				)
				( attribute "CHIPS_PART_NAME" "RES"
					( Origin gPackager )
				)
				( attribute "CDS_PART_NAME" "RES_0402-33.2,1%,1/16W,CHIP,G2A"
					( Origin gPackager )
				)
				( objectStatus "R1L26" )
				( pin "a"
					( attribute "PN" "1"
						( Origin gPackager )
					)
					( objectStatus "R1L26.1" )
				)
				( pin "b"
					( attribute "PN" "2"
						( Origin gPackager )
					)
					( objectStatus "R1L26.2" )
				)
			)
			( gate "@baseboard_fab2_lib.baseboard_fab2(sch_1):page175_i15"
				( attribute "BOM_COST" "MIO_CHASSIS"
					( Origin gFrontEnd )
				)
				( attribute "CDS_LIB" "mstr_ttl"
					( Origin gPackager )
				)
				( attribute "CDS_LOCATION" "U9A3"
					( Origin gPackager )
				)
				( attribute "CDS_SEC" "2"
					( Origin gPackager )
				)
				( attribute "LOCATION" "U9A3"
					( Origin gFrontEnd )
				)
				( attribute "MATERIAL" "IC"
					( Origin gFrontEnd )
				)
				( attribute "PACK_TYPE" "SMLF"
					( Origin gFrontEnd )
				)
				( attribute "PART_NUMBER" "D18476-001"
					( Origin gFrontEnd )
				)
				( attribute "PHYS_PAGE" "175"
					( Origin gFrontEnd )
				)
				( attribute "ROOM" "MIO_CHASSIS"
					( Origin gFrontEnd )
				)
				( attribute "ROT" "0"
					( Origin gFrontEnd )
				)
				( attribute "SEC" "2"
					( Origin gFrontEnd )
				)
				( attribute "SEC_TYPE" "SMLF"
					( Origin gFrontEnd )
				)
				( attribute "VALUE" "74LVC2G14"
					( Origin gFrontEnd )
				)
				( attribute "VER" "1"
					( Origin gFrontEnd )
				)
				( attribute "XY" "(-3675,2775)"
					( Origin gFrontEnd )
				)
				( attribute "CHIPS_PART_NAME" "TTL2G14"
					( Origin gPackager )
				)
				( attribute "CDS_PART_NAME" "TTL2G14_SMLF-74LVC2G14,IC,D184B"
					( Origin gPackager )
				)
				( objectStatus "U9A3" )
				( pin "a(0)"
					( attribute "PN" "3"
						( Origin gPackager )
					)
					( objectStatus "U9A3.3" )
				)
				( pin "y(0)"
					( attribute "PN" "4"
						( Origin gPackager )
					)
					( objectStatus "U9A3.4" )
				)
			)
			( gate "@baseboard_fab2_lib.baseboard_fab2(sch_1):page175_i18"
				( attribute "BOM_COST" "MIO_CHASSIS"
					( Origin gFrontEnd )
				)
				( attribute "CDS_LIB" "mstr_ttl"
					( Origin gPackager )
				)
				( attribute "CDS_LOCATION" "U9A3"
					( Origin gPackager )
				)
				( attribute "CDS_SEC" "1"
					( Origin gPackager )
				)
				( attribute "LOCATION" "U9A3"
					( Origin gFrontEnd )
				)
				( attribute "MATERIAL" "IC"
					( Origin gFrontEnd )
				)
				( attribute "PACK_TYPE" "SMLF"
					( Origin gFrontEnd )
				)
				( attribute "PART_NUMBER" "D18476-001"
					( Origin gFrontEnd )
				)
				( attribute "PHYS_PAGE" "175"
					( Origin gFrontEnd )
				)
				( attribute "ROOM" "MIO_CHASSIS"
					( Origin gFrontEnd )
				)
				( attribute "ROT" "0"
					( Origin gFrontEnd )
				)
				( attribute "SEC" "1"
					( Origin gFrontEnd )
				)
				( attribute "SEC_TYPE" "SMLF"
					( Origin gFrontEnd )
				)
				( attribute "VALUE" "74LVC2G14"
					( Origin gFrontEnd )
				)
				( attribute "VER" "1"
					( Origin gFrontEnd )
				)
				( attribute "XY" "(-4625,2775)"
					( Origin gFrontEnd )
				)
				( attribute "CHIPS_PART_NAME" "TTL2G14"
					( Origin gPackager )
				)
				( attribute "CDS_PART_NAME" "TTL2G14_SMLF-74LVC2G14,IC,D184B"
					( Origin gPackager )
				)
				( objectStatus "U9A3" )
				( pin "a(0)"
					( attribute "PN" "1"
						( Origin gPackager )
					)
					( objectStatus "U9A3.1" )
				)
				( pin "y(0)"
					( attribute "PN" "6"
						( Origin gPackager )
					)
					( objectStatus "U9A3.6" )
				)
			)
			( gate "@baseboard_fab2_lib.baseboard_fab2(sch_1):page175_i19"
				( attribute "BOM_COST" "MIO_CHASSIS"
					( Origin gFrontEnd )
				)
				( attribute "CDS_LIB" "dev_discrete"
					( Origin gPackager )
				)
				( attribute "CDS_LOCATION" "C1L10"
					( Origin gPackager )
				)
				( attribute "CDS_SEC" "1"
					( Origin gPackager )
				)
				( attribute "LOCATION" "C1L10"
					( Origin gFrontEnd )
				)
				( attribute "MATERIAL" "X6S"
					( Origin gFrontEnd )
				)
				( attribute "PACK_TYPE" "0402V"
					( Origin gFrontEnd )
				)
				( attribute "PART_NUMBER" "D97712-004"
					( Origin gFrontEnd )
				)
				( attribute "PHYS_PAGE" "175"
					( Origin gFrontEnd )
				)
				( attribute "ROOM" "MIO_CHASSIS"
					( Origin gFrontEnd )
				)
				( attribute "ROT" "0"
					( Origin gFrontEnd )
				)
				( attribute "SEC" "1"
					( Origin gFrontEnd )
				)
				( attribute "SEC_TYPE" "0402V"
					( Origin gFrontEnd )
				)
				( attribute "TOLERANCE" "10%"
					( Origin gFrontEnd )
				)
				( attribute "VALUE" "1.0UF"
					( Origin gFrontEnd )
				)
				( attribute "VER" "1"
					( Origin gFrontEnd )
				)
				( attribute "VOLTAGE" "6.3V"
					( Units "uVoltage" "V" 1.000000)
					( Origin gFrontEnd )
				)
				( attribute "XY" "(-4925,2550)"
					( Origin gFrontEnd )
				)
				( attribute "CHIPS_PART_NAME" "CAP_A"
					( Origin gPackager )
				)
				( attribute "CDS_PART_NAME" "CAP_A_0402V-1.0UF,6.3V,10%,X6SA"
					( Origin gPackager )
				)
				( objectStatus "C1L10" )
				( pin "a"
					( attribute "PN" "1"
						( Origin gPackager )
					)
					( objectStatus "C1L10.1" )
				)
				( pin "b"
					( attribute "PN" "2"
						( Origin gPackager )
					)
					( objectStatus "C1L10.2" )
				)
			)
			( gate "@baseboard_fab2_lib.baseboard_fab2(sch_1):page175_i22"
				( attribute "BOM_COST" "MIO_CHASSIS"
					( Origin gFrontEnd )
				)
				( attribute "CDS_LIB" "mstr_discrete"
					( Origin gPackager )
				)
				( attribute "CDS_LOCATION" "R1L22"
					( Origin gPackager )
				)
				( attribute "CDS_SEC" "1"
					( Origin gPackager )
				)
				( attribute "LOCATION" "R1L22"
					( Origin gFrontEnd )
				)
				( attribute "MATERIAL" "CHIP"
					( Origin gFrontEnd )
				)
				( attribute "PACK_TYPE" "0402"
					( Origin gFrontEnd )
				)
				( attribute "PART_NUMBER" "G21796-004"
					( Origin gFrontEnd )
				)
				( attribute "PHYS_PAGE" "175"
					( Origin gFrontEnd )
				)
				( attribute "ROOM" "MIO_CHASSIS"
					( Origin gFrontEnd )
				)
				( attribute "ROT" "0"
					( Origin gFrontEnd )
				)
				( attribute "SEC" "1"
					( Origin gFrontEnd )
				)
				( attribute "SEC_TYPE" "0402"
					( Origin gFrontEnd )
				)
				( attribute "TOLERANCE" "1%"
					( Origin gFrontEnd )
				)
				( attribute "VALUE" "200.0"
					( Origin gFrontEnd )
				)
				( attribute "VER" "1"
					( Origin gFrontEnd )
				)
				( attribute "WATTAGE" "1/16W"
					( Origin gFrontEnd )
				)
				( attribute "XY" "(-5600,2775)"
					( Origin gFrontEnd )
				)
				( attribute "CHIPS_PART_NAME" "RES"
					( Origin gPackager )
				)
				( attribute "CDS_PART_NAME" "RES_0402-200.0,1%,1/16W,CHIP,GA"
					( Origin gPackager )
				)
				( objectStatus "R1L22" )
				( pin "a"
					( attribute "PN" "1"
						( Origin gPackager )
					)
					( objectStatus "R1L22.1" )
				)
				( pin "b"
					( attribute "PN" "2"
						( Origin gPackager )
					)
					( objectStatus "R1L22.2" )
				)
			)
			( gate "@baseboard_fab2_lib.baseboard_fab2(sch_1):page175_i24"
				( attribute "BOM_COST" "MIO_CHASSIS"
					( Origin gFrontEnd )
				)
				( attribute "CDS_LIB" "mstr_discrete"
					( Origin gPackager )
				)
				( attribute "CDS_LOCATION" "R1L19"
					( Origin gPackager )
				)
				( attribute "CDS_SEC" "1"
					( Origin gPackager )
				)
				( attribute "LOCATION" "R1L19"
					( Origin gFrontEnd )
				)
				( attribute "MATERIAL" "EMPTY"
					( Origin gFrontEnd )
				)
				( attribute "PACK_TYPE" "0402"
					( Origin gFrontEnd )
				)
				( attribute "PART_NUMBER" "G21796-072"
					( Origin gFrontEnd )
				)
				( attribute "PHYS_PAGE" "175"
					( Origin gFrontEnd )
				)
				( attribute "ROOM" "MIO_CHASSIS"
					( Origin gFrontEnd )
				)
				( attribute "ROT" "0"
					( Origin gFrontEnd )
				)
				( attribute "SEC" "1"
					( Origin gFrontEnd )
				)
				( attribute "SEC_TYPE" "0402"
					( Origin gFrontEnd )
				)
				( attribute "TOLERANCE" "1%"
					( Origin gFrontEnd )
				)
				( attribute "VALUE" "4.75K"
					( Origin gFrontEnd )
				)
				( attribute "VER" "2"
					( Origin gFrontEnd )
				)
				( attribute "WATTAGE" "1/16W"
					( Origin gFrontEnd )
				)
				( attribute "XY" "(-5875,3075)"
					( Origin gFrontEnd )
				)
				( attribute "CHIPS_PART_NAME" "RES"
					( Origin gPackager )
				)
				( attribute "CDS_PART_NAME" "RES_0402-4.75K,1%,1/16W,EMPTY,A"
					( Origin gPackager )
				)
				( objectStatus "R1L19" )
				( pin "a"
					( attribute "PN" "1"
						( Origin gPackager )
					)
					( objectStatus "R1L19.1" )
				)
				( pin "b"
					( attribute "PN" "2"
						( Origin gPackager )
					)
					( objectStatus "R1L19.2" )
				)
			)
			( gate "@baseboard_fab2_lib.baseboard_fab2(sch_1):page175_i35"
				( attribute "BOM_COST" "MIO_CHASSIS"
					( Origin gFrontEnd )
				)
				( attribute "CDS_LIB" "mstr_discrete"
					( Origin gPackager )
				)
				( attribute "CDS_LOCATION" "R9A9"
					( Origin gPackager )
				)
				( attribute "CDS_SEC" "1"
					( Origin gPackager )
				)
				( attribute "LOCATION" "R9A9"
					( Origin gFrontEnd )
				)
				( attribute "MATERIAL" "CHIP"
					( Origin gFrontEnd )
				)
				( attribute "PACK_TYPE" "0402"
					( Origin gFrontEnd )
				)
				( attribute "PART_NUMBER" "G21796-017"
					( Origin gFrontEnd )
				)
				( attribute "PHYS_PAGE" "175"
					( Origin gFrontEnd )
				)
				( attribute "ROOM" "MIO_CHASSIS"
					( Origin gFrontEnd )
				)
				( attribute "ROT" "0"
					( Origin gFrontEnd )
				)
				( attribute "SEC" "1"
					( Origin gFrontEnd )
				)
				( attribute "SEC_TYPE" "0402"
					( Origin gFrontEnd )
				)
				( attribute "TOLERANCE" "1%"
					( Origin gFrontEnd )
				)
				( attribute "VALUE" "100.0"
					( Origin gFrontEnd )
				)
				( attribute "VER" "1"
					( Origin gFrontEnd )
				)
				( attribute "WATTAGE" "1/16W"
					( Origin gFrontEnd )
				)
				( attribute "XY" "(-2225,2775)"
					( Origin gFrontEnd )
				)
				( attribute "CHIPS_PART_NAME" "RES"
					( Origin gPackager )
				)
				( attribute "CDS_PART_NAME" "RES_0402-100.0,1%,1/16W,CHIP,GA"
					( Origin gPackager )
				)
				( objectStatus "R9A9" )
				( pin "a"
					( attribute "PN" "1"
						( Origin gPackager )
					)
					( objectStatus "R9A9.1" )
				)
				( pin "b"
					( attribute "PN" "2"
						( Origin gPackager )
					)
					( objectStatus "R9A9.2" )
				)
			)
			( gate "@baseboard_fab2_lib.baseboard_fab2(sch_1):page175_i37"
				( attribute "BOM_COST" "MIO_CHASSIS"
					( Origin gFrontEnd )
				)
				( attribute "CDS_LIB" "dev_discrete"
					( Origin gPackager )
				)
				( attribute "CDS_LOCATION" "C1L17"
					( Origin gPackager )
				)
				( attribute "CDS_SEC" "1"
					( Origin gPackager )
				)
				( attribute "LOCATION" "C1L17"
					( Origin gFrontEnd )
				)
				( attribute "MATERIAL" "X7R"
					( Origin gFrontEnd )
				)
				( attribute "PACK_TYPE" "0402V"
					( Origin gFrontEnd )
				)
				( attribute "PART_NUMBER" "A36096-030"
					( Origin gFrontEnd )
				)
				( attribute "PHYS_PAGE" "175"
					( Origin gFrontEnd )
				)
				( attribute "ROOM" "MIO_CHASSIS"
					( Origin gFrontEnd )
				)
				( attribute "ROT" "0"
					( Origin gFrontEnd )
				)
				( attribute "SEC" "1"
					( Origin gFrontEnd )
				)
				( attribute "SEC_TYPE" "0402V"
					( Origin gFrontEnd )
				)
				( attribute "TOLERANCE" "10%"
					( Origin gFrontEnd )
				)
				( attribute "VALUE" "0.1UF"
					( Origin gFrontEnd )
				)
				( attribute "VER" "1"
					( Origin gFrontEnd )
				)
				( attribute "VOLTAGE" "16V"
					( Units "uVoltage" "V" 1.000000)
					( Origin gFrontEnd )
				)
				( attribute "XY" "(-4400,4675)"
					( Origin gFrontEnd )
				)
				( attribute "CHIPS_PART_NAME" "CAP_A"
					( Origin gPackager )
				)
				( attribute "CDS_PART_NAME" "CAP_A_0402V-0.1UF,16V,10%,X7R,A"
					( Origin gPackager )
				)
				( objectStatus "C1L17" )
				( pin "a"
					( attribute "PN" "1"
						( Origin gPackager )
					)
					( objectStatus "C1L17.1" )
				)
				( pin "b"
					( attribute "PN" "2"
						( Origin gPackager )
					)
					( objectStatus "C1L17.2" )
				)
			)
			( gate "@baseboard_fab2_lib.baseboard_fab2(sch_1):page175_i38"
				( attribute "BOM_COST" "MIO_CHASSIS"
					( Origin gFrontEnd )
				)
				( attribute "CDS_LIB" "dev_discrete"
					( Origin gPackager )
				)
				( attribute "CDS_LOCATION" "C1L9"
					( Origin gPackager )
				)
				( attribute "CDS_SEC" "1"
					( Origin gPackager )
				)
				( attribute "LOCATION" "C1L9"
					( Origin gFrontEnd )
				)
				( attribute "MATERIAL" "X7R"
					( Origin gFrontEnd )
				)
				( attribute "PACK_TYPE" "0402V"
					( Origin gFrontEnd )
				)
				( attribute "PART_NUMBER" "A36096-030"
					( Origin gFrontEnd )
				)
				( attribute "PHYS_PAGE" "175"
					( Origin gFrontEnd )
				)
				( attribute "ROOM" "MIO_CHASSIS"
					( Origin gFrontEnd )
				)
				( attribute "ROT" "0"
					( Origin gFrontEnd )
				)
				( attribute "SEC" "1"
					( Origin gFrontEnd )
				)
				( attribute "SEC_TYPE" "0402V"
					( Origin gFrontEnd )
				)
				( attribute "TOLERANCE" "10%"
					( Origin gFrontEnd )
				)
				( attribute "VALUE" "0.1UF"
					( Origin gFrontEnd )
				)
				( attribute "VER" "1"
					( Origin gFrontEnd )
				)
				( attribute "VOLTAGE" "16V"
					( Units "uVoltage" "V" 1.000000)
					( Origin gFrontEnd )
				)
				( attribute "XY" "(-4500,3350)"
					( Origin gFrontEnd )
				)
				( attribute "CHIPS_PART_NAME" "CAP_A"
					( Origin gPackager )
				)
				( attribute "CDS_PART_NAME" "CAP_A_0402V-0.1UF,16V,10%,X7R,A"
					( Origin gPackager )
				)
				( objectStatus "C1L9" )
				( pin "a"
					( attribute "PN" "1"
						( Origin gPackager )
					)
					( objectStatus "C1L9.1" )
				)
				( pin "b"
					( attribute "PN" "2"
						( Origin gPackager )
					)
					( objectStatus "C1L9.2" )
				)
			)
			( gate "@baseboard_fab2_lib.baseboard_fab2(sch_1):page175_i40"
				( attribute "BOM_COST" "MIO_CHASSIS"
					( Origin gFrontEnd )
				)
				( attribute "CDS_LIB" "dev_discrete"
					( Origin gPackager )
				)
				( attribute "CDS_LOCATION" "C9A3"
					( Origin gPackager )
				)
				( attribute "CDS_SEC" "1"
					( Origin gPackager )
				)
				( attribute "LOCATION" "C9A3"
					( Origin gFrontEnd )
				)
				( attribute "MATERIAL" "X7R"
					( Origin gFrontEnd )
				)
				( attribute "PACK_TYPE" "0402V"
					( Origin gFrontEnd )
				)
				( attribute "PART_NUMBER" "A36096-030"
					( Origin gFrontEnd )
				)
				( attribute "PHYS_PAGE" "175"
					( Origin gFrontEnd )
				)
				( attribute "ROOM" "MIO_CHASSIS"
					( Origin gFrontEnd )
				)
				( attribute "ROT" "0"
					( Origin gFrontEnd )
				)
				( attribute "SEC" "1"
					( Origin gFrontEnd )
				)
				( attribute "SEC_TYPE" "0402V"
					( Origin gFrontEnd )
				)
				( attribute "TOLERANCE" "10%"
					( Origin gFrontEnd )
				)
				( attribute "VALUE" "0.1UF"
					( Origin gFrontEnd )
				)
				( attribute "VER" "1"
					( Origin gFrontEnd )
				)
				( attribute "VOLTAGE" "16V"
					( Units "uVoltage" "V" 1.000000)
					( Origin gFrontEnd )
				)
				( attribute "XY" "(-575,3500)"
					( Origin gFrontEnd )
				)
				( attribute "CHIPS_PART_NAME" "CAP_A"
					( Origin gPackager )
				)
				( attribute "CDS_PART_NAME" "CAP_A_0402V-0.1UF,16V,10%,X7R,A"
					( Origin gPackager )
				)
				( objectStatus "C9A3" )
				( pin "a"
					( attribute "PN" "1"
						( Origin gPackager )
					)
					( objectStatus "C9A3.1" )
				)
				( pin "b"
					( attribute "PN" "2"
						( Origin gPackager )
					)
					( objectStatus "C9A3.2" )
				)
			)
			( gate "@baseboard_fab2_lib.baseboard_fab2(sch_1):page175_i45"
				( attribute "BOM_COST" "MIO_CHASSIS"
					( Origin gFrontEnd )
				)
				( attribute "CDS_LIB" "mstr_discrete"
					( Origin gPackager )
				)
				( attribute "CDS_LOCATION" "R1L33"
					( Origin gPackager )
				)
				( attribute "CDS_SEC" "1"
					( Origin gPackager )
				)
				( attribute "LOCATION" "R1L33"
					( Origin gFrontEnd )
				)
				( attribute "MATERIAL" "CHIP"
					( Origin gFrontEnd )
				)
				( attribute "PACK_TYPE" "0402"
					( Origin gFrontEnd )
				)
				( attribute "PART_NUMBER" "G21796-271"
					( Origin gFrontEnd )
				)
				( attribute "PHYS_PAGE" "175"
					( Origin gFrontEnd )
				)
				( attribute "ROOM" "MIO_CHASSIS"
					( Origin gFrontEnd )
				)
				( attribute "ROT" "0"
					( Origin gFrontEnd )
				)
				( attribute "SEC" "1"
					( Origin gFrontEnd )
				)
				( attribute "SEC_TYPE" "0402"
					( Origin gFrontEnd )
				)
				( attribute "TOLERANCE" "1.0%"
					( Origin gFrontEnd )
				)
				( attribute "VALUE" "221"
					( Origin gFrontEnd )
				)
				( attribute "VER" "1"
					( Origin gFrontEnd )
				)
				( attribute "WATTAGE" "1/16W"
					( Origin gFrontEnd )
				)
				( attribute "XY" "(-4000,1550)"
					( Origin gFrontEnd )
				)
				( attribute "CHIPS_PART_NAME" "RES"
					( Origin gPackager )
				)
				( attribute "CDS_PART_NAME" "RES_0402-221,1.0%,1/16W,CHIP,GA"
					( Origin gPackager )
				)
				( objectStatus "R1L33" )
				( pin "a"
					( attribute "PN" "1"
						( Origin gPackager )
					)
					( objectStatus "R1L33.1" )
				)
				( pin "b"
					( attribute "PN" "2"
						( Origin gPackager )
					)
					( objectStatus "R1L33.2" )
				)
			)
			( gate "@baseboard_fab2_lib.baseboard_fab2(sch_1):page175_i49"
				( attribute "BOM_COST" "MIO_CHASSIS"
					( Origin gFrontEnd )
				)
				( attribute "CDS_LIB" "mstr_discrete"
					( Origin gPackager )
				)
				( attribute "CDS_LOCATION" "Q9A3"
					( Origin gPackager )
				)
				( attribute "LOCATION" "Q9A3"
					( Origin gFrontEnd )
				)
				( attribute "MATERIAL" "FET"
					( Origin gFrontEnd )
				)
				( attribute "PACK_TYPE" "SOT23LF"
					( Origin gFrontEnd )
				)
				( attribute "PART_NUMBER" "C79254-001"
					( Origin gFrontEnd )
				)
				( attribute "PHYS_PAGE" "175"
					( Origin gFrontEnd )
				)
				( attribute "ROOM" "MIO_CHASSIS"
					( Origin gFrontEnd )
				)
				( attribute "ROT" "0"
					( Origin gFrontEnd )
				)
				( attribute "SEC" "1"
					( Origin gFrontEnd )
				)
				( attribute "SEC_TYPE" "SOT23LF"
					( Origin gFrontEnd )
				)
				( attribute "VALUE" "2N7002"
					( Origin gFrontEnd )
				)
				( attribute "VER" "8"
					( Origin gFrontEnd )
				)
				( attribute "XY" "(-5025,1175)"
					( Origin gFrontEnd )
				)
				( attribute "CHIPS_PART_NAME" "FET_N"
					( Origin gPackager )
				)
				( attribute "CDS_PART_NAME" "FET_N_SOT23LF-2N7002,FET,C7925A"
					( Origin gPackager )
				)
				( attribute "CDS_SEC" "1"
					( Origin gPackager )
				)
				( objectStatus "Q9A3" )
				( pin "drn"
					( attribute "PN" "3"
						( Origin gPackager )
					)
					( objectStatus "Q9A3.3" )
				)
				( pin "gate"
					( attribute "PN" "1"
						( Origin gPackager )
					)
					( objectStatus "Q9A3.1" )
				)
				( pin "src"
					( attribute "PN" "2"
						( Origin gPackager )
					)
					( objectStatus "Q9A3.2" )
				)
			)
			( gate "@baseboard_fab2_lib.baseboard_fab2(sch_1):page175_i50"
				( attribute "BOM_COST" "MIO_CHASSIS"
					( Origin gFrontEnd )
				)
				( attribute "CDS_LIB" "mstr_discrete"
					( Origin gPackager )
				)
				( attribute "CDS_LOCATION" "DS9A1"
					( Origin gPackager )
				)
				( attribute "CDS_SEC" "1"
					( Origin gPackager )
				)
				( attribute "COLOR" "BLUE"
					( Origin gFrontEnd )
				)
				( attribute "LOCATION" "DS9A1"
					( Origin gFrontEnd )
				)
				( attribute "MATERIAL" "IC"
					( Origin gFrontEnd )
				)
				( attribute "PACK_TYPE" "1NC"
					( Origin gFrontEnd )
				)
				( attribute "PART_NUMBER" "C96565-012"
					( Origin gFrontEnd )
				)
				( attribute "PHYS_PAGE" "175"
					( Origin gFrontEnd )
				)
				( attribute "ROOM" "MIO_CHASSIS"
					( Origin gFrontEnd )
				)
				( attribute "ROT" "0"
					( Origin gFrontEnd )
				)
				( attribute "SEC" "1"
					( Origin gPackager )
				)
				( attribute "VER" "3"
					( Origin gFrontEnd )
				)
				( attribute "XY" "(-1700,1025)"
					( Origin gFrontEnd )
				)
				( attribute "CHIPS_PART_NAME" "LED"
					( Origin gPackager )
				)
				( attribute "CDS_PART_NAME" "LED_1NC-BLUE,IC,C96565-012"
					( Origin gPackager )
				)
				( objectStatus "DS9A1" )
				( pin "a"
					( attribute "PN" "2"
						( Origin gPackager )
					)
					( objectStatus "DS9A1.2" )
				)
				( pin "c"
					( attribute "PN" "1"
						( Origin gPackager )
					)
					( objectStatus "DS9A1.1" )
				)
			)
			( gate "@baseboard_fab2_lib.baseboard_fab2(sch_1):page175_i57"
				( attribute "BOM_COST" "MIO_CHASSIS"
					( Origin gFrontEnd )
				)
				( attribute "CDS_LIB" "mstr_ttl"
					( Origin gPackager )
				)
				( attribute "CDS_LOCATION" "U1L2"
					( Origin gPackager )
				)
				( attribute "CDS_SEC" "1"
					( Origin gPackager )
				)
				( attribute "LOCATION" "U1L2"
					( Origin gFrontEnd )
				)
				( attribute "MATERIAL" "IC"
					( Origin gFrontEnd )
				)
				( attribute "PACK_TYPE" "SOTLF"
					( Origin gFrontEnd )
				)
				( attribute "PART_NUMBER" "D39848-001"
					( Origin gFrontEnd )
				)
				( attribute "PHYS_PAGE" "175"
					( Origin gFrontEnd )
				)
				( attribute "ROOM" "MIO_CHASSIS"
					( Origin gFrontEnd )
				)
				( attribute "ROT" "0"
					( Origin gFrontEnd )
				)
				( attribute "SEC" "1"
					( Origin gPackager )
				)
				( attribute "VALUE" "74AHCT1G86"
					( Origin gFrontEnd )
				)
				( attribute "VER" "1"
					( Origin gFrontEnd )
				)
				( attribute "XY" "(-2750,1025)"
					( Origin gFrontEnd )
				)
				( attribute "CHIPS_PART_NAME" "TTL1G86"
					( Origin gPackager )
				)
				( attribute "CDS_PART_NAME" "TTL1G86_SOTLF-74AHCT1G86,IC,D3B"
					( Origin gPackager )
				)
				( objectStatus "U1L2" )
				( pin "a"
					( attribute "PN" "1"
						( Origin gPackager )
					)
					( objectStatus "U1L2.1" )
				)
				( pin "b"
					( attribute "PN" "2"
						( Origin gPackager )
					)
					( objectStatus "U1L2.2" )
				)
				( pin "y"
					( attribute "PN" "4"
						( Origin gPackager )
					)
					( objectStatus "U1L2.4" )
				)
			)
			( gate "@baseboard_fab2_lib.baseboard_fab2(sch_1):page175_i58"
				( attribute "BOM_COST" "MIO_CHASSIS"
					( Origin gFrontEnd )
				)
				( attribute "CDS_LIB" "mstr_discrete"
					( Origin gPackager )
				)
				( attribute "CDS_LOCATION" "R1L8"
					( Origin gPackager )
				)
				( attribute "CDS_SEC" "1"
					( Origin gPackager )
				)
				( attribute "LOCATION" "R1L8"
					( Origin gFrontEnd )
				)
				( attribute "MATERIAL" "CHIP"
					( Origin gFrontEnd )
				)
				( attribute "PACK_TYPE" "0402"
					( Origin gFrontEnd )
				)
				( attribute "PART_NUMBER" "G21497-024"
					( Origin gFrontEnd )
				)
				( attribute "PHYS_PAGE" "175"
					( Origin gFrontEnd )
				)
				( attribute "ROOM" "MIO_CHASSIS"
					( Origin gFrontEnd )
				)
				( attribute "ROT" "0"
					( Origin gFrontEnd )
				)
				( attribute "SEC" "1"
					( Origin gFrontEnd )
				)
				( attribute "SEC_TYPE" "0402"
					( Origin gFrontEnd )
				)
				( attribute "TOLERANCE" "5%"
					( Origin gFrontEnd )
				)
				( attribute "VALUE" "470.0"
					( Origin gFrontEnd )
				)
				( attribute "VER" "2"
					( Origin gFrontEnd )
				)
				( attribute "WATTAGE" "1/16W"
					( Origin gFrontEnd )
				)
				( attribute "XY" "(-1175,1350)"
					( Origin gFrontEnd )
				)
				( attribute "CHIPS_PART_NAME" "RES"
					( Origin gPackager )
				)
				( attribute "CDS_PART_NAME" "RES_0402-470.0,5%,1/16W,CHIP,GA"
					( Origin gPackager )
				)
				( objectStatus "R1L8" )
				( pin "a"
					( attribute "PN" "1"
						( Origin gPackager )
					)
					( objectStatus "R1L8.1" )
				)
				( pin "b"
					( attribute "PN" "2"
						( Origin gPackager )
					)
					( objectStatus "R1L8.2" )
				)
			)
			( gate "@baseboard_fab2_lib.baseboard_fab2(sch_1):page175_i63"
				( attribute "BOM_COST" "MIO_CHASSIS"
					( Origin gFrontEnd )
				)
				( attribute "CDS_LIB" "mstr_discrete"
					( Origin gPackager )
				)
				( attribute "CDS_LOCATION" "R1L12"
					( Origin gPackager )
				)
				( attribute "CDS_SEC" "1"
					( Origin gPackager )
				)
				( attribute "LOCATION" "R1L12"
					( Origin gFrontEnd )
				)
				( attribute "MATERIAL" "CHIP"
					( Origin gFrontEnd )
				)
				( attribute "PACK_TYPE" "0402"
					( Origin gFrontEnd )
				)
				( attribute "PART_NUMBER" "G21497-005"
					( Origin gFrontEnd )
				)
				( attribute "PHYS_PAGE" "175"
					( Origin gFrontEnd )
				)
				( attribute "ROOM" "MIO_CHASSIS"
					( Origin gFrontEnd )
				)
				( attribute "ROT" "0"
					( Origin gFrontEnd )
				)
				( attribute "SEC" "1"
					( Origin gFrontEnd )
				)
				( attribute "SEC_TYPE" "0402"
					( Origin gFrontEnd )
				)
				( attribute "TOLERANCE" "5%"
					( Origin gFrontEnd )
				)
				( attribute "VALUE" "0.0"
					( Origin gFrontEnd )
				)
				( attribute "VER" "1"
					( Origin gFrontEnd )
				)
				( attribute "WATTAGE" "1/16W"
					( Origin gFrontEnd )
				)
				( attribute "XY" "(-3525,1075)"
					( Origin gFrontEnd )
				)
				( attribute "CHIPS_PART_NAME" "RES"
					( Origin gPackager )
				)
				( attribute "CDS_PART_NAME" "RES_0402-0.0,5%,1/16W,CHIP,G21A"
					( Origin gPackager )
				)
				( objectStatus "R1L12" )
				( pin "a"
					( attribute "PN" "1"
						( Origin gPackager )
					)
					( objectStatus "R1L12.1" )
				)
				( pin "b"
					( attribute "PN" "2"
						( Origin gPackager )
					)
					( objectStatus "R1L12.2" )
				)
			)
			( gate "@baseboard_fab2_lib.baseboard_fab2(sch_1):page175_i64"
				( attribute "BOM_COST" "MIO_CHASSIS"
					( Origin gFrontEnd )
				)
				( attribute "CDS_LIB" "dev_discrete"
					( Origin gPackager )
				)
				( attribute "CDS_LOCATION" "C1L4"
					( Origin gPackager )
				)
				( attribute "CDS_SEC" "1"
					( Origin gPackager )
				)
				( attribute "LOCATION" "C1L4"
					( Origin gFrontEnd )
				)
				( attribute "MATERIAL" "X7R"
					( Origin gFrontEnd )
				)
				( attribute "PACK_TYPE" "0402V"
					( Origin gFrontEnd )
				)
				( attribute "PART_NUMBER" "A36096-030"
					( Origin gFrontEnd )
				)
				( attribute "PHYS_PAGE" "175"
					( Origin gFrontEnd )
				)
				( attribute "ROOM" "MIO_CHASSIS"
					( Origin gFrontEnd )
				)
				( attribute "ROT" "0"
					( Origin gFrontEnd )
				)
				( attribute "SEC" "1"
					( Origin gFrontEnd )
				)
				( attribute "SEC_TYPE" "0402V"
					( Origin gFrontEnd )
				)
				( attribute "TOLERANCE" "10%"
					( Origin gFrontEnd )
				)
				( attribute "VALUE" "0.1UF"
					( Origin gFrontEnd )
				)
				( attribute "VER" "1"
					( Origin gFrontEnd )
				)
				( attribute "VOLTAGE" "16V"
					( Units "uVoltage" "V" 1.000000)
					( Origin gFrontEnd )
				)
				( attribute "XY" "(-2900,1725)"
					( Origin gFrontEnd )
				)
				( attribute "CHIPS_PART_NAME" "CAP_A"
					( Origin gPackager )
				)
				( attribute "CDS_PART_NAME" "CAP_A_0402V-0.1UF,16V,10%,X7R,A"
					( Origin gPackager )
				)
				( objectStatus "C1L4" )
				( pin "a"
					( attribute "PN" "1"
						( Origin gPackager )
					)
					( objectStatus "C1L4.1" )
				)
				( pin "b"
					( attribute "PN" "2"
						( Origin gPackager )
					)
					( objectStatus "C1L4.2" )
				)
			)
			( gate "@baseboard_fab2_lib.baseboard_fab2(sch_1):page175_i67"
				( attribute "BOM_COST" "MIO_CHASSIS"
					( Origin gFrontEnd )
				)
				( attribute "CDS_LIB" "mstr_discrete"
					( Origin gPackager )
				)
				( attribute "CDS_LOCATION" "DS9A3"
					( Origin gPackager )
				)
				( attribute "CDS_SEC" "1"
					( Origin gPackager )
				)
				( attribute "COLOR" "YELLOW"
					( Origin gFrontEnd )
				)
				( attribute "LOCATION" "DS9A3"
					( Origin gFrontEnd )
				)
				( attribute "MATERIAL" "IC"
					( Origin gFrontEnd )
				)
				( attribute "PACK_TYPE" "1NCLF"
					( Origin gFrontEnd )
				)
				( attribute "PART_NUMBER" "C96565-003"
					( Origin gFrontEnd )
				)
				( attribute "PHYS_PAGE" "175"
					( Origin gFrontEnd )
				)
				( attribute "ROOM" "MIO_CHASSIS"
					( Origin gFrontEnd )
				)
				( attribute "ROT" "0"
					( Origin gFrontEnd )
				)
				( attribute "SEC" "1"
					( Origin gFrontEnd )
				)
				( attribute "SEC_TYPE" "1NCLF"
					( Origin gFrontEnd )
				)
				( attribute "VER" "3"
					( Origin gFrontEnd )
				)
				( attribute "XY" "(-4600,1550)"
					( Origin gFrontEnd )
				)
				( attribute "CHIPS_PART_NAME" "LED"
					( Origin gPackager )
				)
				( attribute "CDS_PART_NAME" "LED_1NCLF-YELLOW,IC,C96565-003"
					( Origin gPackager )
				)
				( objectStatus "DS9A3" )
				( pin "a"
					( attribute "PN" "2"
						( Origin gPackager )
					)
					( objectStatus "DS9A3.2" )
				)
				( pin "c"
					( attribute "PN" "1"
						( Origin gPackager )
					)
					( objectStatus "DS9A3.1" )
				)
			)
			( gate "@baseboard_fab2_lib.baseboard_fab2(sch_1):page175_i78"
				( attribute "BOM_COST" "MIO_CHASSIS"
					( Origin gFrontEnd )
				)
				( attribute "CDS_LIB" "mstr_misc"
					( Origin gPackager )
				)
				( attribute "CDS_LMAN_SYM_OUTLINE" "-100,125,100,-75"
					( Origin gPackager )
				)
				( attribute "CDS_LOCATION" "S9A1"
					( Origin gPackager )
				)
				( attribute "CDS_SEC" "1"
					( Origin gPackager )
				)
				( attribute "LOCATION" "S9A1"
					( Origin gFrontEnd )
				)
				( attribute "MATERIAL" "IC"
					( Origin gFrontEnd )
				)
				( attribute "PACK_TYPE" "SM"
					( Origin gFrontEnd )
				)
				( attribute "PART_NUMBER" "D37771-002"
					( Origin gFrontEnd )
				)
				( attribute "PHYS_PAGE" "175"
					( Origin gFrontEnd )
				)
				( attribute "ROOM" "MIO_CHASSIS"
					( Origin gFrontEnd )
				)
				( attribute "ROT" "3"
					( Origin gFrontEnd )
				)
				( attribute "SEC" "1"
					( Origin gFrontEnd )
				)
				( attribute "SEC_TYPE" "SM"
					( Origin gFrontEnd )
				)
				( attribute "VER" "1"
					( Origin gFrontEnd )
				)
				( attribute "XY" "(-7075,2675)"
					( Origin gFrontEnd )
				)
				( attribute "CHIPS_PART_NAME" "SWITCH_D37771002"
					( Origin gPackager )
				)
				( attribute "CDS_PART_NAME" "SWITCH_D37771002_SM-IC,D37771-A"
					( Origin gPackager )
				)
				( objectStatus "S9A1" )
				( pin "pin1"
					( attribute "PN" "1"
						( Origin gPackager )
					)
					( objectStatus "S9A1.1" )
				)
				( pin "pin2"
					( attribute "PN" "2"
						( Origin gPackager )
					)
					( objectStatus "S9A1.2" )
				)
				( pin "pin3"
					( attribute "PN" "3"
						( Origin gPackager )
					)
					( objectStatus "S9A1.3" )
				)
				( pin "pin4"
					( attribute "PN" "4"
						( Origin gPackager )
					)
					( objectStatus "S9A1.4" )
				)
			)
			( gate "@baseboard_fab2_lib.baseboard_fab2(sch_1):page175_i84"
				( attribute "BOM_COST" "MIO_CHASSIS"
					( Origin gFrontEnd )
				)
				( attribute "CDS_LIB" "mstr_misc"
					( Origin gPackager )
				)
				( attribute "CDS_LMAN_SYM_OUTLINE" "-200,200,200,-200"
					( Origin gPackager )
				)
				( attribute "CDS_LOCATION" "S9A2"
					( Origin gPackager )
				)
				( attribute "CDS_SEC" "1"
					( Origin gPackager )
				)
				( attribute "LOCATION" "S9A2"
					( Origin gFrontEnd )
				)
				( attribute "MATERIAL" "IC"
					( Origin gFrontEnd )
				)
				( attribute "PACK_TYPE" "SM"
					( Origin gFrontEnd )
				)
				( attribute "PART_NUMBER" "H67881-001"
					( Origin gFrontEnd )
				)
				( attribute "PHYS_PAGE" "175"
					( Origin gFrontEnd )
				)
				( attribute "ROOM" "MIO_CHASSIS"
					( Origin gFrontEnd )
				)
				( attribute "ROT" "0"
					( Origin gFrontEnd )
				)
				( attribute "SEC" "1"
					( Origin gPackager )
				)
				( attribute "VER" "1"
					( Origin gFrontEnd )
				)
				( attribute "XY" "(-7150,4075)"
					( Origin gFrontEnd )
				)
				( attribute "CHIPS_PART_NAME" "SW_H67881001"
					( Origin gPackager )
				)
				( attribute "CDS_PART_NAME" "SW_H67881001_SM-IC,H67881-001"
					( Origin gPackager )
				)
				( objectStatus "S9A2" )
				( pin "io1"
					( attribute "PN" "1"
						( Origin gPackager )
					)
					( objectStatus "S9A2.1" )
				)
				( pin "io2"
					( attribute "PN" "2"
						( Origin gPackager )
					)
					( objectStatus "S9A2.2" )
				)
				( pin "io3"
					( attribute "PN" "3"
						( Origin gPackager )
					)
					( objectStatus "S9A2.3" )
				)
				( pin "io4"
					( attribute "PN" "4"
						( Origin gPackager )
					)
					( objectStatus "S9A2.4" )
				)
			)
			( gate "@baseboard_fab2_lib.baseboard_fab2(sch_1):page176_i16"
				( attribute "BOM_COST" "MIO_USB"
					( Origin gFrontEnd )
				)
				( attribute "CDS_LIB" "mstr_discrete"
					( Origin gPackager )
				)
				( attribute "CDS_LOCATION" "R1M5"
					( Origin gPackager )
				)
				( attribute "CDS_SEC" "1"
					( Origin gPackager )
				)
				( attribute "LOCATION" "R1M5"
					( Origin gFrontEnd )
				)
				( attribute "MATERIAL" "CHIP"
					( Origin gFrontEnd )
				)
				( attribute "PACK_TYPE" "0402"
					( Origin gFrontEnd )
				)
				( attribute "PART_NUMBER" "G21497-005"
					( Origin gFrontEnd )
				)
				( attribute "PHYS_PAGE" "176"
					( Origin gFrontEnd )
				)
				( attribute "ROOM" "USB_REAR"
					( Origin gFrontEnd )
				)
				( attribute "ROT" "0"
					( Origin gFrontEnd )
				)
				( attribute "SEC" "1"
					( Origin gFrontEnd )
				)
				( attribute "SEC_TYPE" "0402"
					( Origin gFrontEnd )
				)
				( attribute "TOLERANCE" "5%"
					( Origin gFrontEnd )
				)
				( attribute "VALUE" "0.0"
					( Origin gFrontEnd )
				)
				( attribute "VER" "1"
					( Origin gFrontEnd )
				)
				( attribute "WATTAGE" "1/16W"
					( Origin gFrontEnd )
				)
				( attribute "XY" "(-5300,4375)"
					( Origin gFrontEnd )
				)
				( attribute "CHIPS_PART_NAME" "RES"
					( Origin gPackager )
				)
				( attribute "CDS_PART_NAME" "RES_0402-0.0,5%,1/16W,CHIP,G21A"
					( Origin gPackager )
				)
				( objectStatus "R1M5" )
				( pin "a"
					( attribute "PN" "1"
						( Origin gPackager )
					)
					( objectStatus "R1M5.1" )
				)
				( pin "b"
					( attribute "PN" "2"
						( Origin gPackager )
					)
					( objectStatus "R1M5.2" )
				)
			)
			( gate "@baseboard_fab2_lib.baseboard_fab2(sch_1):page176_i30"
				( attribute "BOM_COST" "MIO_USB"
					( Origin gFrontEnd )
				)
				( attribute "CDS_LIB" "mstr_discrete"
					( Origin gPackager )
				)
				( attribute "CDS_LOCATION" "L1M2"
					( Origin gPackager )
				)
				( attribute "CDS_SEC" "1"
					( Origin gPackager )
				)
				( attribute "LOCATION" "L1M2"
					( Origin gFrontEnd )
				)
				( attribute "MATERIAL" "EMPTY"
					( Origin gFrontEnd )
				)
				( attribute "PACK_TYPE" "SMLF"
					( Origin gFrontEnd )
				)
				( attribute "PART_NUMBER" "752402-015"
					( Origin gFrontEnd )
				)
				( attribute "PHYS_PAGE" "176"
					( Origin gFrontEnd )
				)
				( attribute "ROOM" "USB_REAR"
					( Origin gFrontEnd )
				)
				( attribute "ROT" "0"
					( Origin gFrontEnd )
				)
				( attribute "SEC" "1"
					( Origin gFrontEnd )
				)
				( attribute "SEC_TYPE" "SMLF"
					( Origin gFrontEnd )
				)
				( attribute "VALUE" "90 OHM"
					( Origin gFrontEnd )
				)
				( attribute "VER" "1"
					( Origin gFrontEnd )
				)
				( attribute "XY" "(-5250,4725)"
					( Origin gFrontEnd )
				)
				( attribute "CHIPS_PART_NAME" "CHOKE_4PIN"
					( Origin gPackager )
				)
				( attribute "CDS_PART_NAME" "CHOKE_4PIN_SMLF-90 OHM,EMPTY,7A"
					( Origin gPackager )
				)
				( objectStatus "L1M2" )
				( pin "a1"
					( attribute "PN" "1"
						( Origin gPackager )
					)
					( objectStatus "L1M2.1" )
				)
				( pin "a2"
					( attribute "PN" "2"
						( Origin gPackager )
					)
					( objectStatus "L1M2.2" )
				)
				( pin "b1"
					( attribute "PN" "3"
						( Origin gPackager )
					)
					( objectStatus "L1M2.3" )
				)
				( pin "b2"
					( attribute "PN" "4"
						( Origin gPackager )
					)
					( objectStatus "L1M2.4" )
				)
			)
			( gate "@baseboard_fab2_lib.baseboard_fab2(sch_1):page176_i31"
				( attribute "BOM_COST" "MIO_USB"
					( Origin gFrontEnd )
				)
				( attribute "CDS_LIB" "mstr_discrete"
					( Origin gPackager )
				)
				( attribute "CDS_LOCATION" "R1M6"
					( Origin gPackager )
				)
				( attribute "CDS_SEC" "1"
					( Origin gPackager )
				)
				( attribute "LOCATION" "R1M6"
					( Origin gFrontEnd )
				)
				( attribute "MATERIAL" "CHIP"
					( Origin gFrontEnd )
				)
				( attribute "PACK_TYPE" "0402"
					( Origin gFrontEnd )
				)
				( attribute "PART_NUMBER" "G21497-005"
					( Origin gFrontEnd )
				)
				( attribute "PHYS_PAGE" "176"
					( Origin gFrontEnd )
				)
				( attribute "ROOM" "USB"
					( Origin gFrontEnd )
				)
				( attribute "ROT" "0"
					( Origin gFrontEnd )
				)
				( attribute "SEC" "1"
					( Origin gFrontEnd )
				)
				( attribute "SEC_TYPE" "0402"
					( Origin gFrontEnd )
				)
				( attribute "TOLERANCE" "5%"
					( Origin gFrontEnd )
				)
				( attribute "VALUE" "0.0"
					( Origin gFrontEnd )
				)
				( attribute "VER" "1"
					( Origin gFrontEnd )
				)
				( attribute "WATTAGE" "1/16W"
					( Origin gFrontEnd )
				)
				( attribute "XY" "(-5300,5200)"
					( Origin gFrontEnd )
				)
				( attribute "CHIPS_PART_NAME" "RES"
					( Origin gPackager )
				)
				( attribute "CDS_PART_NAME" "RES_0402-0.0,5%,1/16W,CHIP,G21A"
					( Origin gPackager )
				)
				( objectStatus "R1M6" )
				( pin "a"
					( attribute "PN" "1"
						( Origin gPackager )
					)
					( objectStatus "R1M6.1" )
				)
				( pin "b"
					( attribute "PN" "2"
						( Origin gPackager )
					)
					( objectStatus "R1M6.2" )
				)
			)
			( gate "@baseboard_fab2_lib.baseboard_fab2(sch_1):page176_i69"
				( attribute "CDS_LIB" "mstr_conn"
					( Origin gPackager )
				)
				( attribute "CDS_LOCATION" "J9B1"
					( Origin gPackager )
				)
				( attribute "CDS_SEC" "1"
					( Origin gPackager )
				)
				( attribute "LOCATION" "J9B1"
					( Origin gFrontEnd )
				)
				( attribute "MATERIAL" "CONN"
					( Origin gFrontEnd )
				)
				( attribute "PACK_TYPE" "PIP2"
					( Origin gFrontEnd )
				)
				( attribute "PART_NUMBER" "H51826-001"
					( Origin gFrontEnd )
				)
				( attribute "PHYS_PAGE" "176"
					( Origin gFrontEnd )
				)
				( attribute "ROOM" "USB_REAR"
					( Origin gFrontEnd )
				)
				( attribute "ROT" "0"
					( Origin gFrontEnd )
				)
				( attribute "SEC" "1"
					( Origin gPackager )
				)
				( attribute "VER" "2"
					( Origin gFrontEnd )
				)
				( attribute "XY" "(-1300,4550)"
					( Origin gFrontEnd )
				)
				( attribute "CHIPS_PART_NAME" "CONN9_H51826001"
					( Origin gPackager )
				)
				( attribute "CDS_PART_NAME" "CONN9_H51826001_PIP2-CONN,H518A"
					( Origin gPackager )
				)
				( objectStatus "J9B1" )
				( pin "dn"
					( attribute "PN" "2"
						( Origin gPackager )
					)
					( objectStatus "J9B1.2" )
				)
				( pin "dp"
					( attribute "PN" "3"
						( Origin gPackager )
					)
					( objectStatus "J9B1.3" )
				)
				( pin "gnd"
					( attribute "PN" "4"
						( Origin gPackager )
					)
					( objectStatus "J9B1.4" )
				)
				( pin "gnd_drain"
					( attribute "PN" "7"
						( Origin gPackager )
					)
					( objectStatus "J9B1.7" )
				)
				( pin "mh1"
					( attribute "PN" "MH1"
						( Origin gPackager )
					)
					( objectStatus "J9B1.MH1" )
				)
				( pin "mh2"
					( attribute "PN" "MH2"
						( Origin gPackager )
					)
					( objectStatus "J9B1.MH2" )
				)
				( pin "mh3"
					( attribute "PN" "MH3"
						( Origin gPackager )
					)
					( objectStatus "J9B1.MH3" )
				)
				( pin "mh4"
					( attribute "PN" "MH4"
						( Origin gPackager )
					)
					( objectStatus "J9B1.MH4" )
				)
				( pin "stda_ssrxn"
					( attribute "PN" "5"
						( Origin gPackager )
					)
					( objectStatus "J9B1.5" )
				)
				( pin "stda_ssrxp"
					( attribute "PN" "6"
						( Origin gPackager )
					)
					( objectStatus "J9B1.6" )
				)
				( pin "stda_sstxn"
					( attribute "PN" "8"
						( Origin gPackager )
					)
					( objectStatus "J9B1.8" )
				)
				( pin "stda_sstxp"
					( attribute "PN" "9"
						( Origin gPackager )
					)
					( objectStatus "J9B1.9" )
				)
				( pin "vbus"
					( attribute "PN" "1"
						( Origin gPackager )
					)
					( objectStatus "J9B1.1" )
				)
			)
			( gate "@baseboard_fab2_lib.baseboard_fab2(sch_1):page176_i98"
				( attribute "BOM_COST" "MIO_USB"
					( Origin gFrontEnd )
				)
				( attribute "CDS_LIB" "mstr_discrete"
					( Origin gPackager )
				)
				( attribute "CDS_LOCATION" "CR1M2"
					( Origin gPackager )
				)
				( attribute "CDS_SEC" "1"
					( Origin gPackager )
				)
				( attribute "LOCATION" "CR1M2"
					( Origin gFrontEnd )
				)
				( attribute "MATERIAL" "IC"
					( Origin gFrontEnd )
				)
				( attribute "PACK_TYPE" "SM9"
					( Origin gFrontEnd )
				)
				( attribute "PART_NUMBER" "G18435-001"
					( Origin gFrontEnd )
				)
				( attribute "PHYS_PAGE" "176"
					( Origin gFrontEnd )
				)
				( attribute "ROOM" "USB_REAR"
					( Origin gFrontEnd )
				)
				( attribute "ROT" "0"
					( Origin gFrontEnd )
				)
				( attribute "SEC" "1"
					( Origin gFrontEnd )
				)
				( attribute "SEC_TYPE" "SM9"
					( Origin gFrontEnd )
				)
				( attribute "VALUE" "ESD3V3U4ULC"
					( Origin gFrontEnd )
				)
				( attribute "VER" "7"
					( Origin gFrontEnd )
				)
				( attribute "XY" "(-3950,4100)"
					( Origin gFrontEnd )
				)
				( attribute "CHIPS_PART_NAME" "DIODEAC_DUAL_ARRAY"
					( Origin gPackager )
				)
				( attribute "CDS_PART_NAME" "DIODEAC_DUAL_ARRAY_SM9-ESD3V3UA"
					( Origin gPackager )
				)
				( objectStatus "CR1M2" )
				( pin "ac0"
					( attribute "PN" "1"
						( Origin gPackager )
					)
					( objectStatus "CR1M2.1" )
				)
				( pin "ac1"
					( attribute "PN" "2"
						( Origin gPackager )
					)
					( objectStatus "CR1M2.2" )
				)
				( pin "ac2"
					( attribute "PN" "4"
						( Origin gPackager )
					)
					( objectStatus "CR1M2.4" )
				)
				( pin "ac3"
					( attribute "PN" "5"
						( Origin gPackager )
					)
					( objectStatus "CR1M2.5" )
				)
				( pin "gnd(0)"
					( attribute "PN" "3"
						( Origin gPackager )
					)
					( objectStatus "CR1M2.3" )
				)
				( pin "out0"
					( attribute "PN" "9"
						( Origin gPackager )
					)
					( objectStatus "CR1M2.9" )
				)
				( pin "out1"
					( attribute "PN" "8"
						( Origin gPackager )
					)
					( objectStatus "CR1M2.8" )
				)
				( pin "out2"
					( attribute "PN" "7"
						( Origin gPackager )
					)
					( objectStatus "CR1M2.7" )
				)
				( pin "out3"
					( attribute "PN" "6"
						( Origin gPackager )
					)
					( objectStatus "CR1M2.6" )
				)
			)
			( gate "@baseboard_fab2_lib.baseboard_fab2(sch_1):page176_i100"
				( attribute "BOM_COST" "MIO_USB"
					( Origin gFrontEnd )
				)
				( attribute "CDS_LIB" "mstr_vreg"
					( Origin gPackager )
				)
				( attribute "CDS_LOCATION" "U1M3"
					( Origin gPackager )
				)
				( attribute "CDS_SEC" "1"
					( Origin gPackager )
				)
				( attribute "LOCATION" "U1M3"
					( Origin gFrontEnd )
				)
				( attribute "MATERIAL" "IC"
					( Origin gFrontEnd )
				)
				( attribute "PACK_TYPE" "SM"
					( Origin gFrontEnd )
				)
				( attribute "PART_NUMBER" "H66405-001"
					( Origin gFrontEnd )
				)
				( attribute "PHYS_PAGE" "176"
					( Origin gFrontEnd )
				)
				( attribute "ROOM" "USB_REAR"
					( Origin gFrontEnd )
				)
				( attribute "ROT" "0"
					( Origin gFrontEnd )
				)
				( attribute "SEC" "1"
					( Origin gFrontEnd )
				)
				( attribute "SEC_TYPE" "SM"
					( Origin gFrontEnd )
				)
				( attribute "VER" "1"
					( Origin gFrontEnd )
				)
				( attribute "XY" "(-1100,1825)"
					( Origin gFrontEnd )
				)
				( attribute "CHIPS_PART_NAME" "TPS2061"
					( Origin gPackager )
				)
				( attribute "CDS_PART_NAME" "TPS2061_SM-IC,H66405-001"
					( Origin gPackager )
				)
				( objectStatus "U1M3" )
				( pin "en_n"
					( attribute "PN" "4"
						( Origin gPackager )
					)
					( objectStatus "U1M3.4" )
				)
				( pin "gnd"
					( attribute "PN" "2"
						( Origin gPackager )
					)
					( objectStatus "U1M3.2" )
				)
				( pin "\in\"
					( attribute "PN" "5"
						( Origin gPackager )
					)
					( objectStatus "U1M3.5" )
				)
				( pin "oc_n"
					( attribute "PN" "3"
						( Origin gPackager )
					)
					( objectStatus "U1M3.3" )
				)
				( pin "\out\"
					( attribute "PN" "1"
						( Origin gPackager )
					)
					( objectStatus "U1M3.1" )
				)
			)
			( gate "@baseboard_fab2_lib.baseboard_fab2(sch_1):page176_i105"
				( attribute "BOM_COST" "MIO_USB"
					( Origin gFrontEnd )
				)
				( attribute "CDS_LIB" "mstr_discrete"
					( Origin gPackager )
				)
				( attribute "CDS_LOCATION" "R1M24"
					( Origin gPackager )
				)
				( attribute "CDS_SEC" "1"
					( Origin gPackager )
				)
				( attribute "LOCATION" "R1M24"
					( Origin gFrontEnd )
				)
				( attribute "MATERIAL" "CHIP"
					( Origin gFrontEnd )
				)
				( attribute "PACK_TYPE" "0402"
					( Origin gFrontEnd )
				)
				( attribute "PART_NUMBER" "G21796-016"
					( Origin gFrontEnd )
				)
				( attribute "PHYS_PAGE" "176"
					( Origin gFrontEnd )
				)
				( attribute "ROOM" "USB_REAR"
					( Origin gFrontEnd )
				)
				( attribute "ROT" "0"
					( Origin gFrontEnd )
				)
				( attribute "SEC" "1"
					( Origin gFrontEnd )
				)
				( attribute "SEC_TYPE" "0402"
					( Origin gFrontEnd )
				)
				( attribute "TOLERANCE" "1%"
					( Origin gFrontEnd )
				)
				( attribute "VALUE" "10.0K"
					( Origin gFrontEnd )
				)
				( attribute "VER" "2"
					( Origin gFrontEnd )
				)
				( attribute "WATTAGE" "1/16W"
					( Origin gFrontEnd )
				)
				( attribute "XY" "(-675,2300)"
					( Origin gFrontEnd )
				)
				( attribute "CHIPS_PART_NAME" "RES"
					( Origin gPackager )
				)
				( attribute "CDS_PART_NAME" "RES_0402-10.0K,1%,1/16W,CHIP,GA"
					( Origin gPackager )
				)
				( objectStatus "R1M24" )
				( pin "a"
					( attribute "PN" "1"
						( Origin gPackager )
					)
					( objectStatus "R1M24.1" )
				)
				( pin "b"
					( attribute "PN" "2"
						( Origin gPackager )
					)
					( objectStatus "R1M24.2" )
				)
			)
			( gate "@baseboard_fab2_lib.baseboard_fab2(sch_1):page176_i108"
				( attribute "BOM_COST" "MIO_USB"
					( Origin gFrontEnd )
				)
				( attribute "CDS_LIB" "dev_discrete"
					( Origin gPackager )
				)
				( attribute "CDS_LOCATION" "C1M38"
					( Origin gPackager )
				)
				( attribute "CDS_SEC" "1"
					( Origin gPackager )
				)
				( attribute "LOCATION" "C1M38"
					( Origin gFrontEnd )
				)
				( attribute "MATERIAL" "X7R"
					( Origin gFrontEnd )
				)
				( attribute "PACK_TYPE" "0402V"
					( Origin gFrontEnd )
				)
				( attribute "PART_NUMBER" "A36096-030"
					( Origin gFrontEnd )
				)
				( attribute "PHYS_PAGE" "176"
					( Origin gFrontEnd )
				)
				( attribute "ROOM" "USB_REAR"
					( Origin gFrontEnd )
				)
				( attribute "ROT" "0"
					( Origin gFrontEnd )
				)
				( attribute "SEC" "1"
					( Origin gFrontEnd )
				)
				( attribute "SEC_TYPE" "0402V"
					( Origin gFrontEnd )
				)
				( attribute "TOLERANCE" "10%"
					( Origin gFrontEnd )
				)
				( attribute "VALUE" "0.1UF"
					( Origin gFrontEnd )
				)
				( attribute "VER" "1"
					( Origin gFrontEnd )
				)
				( attribute "VOLTAGE" "16V"
					( Units "uVoltage" "V" 1.000000)
					( Origin gFrontEnd )
				)
				( attribute "XY" "(-2075,2250)"
					( Origin gFrontEnd )
				)
				( attribute "CHIPS_PART_NAME" "CAP_A"
					( Origin gPackager )
				)
				( attribute "CDS_PART_NAME" "CAP_A_0402V-0.1UF,16V,10%,X7R,A"
					( Origin gPackager )
				)
				( objectStatus "C1M38" )
				( pin "a"
					( attribute "PN" "1"
						( Origin gPackager )
					)
					( objectStatus "C1M38.1" )
				)
				( pin "b"
					( attribute "PN" "2"
						( Origin gPackager )
					)
					( objectStatus "C1M38.2" )
				)
			)
			( gate "@baseboard_fab2_lib.baseboard_fab2(sch_1):page176_i111"
				( attribute "BOM_COST" "MIO_USB"
					( Origin gFrontEnd )
				)
				( attribute "CDS_LIB" "mstr_discrete"
					( Origin gPackager )
				)
				( attribute "CDS_LOCATION" "R1M25"
					( Origin gPackager )
				)
				( attribute "CDS_SEC" "1"
					( Origin gPackager )
				)
				( attribute "LOCATION" "R1M25"
					( Origin gFrontEnd )
				)
				( attribute "MATERIAL" "CHIP"
					( Origin gFrontEnd )
				)
				( attribute "PACK_TYPE" "0402"
					( Origin gFrontEnd )
				)
				( attribute "PART_NUMBER" "G21796-016"
					( Origin gFrontEnd )
				)
				( attribute "PHYS_PAGE" "176"
					( Origin gFrontEnd )
				)
				( attribute "ROOM" "USB_REAR"
					( Origin gFrontEnd )
				)
				( attribute "ROT" "0"
					( Origin gFrontEnd )
				)
				( attribute "SEC" "1"
					( Origin gFrontEnd )
				)
				( attribute "SEC_TYPE" "0402"
					( Origin gFrontEnd )
				)
				( attribute "TOLERANCE" "1%"
					( Origin gFrontEnd )
				)
				( attribute "VALUE" "10.0K"
					( Origin gFrontEnd )
				)
				( attribute "VER" "2"
					( Origin gFrontEnd )
				)
				( attribute "WATTAGE" "1/16W"
					( Origin gFrontEnd )
				)
				( attribute "XY" "(-1850,1525)"
					( Origin gFrontEnd )
				)
				( attribute "CHIPS_PART_NAME" "RES"
					( Origin gPackager )
				)
				( attribute "CDS_PART_NAME" "RES_0402-10.0K,1%,1/16W,CHIP,GA"
					( Origin gPackager )
				)
				( objectStatus "R1M25" )
				( pin "a"
					( attribute "PN" "1"
						( Origin gPackager )
					)
					( objectStatus "R1M25.1" )
				)
				( pin "b"
					( attribute "PN" "2"
						( Origin gPackager )
					)
					( objectStatus "R1M25.2" )
				)
			)
			( gate "@baseboard_fab2_lib.baseboard_fab2(sch_1):page176_i113"
				( attribute "CDS_LIB" "mstr_discrete"
					( Origin gPackager )
				)
				( attribute "CDS_LOCATION" "C9B8"
					( Origin gPackager )
				)
				( attribute "CDS_SEC" "1"
					( Origin gPackager )
				)
				( attribute "LOCATION" "C9B8"
					( Origin gFrontEnd )
				)
				( attribute "MATERIAL" "POSCAP"
					( Origin gFrontEnd )
				)
				( attribute "PACK_TYPE" "7343HLF"
					( Origin gFrontEnd )
				)
				( attribute "PART_NUMBER" "724613-043"
					( Origin gFrontEnd )
				)
				( attribute "PHYS_PAGE" "176"
					( Origin gFrontEnd )
				)
				( attribute "ROT" "0"
					( Origin gFrontEnd )
				)
				( attribute "SEC" "1"
					( Origin gFrontEnd )
				)
				( attribute "SEC_TYPE" "7343HLF"
					( Origin gFrontEnd )
				)
				( attribute "TOLERANCE" "20%"
					( Origin gFrontEnd )
				)
				( attribute "VALUE" "330UF"
					( Origin gFrontEnd )
				)
				( attribute "VER" "1"
					( Origin gFrontEnd )
				)
				( attribute "VOLTAGE" "10V"
					( Units "uVoltage" "V" 1.000000)
					( Origin gFrontEnd )
				)
				( attribute "XY" "(-525,1625)"
					( Origin gFrontEnd )
				)
				( attribute "CHIPS_PART_NAME" "CAPP"
					( Origin gPackager )
				)
				( attribute "CDS_PART_NAME" "CAPP_7343HLF-330UF,10V,20%,POSA"
					( Origin gPackager )
				)
				( objectStatus "C9B8" )
				( pin "a"
					( attribute "PN" "1"
						( Origin gPackager )
					)
					( objectStatus "C9B8.1" )
				)
				( pin "b"
					( attribute "PN" "2"
						( Origin gPackager )
					)
					( objectStatus "C9B8.2" )
				)
			)
			( gate "@baseboard_fab2_lib.baseboard_fab2(sch_1):page177_i3"
				( attribute "CDS_LIB" "mstr_discrete"
					( Origin gPackager )
				)
				( attribute "CDS_LOCATION" "R1M13"
					( Origin gPackager )
				)
				( attribute "CDS_SEC" "1"
					( Origin gPackager )
				)
				( attribute "LOCATION" "R1M13"
					( Origin gFrontEnd )
				)
				( attribute "MATERIAL" "CHIP"
					( Origin gFrontEnd )
				)
				( attribute "PACK_TYPE" "0402"
					( Origin gFrontEnd )
				)
				( attribute "PART_NUMBER" "G21497-005"
					( Origin gFrontEnd )
				)
				( attribute "PHYS_PAGE" "177"
					( Origin gFrontEnd )
				)
				( attribute "ROOM" "MIO_CHASSIS"
					( Origin gFrontEnd )
				)
				( attribute "ROT" "0"
					( Origin gFrontEnd )
				)
				( attribute "SEC" "1"
					( Origin gPackager )
				)
				( attribute "TOLERANCE" "5%"
					( Origin gFrontEnd )
				)
				( attribute "VALUE" "0.0"
					( Origin gFrontEnd )
				)
				( attribute "VER" "1"
					( Origin gFrontEnd )
				)
				( attribute "WATTAGE" "1/16W"
					( Origin gFrontEnd )
				)
				( attribute "XY" "(-7550,6225)"
					( Origin gFrontEnd )
				)
				( attribute "CHIPS_PART_NAME" "RES"
					( Origin gPackager )
				)
				( attribute "CDS_PART_NAME" "RES_0402-0.0,5%,1/16W,CHIP,G21A"
					( Origin gPackager )
				)
				( objectStatus "R1M13" )
				( pin "a"
					( attribute "PN" "1"
						( Origin gPackager )
					)
					( objectStatus "R1M13.1" )
				)
				( pin "b"
					( attribute "PN" "2"
						( Origin gPackager )
					)
					( objectStatus "R1M13.2" )
				)
			)
			( gate "@baseboard_fab2_lib.baseboard_fab2(sch_1):page177_i6"
				( attribute "CDS_LIB" "mstr_discrete"
					( Origin gPackager )
				)
				( attribute "CDS_LOCATION" "R1M10"
					( Origin gPackager )
				)
				( attribute "CDS_SEC" "1"
					( Origin gPackager )
				)
				( attribute "LOCATION" "R1M10"
					( Origin gFrontEnd )
				)
				( attribute "MATERIAL" "CHIP"
					( Origin gFrontEnd )
				)
				( attribute "PACK_TYPE" "0402"
					( Origin gFrontEnd )
				)
				( attribute "PART_NUMBER" "G21497-005"
					( Origin gFrontEnd )
				)
				( attribute "PHYS_PAGE" "177"
					( Origin gFrontEnd )
				)
				( attribute "ROOM" "MIO_CHASSIS"
					( Origin gFrontEnd )
				)
				( attribute "ROT" "0"
					( Origin gFrontEnd )
				)
				( attribute "SEC" "1"
					( Origin gPackager )
				)
				( attribute "TOLERANCE" "5%"
					( Origin gFrontEnd )
				)
				( attribute "VALUE" "0.0"
					( Origin gFrontEnd )
				)
				( attribute "VER" "1"
					( Origin gFrontEnd )
				)
				( attribute "WATTAGE" "1/16W"
					( Origin gFrontEnd )
				)
				( attribute "XY" "(-7750,6325)"
					( Origin gFrontEnd )
				)
				( attribute "CHIPS_PART_NAME" "RES"
					( Origin gPackager )
				)
				( attribute "CDS_PART_NAME" "RES_0402-0.0,5%,1/16W,CHIP,G21A"
					( Origin gPackager )
				)
				( objectStatus "R1M10" )
				( pin "a"
					( attribute "PN" "1"
						( Origin gPackager )
					)
					( objectStatus "R1M10.1" )
				)
				( pin "b"
					( attribute "PN" "2"
						( Origin gPackager )
					)
					( objectStatus "R1M10.2" )
				)
			)
			( gate "@baseboard_fab2_lib.baseboard_fab2(sch_1):page177_i8"
				( attribute "CDS_LIB" "mstr_discrete"
					( Origin gPackager )
				)
				( attribute "CDS_LOCATION" "R1M12"
					( Origin gPackager )
				)
				( attribute "CDS_SEC" "1"
					( Origin gPackager )
				)
				( attribute "LOCATION" "R1M12"
					( Origin gFrontEnd )
				)
				( attribute "MATERIAL" "CHIP"
					( Origin gFrontEnd )
				)
				( attribute "PACK_TYPE" "0402"
					( Origin gFrontEnd )
				)
				( attribute "PART_NUMBER" "G21796-016"
					( Origin gFrontEnd )
				)
				( attribute "PHYS_PAGE" "177"
					( Origin gFrontEnd )
				)
				( attribute "ROOM" "MIO_CHASSIS"
					( Origin gFrontEnd )
				)
				( attribute "ROT" "0"
					( Origin gFrontEnd )
				)
				( attribute "SEC" "1"
					( Origin gFrontEnd )
				)
				( attribute "SEC_TYPE" "0402"
					( Origin gFrontEnd )
				)
				( attribute "TOLERANCE" "1%"
					( Origin gFrontEnd )
				)
				( attribute "VALUE" "10.0K"
					( Origin gFrontEnd )
				)
				( attribute "VER" "2"
					( Origin gFrontEnd )
				)
				( attribute "WATTAGE" "1/16W"
					( Origin gFrontEnd )
				)
				( attribute "XY" "(-6975,6550)"
					( Origin gFrontEnd )
				)
				( attribute "CHIPS_PART_NAME" "RES"
					( Origin gPackager )
				)
				( attribute "CDS_PART_NAME" "RES_0402-10.0K,1%,1/16W,CHIP,GA"
					( Origin gPackager )
				)
				( objectStatus "R1M12" )
				( pin "a"
					( attribute "PN" "1"
						( Origin gPackager )
					)
					( objectStatus "R1M12.1" )
				)
				( pin "b"
					( attribute "PN" "2"
						( Origin gPackager )
					)
					( objectStatus "R1M12.2" )
				)
			)
			( gate "@baseboard_fab2_lib.baseboard_fab2(sch_1):page177_i9"
				( attribute "CDS_LIB" "mstr_discrete"
					( Origin gPackager )
				)
				( attribute "CDS_LOCATION" "R1M11"
					( Origin gPackager )
				)
				( attribute "CDS_SEC" "1"
					( Origin gPackager )
				)
				( attribute "LOCATION" "R1M11"
					( Origin gFrontEnd )
				)
				( attribute "MATERIAL" "CHIP"
					( Origin gFrontEnd )
				)
				( attribute "PACK_TYPE" "0402"
					( Origin gFrontEnd )
				)
				( attribute "PART_NUMBER" "G21796-016"
					( Origin gFrontEnd )
				)
				( attribute "PHYS_PAGE" "177"
					( Origin gFrontEnd )
				)
				( attribute "ROOM" "MIO_CHASSIS"
					( Origin gFrontEnd )
				)
				( attribute "ROT" "2"
					( Origin gFrontEnd )
				)
				( attribute "SEC" "1"
					( Origin gFrontEnd )
				)
				( attribute "SEC_TYPE" "0402"
					( Origin gFrontEnd )
				)
				( attribute "TOLERANCE" "1%"
					( Origin gFrontEnd )
				)
				( attribute "VALUE" "10.0K"
					( Origin gFrontEnd )
				)
				( attribute "VER" "2"
					( Origin gFrontEnd )
				)
				( attribute "WATTAGE" "1/16W"
					( Origin gFrontEnd )
				)
				( attribute "XY" "(-7025,6550)"
					( Origin gFrontEnd )
				)
				( attribute "CHIPS_PART_NAME" "RES"
					( Origin gPackager )
				)
				( attribute "CDS_PART_NAME" "RES_0402-10.0K,1%,1/16W,CHIP,GA"
					( Origin gPackager )
				)
				( objectStatus "R1M11" )
				( pin "a"
					( attribute "PN" "1"
						( Origin gPackager )
					)
					( objectStatus "R1M11.1" )
				)
				( pin "b"
					( attribute "PN" "2"
						( Origin gPackager )
					)
					( objectStatus "R1M11.2" )
				)
			)
			( gate "@baseboard_fab2_lib.baseboard_fab2(sch_1):page177_i20"
				( attribute "CDS_LIB" "dev_discrete"
					( Origin gPackager )
				)
				( attribute "CDS_LOCATION" "C1M3"
					( Origin gPackager )
				)
				( attribute "CDS_SEC" "1"
					( Origin gPackager )
				)
				( attribute "LOCATION" "C1M3"
					( Origin gFrontEnd )
				)
				( attribute "MATERIAL" "X6S"
					( Origin gFrontEnd )
				)
				( attribute "PACK_TYPE" "0402V"
					( Origin gFrontEnd )
				)
				( attribute "PART_NUMBER" "D97712-004"
					( Origin gFrontEnd )
				)
				( attribute "PHYS_PAGE" "177"
					( Origin gFrontEnd )
				)
				( attribute "ROOM" "MIO_CHASSIS"
					( Origin gFrontEnd )
				)
				( attribute "ROT" "0"
					( Origin gFrontEnd )
				)
				( attribute "SEC" "1"
					( Origin gPackager )
				)
				( attribute "TOLERANCE" "10%"
					( Origin gFrontEnd )
				)
				( attribute "VALUE" "1.0UF"
					( Origin gFrontEnd )
				)
				( attribute "VER" "1"
					( Origin gFrontEnd )
				)
				( attribute "VOLTAGE" "6.3V"
					( Units "uVoltage" "V" 1.000000)
					( Origin gFrontEnd )
				)
				( attribute "XY" "(-5625,5425)"
					( Origin gFrontEnd )
				)
				( attribute "CHIPS_PART_NAME" "CAP_A"
					( Origin gPackager )
				)
				( attribute "CDS_PART_NAME" "CAP_A_0402V-1.0UF,6.3V,10%,X6SA"
					( Origin gPackager )
				)
				( objectStatus "C1M3" )
				( pin "a"
					( attribute "PN" "1"
						( Origin gPackager )
					)
					( objectStatus "C1M3.1" )
				)
				( pin "b"
					( attribute "PN" "2"
						( Origin gPackager )
					)
					( objectStatus "C1M3.2" )
				)
			)
			( gate "@baseboard_fab2_lib.baseboard_fab2(sch_1):page177_i31"
				( attribute "CDS_LIB" "mstr_discrete"
					( Origin gPackager )
				)
				( attribute "CDS_LOCATION" "DS9A6"
					( Origin gPackager )
				)
				( attribute "CDS_SEC" "1"
					( Origin gPackager )
				)
				( attribute "COLOR" "GREEN"
					( Origin gFrontEnd )
				)
				( attribute "LOCATION" "DS9A6"
					( Origin gFrontEnd )
				)
				( attribute "MATERIAL" "IC"
					( Origin gFrontEnd )
				)
				( attribute "PACK_TYPE" "A1LF"
					( Origin gFrontEnd )
				)
				( attribute "PART_NUMBER" "C97278-010"
					( Origin gFrontEnd )
				)
				( attribute "PHYS_PAGE" "177"
					( Origin gFrontEnd )
				)
				( attribute "ROOM" "MIO_CHASSIS"
					( Origin gFrontEnd )
				)
				( attribute "ROT" "0"
					( Origin gFrontEnd )
				)
				( attribute "SEC" "1"
					( Origin gFrontEnd )
				)
				( attribute "SEC_TYPE" "A1LF"
					( Origin gFrontEnd )
				)
				( attribute "VER" "2"
					( Origin gFrontEnd )
				)
				( attribute "XY" "(-3825,8475)"
					( Origin gFrontEnd )
				)
				( attribute "CHIPS_PART_NAME" "LED"
					( Origin gPackager )
				)
				( attribute "CDS_PART_NAME" "LED_A1LF-GREEN,IC,C97278-010"
					( Origin gPackager )
				)
				( objectStatus "DS9A6" )
				( pin "a"
					( attribute "PN" "1"
						( Origin gPackager )
					)
					( objectStatus "DS9A6.1" )
				)
				( pin "c"
					( attribute "PN" "2"
						( Origin gPackager )
					)
					( objectStatus "DS9A6.2" )
				)
			)
			( gate "@baseboard_fab2_lib.baseboard_fab2(sch_1):page177_i33"
				( attribute "CDS_LIB" "mstr_discrete"
					( Origin gPackager )
				)
				( attribute "CDS_LOCATION" "R1L37"
					( Origin gPackager )
				)
				( attribute "CDS_SEC" "1"
					( Origin gPackager )
				)
				( attribute "LOCATION" "R1L37"
					( Origin gFrontEnd )
				)
				( attribute "MATERIAL" "CHIP"
					( Origin gFrontEnd )
				)
				( attribute "PACK_TYPE" "0402"
					( Origin gFrontEnd )
				)
				( attribute "PART_NUMBER" "G21796-076"
					( Origin gFrontEnd )
				)
				( attribute "PHYS_PAGE" "177"
					( Origin gFrontEnd )
				)
				( attribute "ROOM" "MIO_CHASSIS"
					( Origin gFrontEnd )
				)
				( attribute "ROT" "0"
					( Origin gFrontEnd )
				)
				( attribute "SEC" "1"
					( Origin gPackager )
				)
				( attribute "SIGNAL_MODEL" "DEFAULT_RESISTOR_332OHM_2_1"
					( Origin gFrontEnd )
				)
				( attribute "TOLERANCE" "1%"
					( Origin gFrontEnd )
				)
				( attribute "VALUE" "301.0"
					( Origin gFrontEnd )
				)
				( attribute "VER" "2"
					( Origin gFrontEnd )
				)
				( attribute "WATTAGE" "1/16W"
					( Origin gFrontEnd )
				)
				( attribute "XY" "(-3825,8850)"
					( Origin gFrontEnd )
				)
				( attribute "CHIPS_PART_NAME" "RES"
					( Origin gPackager )
				)
				( attribute "CDS_PART_NAME" "RES_0402-301.0,1%,1/16W,CHIP,GA"
					( Origin gPackager )
				)
				( objectStatus "R1L37" )
				( pin "a"
					( attribute "PN" "1"
						( Origin gPackager )
					)
					( objectStatus "R1L37.1" )
				)
				( pin "b"
					( attribute "PN" "2"
						( Origin gPackager )
					)
					( objectStatus "R1L37.2" )
				)
			)
			( gate "@baseboard_fab2_lib.baseboard_fab2(sch_1):page177_i42"
				( attribute "CDS_LIB" "mstr_discrete"
					( Origin gPackager )
				)
				( attribute "CDS_LOCATION" "DS9A2"
					( Origin gPackager )
				)
				( attribute "CDS_SEC" "1"
					( Origin gPackager )
				)
				( attribute "COLOR" "GREEN"
					( Origin gFrontEnd )
				)
				( attribute "LOCATION" "DS9A2"
					( Origin gFrontEnd )
				)
				( attribute "MATERIAL" "IC"
					( Origin gFrontEnd )
				)
				( attribute "PACK_TYPE" "1NCLF"
					( Origin gFrontEnd )
				)
				( attribute "PART_NUMBER" "C96565-011"
					( Origin gFrontEnd )
				)
				( attribute "PHYS_PAGE" "177"
					( Origin gFrontEnd )
				)
				( attribute "ROOM" "MIO_CHASSIS"
					( Origin gFrontEnd )
				)
				( attribute "ROT" "0"
					( Origin gFrontEnd )
				)
				( attribute "SEC" "1"
					( Origin gFrontEnd )
				)
				( attribute "SEC_TYPE" "1NCLF"
					( Origin gFrontEnd )
				)
				( attribute "VER" "3"
					( Origin gFrontEnd )
				)
				( attribute "XY" "(-5550,6275)"
					( Origin gFrontEnd )
				)
				( attribute "CHIPS_PART_NAME" "LED"
					( Origin gPackager )
				)
				( attribute "CDS_PART_NAME" "LED_1NCLF-GREEN,IC,C96565-011"
					( Origin gPackager )
				)
				( objectStatus "DS9A2" )
				( pin "a"
					( attribute "PN" "2"
						( Origin gPackager )
					)
					( objectStatus "DS9A2.2" )
				)
				( pin "c"
					( attribute "PN" "1"
						( Origin gPackager )
					)
					( objectStatus "DS9A2.1" )
				)
			)
			( gate "@baseboard_fab2_lib.baseboard_fab2(sch_1):page177_i43"
				( attribute "CDS_LIB" "mstr_discrete"
					( Origin gPackager )
				)
				( attribute "CDS_LOCATION" "R1L21"
					( Origin gPackager )
				)
				( attribute "CDS_SEC" "1"
					( Origin gPackager )
				)
				( attribute "LOCATION" "R1L21"
					( Origin gFrontEnd )
				)
				( attribute "MATERIAL" "CHIP"
					( Origin gFrontEnd )
				)
				( attribute "PACK_TYPE" "0402"
					( Origin gFrontEnd )
				)
				( attribute "PART_NUMBER" "G21796-298"
					( Origin gFrontEnd )
				)
				( attribute "PHYS_PAGE" "177"
					( Origin gFrontEnd )
				)
				( attribute "ROOM" "MIO_CHASSIS"
					( Origin gFrontEnd )
				)
				( attribute "ROT" "0"
					( Origin gFrontEnd )
				)
				( attribute "SEC" "1"
					( Origin gFrontEnd )
				)
				( attribute "SEC_TYPE" "0402"
					( Origin gFrontEnd )
				)
				( attribute "TOLERANCE" "1.0%"
					( Origin gFrontEnd )
				)
				( attribute "VALUE" "64.9"
					( Origin gFrontEnd )
				)
				( attribute "VER" "2"
					( Origin gFrontEnd )
				)
				( attribute "WATTAGE" "1/16W"
					( Origin gFrontEnd )
				)
				( attribute "XY" "(-4675,6600)"
					( Origin gFrontEnd )
				)
				( attribute "CHIPS_PART_NAME" "RES"
					( Origin gPackager )
				)
				( attribute "CDS_PART_NAME" "RES_0402-64.9,1.0%,1/16W,CHIP,A"
					( Origin gPackager )
				)
				( objectStatus "R1L21" )
				( pin "a"
					( attribute "PN" "1"
						( Origin gPackager )
					)
					( objectStatus "R1L21.1" )
				)
				( pin "b"
					( attribute "PN" "2"
						( Origin gPackager )
					)
					( objectStatus "R1L21.2" )
				)
			)
			( gate "@baseboard_fab2_lib.baseboard_fab2(sch_1):page177_i70"
				( attribute "BOM_COST" "MIO_CHASSIS"
					( Origin gFrontEnd )
				)
				( attribute "CDS_LIB" "mstr_ttl"
					( Origin gPackager )
				)
				( attribute "CDS_LOCATION" "U1M1"
					( Origin gPackager )
				)
				( attribute "CDS_SEC" "1"
					( Origin gPackager )
				)
				( attribute "LOCATION" "U1M1"
					( Origin gFrontEnd )
				)
				( attribute "MATERIAL" "IC"
					( Origin gFrontEnd )
				)
				( attribute "PACK_TYPE" "SOTLF"
					( Origin gFrontEnd )
				)
				( attribute "PART_NUMBER" "D10321-001"
					( Origin gFrontEnd )
				)
				( attribute "PHYS_PAGE" "177"
					( Origin gFrontEnd )
				)
				( attribute "ROOM" "MIO_CHASSIS"
					( Origin gFrontEnd )
				)
				( attribute "ROT" "0"
					( Origin gFrontEnd )
				)
				( attribute "SEC" "1"
					( Origin gFrontEnd )
				)
				( attribute "SEC_TYPE" "SOTLF"
					( Origin gFrontEnd )
				)
				( attribute "VALUE" "NC7SZ08"
					( Origin gFrontEnd )
				)
				( attribute "VER" "1"
					( Origin gFrontEnd )
				)
				( attribute "XY" "(-6550,6275)"
					( Origin gFrontEnd )
				)
				( attribute "CHIPS_PART_NAME" "TTL1G08"
					( Origin gPackager )
				)
				( attribute "CDS_PART_NAME" "TTL1G08_SOTLF-NC7SZ08,IC,D1032C"
					( Origin gPackager )
				)
				( objectStatus "U1M1" )
				( pin "a(0)"
					( attribute "PN" "1"
						( Origin gPackager )
					)
					( objectStatus "U1M1.1" )
				)
				( pin "b(0)"
					( attribute "PN" "2"
						( Origin gPackager )
					)
					( objectStatus "U1M1.2" )
				)
				( pin "y(0)"
					( attribute "PN" "4"
						( Origin gPackager )
					)
					( objectStatus "U1M1.4" )
				)
			)
			( gate "@baseboard_fab2_lib.baseboard_fab2(sch_1):page177_i71"
				( attribute "BOM_COST" "SM_CONTROLLER"
					( Origin gFrontEnd )
				)
				( attribute "CDS_LIB" "mstr_discrete"
					( Origin gPackager )
				)
				( attribute "CDS_LOCATION" "DS9F1"
					( Origin gPackager )
				)
				( attribute "CDS_SEC" "1"
					( Origin gPackager )
				)
				( attribute "COLOR" "RED"
					( Origin gFrontEnd )
				)
				( attribute "LOCATION" "DS9F1"
					( Origin gFrontEnd )
				)
				( attribute "MATERIAL" "IC"
					( Origin gFrontEnd )
				)
				( attribute "PACK_TYPE" "A1"
					( Origin gFrontEnd )
				)
				( attribute "PART_NUMBER" "D14725-005"
					( Origin gFrontEnd )
				)
				( attribute "PHYS_PAGE" "177"
					( Origin gFrontEnd )
				)
				( attribute "ROOM" "BMC"
					( Origin gFrontEnd )
				)
				( attribute "ROT" "0"
					( Origin gFrontEnd )
				)
				( attribute "SEC" "1"
					( Origin gFrontEnd )
				)
				( attribute "SEC_TYPE" "A1"
					( Origin gFrontEnd )
				)
				( attribute "VER" "2"
					( Origin gFrontEnd )
				)
				( attribute "XY" "(-7200,8475)"
					( Origin gFrontEnd )
				)
				( attribute "CHIPS_PART_NAME" "LED"
					( Origin gPackager )
				)
				( attribute "CDS_PART_NAME" "LED_A1-RED,IC,D14725-005"
					( Origin gPackager )
				)
				( objectStatus "DS9F1" )
				( pin "a"
					( attribute "PN" "1"
						( Origin gPackager )
					)
					( objectStatus "DS9F1.1" )
				)
				( pin "c"
					( attribute "PN" "2"
						( Origin gPackager )
					)
					( objectStatus "DS9F1.2" )
				)
			)
			( gate "@baseboard_fab2_lib.baseboard_fab2(sch_1):page177_i72"
				( attribute "BOM_COST" "SM_CONTROLLER"
					( Origin gFrontEnd )
				)
				( attribute "CDS_LIB" "mstr_discrete"
					( Origin gPackager )
				)
				( attribute "CDS_LOCATION" "R9F28"
					( Origin gPackager )
				)
				( attribute "CDS_SEC" "1"
					( Origin gPackager )
				)
				( attribute "LOCATION" "R9F28"
					( Origin gFrontEnd )
				)
				( attribute "MATERIAL" "CHIP"
					( Origin gFrontEnd )
				)
				( attribute "PACK_TYPE" "0402"
					( Origin gFrontEnd )
				)
				( attribute "PART_NUMBER" "G21796-271"
					( Origin gFrontEnd )
				)
				( attribute "PHYS_PAGE" "177"
					( Origin gFrontEnd )
				)
				( attribute "ROOM" "BMC"
					( Origin gFrontEnd )
				)
				( attribute "ROT" "0"
					( Origin gFrontEnd )
				)
				( attribute "SEC" "1"
					( Origin gFrontEnd )
				)
				( attribute "SEC_TYPE" "0402"
					( Origin gFrontEnd )
				)
				( attribute "TOLERANCE" "1.0%"
					( Origin gFrontEnd )
				)
				( attribute "VALUE" "221"
					( Origin gFrontEnd )
				)
				( attribute "VER" "2"
					( Origin gFrontEnd )
				)
				( attribute "WATTAGE" "1/16W"
					( Origin gFrontEnd )
				)
				( attribute "XY" "(-7200,8825)"
					( Origin gFrontEnd )
				)
				( attribute "CHIPS_PART_NAME" "RES"
					( Origin gPackager )
				)
				( attribute "CDS_PART_NAME" "RES_0402-221,1.0%,1/16W,CHIP,GA"
					( Origin gPackager )
				)
				( objectStatus "R9F28" )
				( pin "a"
					( attribute "PN" "1"
						( Origin gPackager )
					)
					( objectStatus "R9F28.1" )
				)
				( pin "b"
					( attribute "PN" "2"
						( Origin gPackager )
					)
					( objectStatus "R9F28.2" )
				)
			)
			( gate "@baseboard_fab2_lib.baseboard_fab2(sch_1):page177_i76"
				( attribute "BOM_COST" "SM_CONTROLLER"
					( Origin gFrontEnd )
				)
				( attribute "CDS_LIB" "mstr_discrete"
					( Origin gPackager )
				)
				( attribute "CDS_LOCATION" "R9F30"
					( Origin gPackager )
				)
				( attribute "CDS_SEC" "1"
					( Origin gPackager )
				)
				( attribute "LOCATION" "R9F30"
					( Origin gFrontEnd )
				)
				( attribute "MATERIAL" "CHIP"
					( Origin gFrontEnd )
				)
				( attribute "PACK_TYPE" "0402"
					( Origin gFrontEnd )
				)
				( attribute "PART_NUMBER" "G21796-072"
					( Origin gFrontEnd )
				)
				( attribute "PHYS_PAGE" "177"
					( Origin gFrontEnd )
				)
				( attribute "ROOM" "BMC"
					( Origin gFrontEnd )
				)
				( attribute "ROT" "0"
					( Origin gFrontEnd )
				)
				( attribute "SEC" "1"
					( Origin gFrontEnd )
				)
				( attribute "SEC_TYPE" "0402"
					( Origin gFrontEnd )
				)
				( attribute "TOLERANCE" "1%"
					( Origin gFrontEnd )
				)
				( attribute "VALUE" "4.75K"
					( Origin gFrontEnd )
				)
				( attribute "VER" "2"
					( Origin gFrontEnd )
				)
				( attribute "WATTAGE" "1/16W"
					( Origin gFrontEnd )
				)
				( attribute "XY" "(-8475,7850)"
					( Origin gFrontEnd )
				)
				( attribute "CHIPS_PART_NAME" "RES"
					( Origin gPackager )
				)
				( attribute "CDS_PART_NAME" "RES_0402-4.75K,1%,1/16W,CHIP,GA"
					( Origin gPackager )
				)
				( objectStatus "R9F30" )
				( pin "a"
					( attribute "PN" "1"
						( Origin gPackager )
					)
					( objectStatus "R9F30.1" )
				)
				( pin "b"
					( attribute "PN" "2"
						( Origin gPackager )
					)
					( objectStatus "R9F30.2" )
				)
			)
			( gate "@baseboard_fab2_lib.baseboard_fab2(sch_1):page177_i79"
				( attribute "BOM_COST" "SM_CONTROLLER"
					( Origin gFrontEnd )
				)
				( attribute "CDS_LIB" "mstr_discrete"
					( Origin gPackager )
				)
				( attribute "CDS_LOCATION" "Q9F1"
					( Origin gPackager )
				)
				( attribute "CDS_SEC" "2"
					( Origin gPackager )
				)
				( attribute "LOCATION" "Q9F1"
					( Origin gFrontEnd )
				)
				( attribute "MATERIAL" "FET"
					( Origin gFrontEnd )
				)
				( attribute "PACK_TYPE" "SMLF"
					( Origin gFrontEnd )
				)
				( attribute "PART_NUMBER" "E40049-001"
					( Origin gFrontEnd )
				)
				( attribute "PHYS_PAGE" "177"
					( Origin gFrontEnd )
				)
				( attribute "ROOM" "BMC"
					( Origin gFrontEnd )
				)
				( attribute "ROT" "0"
					( Origin gFrontEnd )
				)
				( attribute "SEC" "2"
					( Origin gFrontEnd )
				)
				( attribute "SEC_TYPE" "SMLF"
					( Origin gFrontEnd )
				)
				( attribute "VALUE" "NTJD4001N"
					( Origin gFrontEnd )
				)
				( attribute "VER" "5"
					( Origin gFrontEnd )
				)
				( attribute "XY" "(-7200,8050)"
					( Origin gFrontEnd )
				)
				( attribute "CHIPS_PART_NAME" "FET_N_DUAL"
					( Origin gPackager )
				)
				( attribute "CDS_PART_NAME" "FET_N_DUAL_SMLF-NTJD4001N,FET,A"
					( Origin gPackager )
				)
				( objectStatus "Q9F1" )
				( pin "drain(0)"
					( attribute "PN" "3"
						( Origin gPackager )
					)
					( objectStatus "Q9F1.3" )
				)
				( pin "gate(0)"
					( attribute "PN" "5"
						( Origin gPackager )
					)
					( objectStatus "Q9F1.5" )
				)
				( pin "source(0)"
					( attribute "PN" "4"
						( Origin gPackager )
					)
					( objectStatus "Q9F1.4" )
				)
			)
			( gate "@baseboard_fab2_lib.baseboard_fab2(sch_1):page177_i80"
				( attribute "BOM_COST" "SM_CONTROLLER"
					( Origin gFrontEnd )
				)
				( attribute "CDS_LIB" "mstr_discrete"
					( Origin gPackager )
				)
				( attribute "CDS_LOCATION" "Q9F1"
					( Origin gPackager )
				)
				( attribute "CDS_SEC" "1"
					( Origin gPackager )
				)
				( attribute "LOCATION" "Q9F1"
					( Origin gFrontEnd )
				)
				( attribute "MATERIAL" "FET"
					( Origin gFrontEnd )
				)
				( attribute "PACK_TYPE" "SMLF"
					( Origin gFrontEnd )
				)
				( attribute "PART_NUMBER" "E40049-001"
					( Origin gFrontEnd )
				)
				( attribute "PHYS_PAGE" "177"
					( Origin gFrontEnd )
				)
				( attribute "ROOM" "BMC"
					( Origin gFrontEnd )
				)
				( attribute "ROT" "0"
					( Origin gFrontEnd )
				)
				( attribute "SEC" "1"
					( Origin gFrontEnd )
				)
				( attribute "SEC_TYPE" "SMLF"
					( Origin gFrontEnd )
				)
				( attribute "VALUE" "NTJD4001N"
					( Origin gFrontEnd )
				)
				( attribute "VER" "5"
					( Origin gFrontEnd )
				)
				( attribute "XY" "(-7800,7675)"
					( Origin gFrontEnd )
				)
				( attribute "CHIPS_PART_NAME" "FET_N_DUAL"
					( Origin gPackager )
				)
				( attribute "CDS_PART_NAME" "FET_N_DUAL_SMLF-NTJD4001N,FET,A"
					( Origin gPackager )
				)
				( objectStatus "Q9F1" )
				( pin "drain(0)"
					( attribute "PN" "6"
						( Origin gPackager )
					)
					( objectStatus "Q9F1.6" )
				)
				( pin "gate(0)"
					( attribute "PN" "2"
						( Origin gPackager )
					)
					( objectStatus "Q9F1.2" )
				)
				( pin "source(0)"
					( attribute "PN" "1"
						( Origin gPackager )
					)
					( objectStatus "Q9F1.1" )
				)
			)
			( gate "@baseboard_fab2_lib.baseboard_fab2(sch_1):page177_i82"
				( attribute "BOM_COST" "SM_CONTROLLER"
					( Origin gFrontEnd )
				)
				( attribute "CDS_LIB" "mstr_discrete"
					( Origin gPackager )
				)
				( attribute "CDS_LOCATION" "R9F52"
					( Origin gPackager )
				)
				( attribute "CDS_SEC" "1"
					( Origin gPackager )
				)
				( attribute "LOCATION" "R9F52"
					( Origin gFrontEnd )
				)
				( attribute "MATERIAL" "CHIP"
					( Origin gFrontEnd )
				)
				( attribute "PACK_TYPE" "0402"
					( Origin gFrontEnd )
				)
				( attribute "PART_NUMBER" "G21796-072"
					( Origin gFrontEnd )
				)
				( attribute "PHYS_PAGE" "177"
					( Origin gFrontEnd )
				)
				( attribute "ROOM" "BMC"
					( Origin gFrontEnd )
				)
				( attribute "ROT" "0"
					( Origin gFrontEnd )
				)
				( attribute "SEC" "1"
					( Origin gFrontEnd )
				)
				( attribute "SEC_TYPE" "0402"
					( Origin gFrontEnd )
				)
				( attribute "TOLERANCE" "1%"
					( Origin gFrontEnd )
				)
				( attribute "VALUE" "4.75K"
					( Origin gFrontEnd )
				)
				( attribute "VER" "2"
					( Origin gFrontEnd )
				)
				( attribute "WATTAGE" "1/16W"
					( Origin gFrontEnd )
				)
				( attribute "XY" "(-7800,8225)"
					( Origin gFrontEnd )
				)
				( attribute "CHIPS_PART_NAME" "RES"
					( Origin gPackager )
				)
				( attribute "CDS_PART_NAME" "RES_0402-4.75K,1%,1/16W,CHIP,GA"
					( Origin gPackager )
				)
				( objectStatus "R9F52" )
				( pin "a"
					( attribute "PN" "1"
						( Origin gPackager )
					)
					( objectStatus "R9F52.1" )
				)
				( pin "b"
					( attribute "PN" "2"
						( Origin gPackager )
					)
					( objectStatus "R9F52.2" )
				)
			)
			( gate "@baseboard_fab2_lib.baseboard_fab2(sch_1):page178_i1"
				( attribute "BOM_COST" "ST_SATA"
					( Origin gFrontEnd )
				)
				( attribute "CDS_LIB" "mstr_discrete"
					( Origin gPackager )
				)
				( attribute "CDS_LOCATION" "R8D20"
					( Origin gPackager )
				)
				( attribute "CDS_SEC" "1"
					( Origin gPackager )
				)
				( attribute "LOCATION" "R8D20"
					( Origin gFrontEnd )
				)
				( attribute "MATERIAL" "CHIP"
					( Origin gFrontEnd )
				)
				( attribute "PACK_TYPE" "0402"
					( Origin gFrontEnd )
				)
				( attribute "PART_NUMBER" "G21796-047"
					( Origin gFrontEnd )
				)
				( attribute "PHYS_PAGE" "178"
					( Origin gFrontEnd )
				)
				( attribute "ROOM" "ST_SATA"
					( Origin gFrontEnd )
				)
				( attribute "ROT" "0"
					( Origin gFrontEnd )
				)
				( attribute "SEC" "1"
					( Origin gFrontEnd )
				)
				( attribute "SEC_TYPE" "0402"
					( Origin gFrontEnd )
				)
				( attribute "TOLERANCE" "1%"
					( Origin gFrontEnd )
				)
				( attribute "VALUE" "49.9"
					( Origin gFrontEnd )
				)
				( attribute "VER" "1"
					( Origin gFrontEnd )
				)
				( attribute "WATTAGE" "1/16W"
					( Origin gFrontEnd )
				)
				( attribute "XY" "(-800,3725)"
					( Origin gFrontEnd )
				)
				( attribute "CHIPS_PART_NAME" "RES"
					( Origin gPackager )
				)
				( attribute "CDS_PART_NAME" "RES_0402-49.9,1%,1/16W,CHIP,G2A"
					( Origin gPackager )
				)
				( objectStatus "R8D20" )
				( pin "a"
					( attribute "PN" "1"
						( Origin gPackager )
					)
					( objectStatus "R8D20.1" )
				)
				( pin "b"
					( attribute "PN" "2"
						( Origin gPackager )
					)
					( objectStatus "R8D20.2" )
				)
			)
			( gate "@baseboard_fab2_lib.baseboard_fab2(sch_1):page178_i2"
				( attribute "BOM_COST" "ST_SATA"
					( Origin gFrontEnd )
				)
				( attribute "CDS_LIB" "mstr_discrete"
					( Origin gPackager )
				)
				( attribute "CDS_LOCATION" "R2L12"
					( Origin gPackager )
				)
				( attribute "CDS_SEC" "1"
					( Origin gPackager )
				)
				( attribute "LOCATION" "R2L12"
					( Origin gFrontEnd )
				)
				( attribute "MATERIAL" "CHIP"
					( Origin gFrontEnd )
				)
				( attribute "PACK_TYPE" "0402"
					( Origin gFrontEnd )
				)
				( attribute "PART_NUMBER" "G21796-001"
					( Origin gFrontEnd )
				)
				( attribute "PHYS_PAGE" "178"
					( Origin gFrontEnd )
				)
				( attribute "ROOM" "ST_SATA"
					( Origin gFrontEnd )
				)
				( attribute "ROT" "2"
					( Origin gFrontEnd )
				)
				( attribute "SEC" "1"
					( Origin gFrontEnd )
				)
				( attribute "SEC_TYPE" "0402"
					( Origin gFrontEnd )
				)
				( attribute "TOLERANCE" "1%"
					( Origin gFrontEnd )
				)
				( attribute "VALUE" "2.0K"
					( Origin gFrontEnd )
				)
				( attribute "VER" "2"
					( Origin gFrontEnd )
				)
				( attribute "WATTAGE" "1/16W"
					( Origin gFrontEnd )
				)
				( attribute "XY" "(-200,4125)"
					( Origin gFrontEnd )
				)
				( attribute "CHIPS_PART_NAME" "RES"
					( Origin gPackager )
				)
				( attribute "CDS_PART_NAME" "RES_0402-2.0K,1%,1/16W,CHIP,G2A"
					( Origin gPackager )
				)
				( objectStatus "R2L12" )
				( pin "a"
					( attribute "PN" "1"
						( Origin gPackager )
					)
					( objectStatus "R2L12.1" )
				)
				( pin "b"
					( attribute "PN" "2"
						( Origin gPackager )
					)
					( objectStatus "R2L12.2" )
				)
			)
			( gate "@baseboard_fab2_lib.baseboard_fab2(sch_1):page178_i8"
				( attribute "BOM_COST" "ST_SATA"
					( Origin gFrontEnd )
				)
				( attribute "CDS_LIB" "mstr_discrete"
					( Origin gPackager )
				)
				( attribute "CDS_LOCATION" "R8D19"
					( Origin gPackager )
				)
				( attribute "CDS_SEC" "1"
					( Origin gPackager )
				)
				( attribute "LOCATION" "R8D19"
					( Origin gFrontEnd )
				)
				( attribute "MATERIAL" "CHIP"
					( Origin gFrontEnd )
				)
				( attribute "PACK_TYPE" "0402"
					( Origin gFrontEnd )
				)
				( attribute "PART_NUMBER" "G21796-047"
					( Origin gFrontEnd )
				)
				( attribute "PHYS_PAGE" "178"
					( Origin gFrontEnd )
				)
				( attribute "ROOM" "ST_SATA"
					( Origin gFrontEnd )
				)
				( attribute "ROT" "0"
					( Origin gFrontEnd )
				)
				( attribute "SEC" "1"
					( Origin gFrontEnd )
				)
				( attribute "SEC_TYPE" "0402"
					( Origin gFrontEnd )
				)
				( attribute "TOLERANCE" "1%"
					( Origin gFrontEnd )
				)
				( attribute "VALUE" "49.9"
					( Origin gFrontEnd )
				)
				( attribute "VER" "1"
					( Origin gFrontEnd )
				)
				( attribute "WATTAGE" "1/16W"
					( Origin gFrontEnd )
				)
				( attribute "XY" "(-800,3575)"
					( Origin gFrontEnd )
				)
				( attribute "CHIPS_PART_NAME" "RES"
					( Origin gPackager )
				)
				( attribute "CDS_PART_NAME" "RES_0402-49.9,1%,1/16W,CHIP,G2A"
					( Origin gPackager )
				)
				( objectStatus "R8D19" )
				( pin "a"
					( attribute "PN" "1"
						( Origin gPackager )
					)
					( objectStatus "R8D19.1" )
				)
				( pin "b"
					( attribute "PN" "2"
						( Origin gPackager )
					)
					( objectStatus "R8D19.2" )
				)
			)
			( gate "@baseboard_fab2_lib.baseboard_fab2(sch_1):page178_i11"
				( attribute "BOM_COST" "ST_SATA"
					( Origin gFrontEnd )
				)
				( attribute "CDS_LIB" "mstr_discrete"
					( Origin gPackager )
				)
				( attribute "CDS_LOCATION" "R2N31"
					( Origin gPackager )
				)
				( attribute "CDS_SEC" "1"
					( Origin gPackager )
				)
				( attribute "LOCATION" "R2N31"
					( Origin gFrontEnd )
				)
				( attribute "MATERIAL" "CHIP"
					( Origin gFrontEnd )
				)
				( attribute "PACK_TYPE" "0402"
					( Origin gFrontEnd )
				)
				( attribute "PART_NUMBER" "G21796-047"
					( Origin gFrontEnd )
				)
				( attribute "PHYS_PAGE" "178"
					( Origin gFrontEnd )
				)
				( attribute "ROOM" "ST_SATA"
					( Origin gFrontEnd )
				)
				( attribute "ROT" "0"
					( Origin gFrontEnd )
				)
				( attribute "SEC" "1"
					( Origin gFrontEnd )
				)
				( attribute "SEC_TYPE" "0402"
					( Origin gFrontEnd )
				)
				( attribute "TOLERANCE" "1%"
					( Origin gFrontEnd )
				)
				( attribute "VALUE" "49.9"
					( Origin gFrontEnd )
				)
				( attribute "VER" "1"
					( Origin gFrontEnd )
				)
				( attribute "WATTAGE" "1/16W"
					( Origin gFrontEnd )
				)
				( attribute "XY" "(-800,3425)"
					( Origin gFrontEnd )
				)
				( attribute "CHIPS_PART_NAME" "RES"
					( Origin gPackager )
				)
				( attribute "CDS_PART_NAME" "RES_0402-49.9,1%,1/16W,CHIP,G2A"
					( Origin gPackager )
				)
				( objectStatus "R2N31" )
				( pin "a"
					( attribute "PN" "1"
						( Origin gPackager )
					)
					( objectStatus "R2N31.1" )
				)
				( pin "b"
					( attribute "PN" "2"
						( Origin gPackager )
					)
					( objectStatus "R2N31.2" )
				)
			)
			( gate "@baseboard_fab2_lib.baseboard_fab2(sch_1):page178_i12"
				( attribute "BOM_COST" "ST_SATA"
					( Origin gFrontEnd )
				)
				( attribute "CDS_LIB" "mstr_discrete"
					( Origin gPackager )
				)
				( attribute "CDS_LOCATION" "R2L15"
					( Origin gPackager )
				)
				( attribute "CDS_SEC" "1"
					( Origin gPackager )
				)
				( attribute "LOCATION" "R2L15"
					( Origin gFrontEnd )
				)
				( attribute "MATERIAL" "CHIP"
					( Origin gFrontEnd )
				)
				( attribute "PACK_TYPE" "0402"
					( Origin gFrontEnd )
				)
				( attribute "PART_NUMBER" "G21796-001"
					( Origin gFrontEnd )
				)
				( attribute "PHYS_PAGE" "178"
					( Origin gFrontEnd )
				)
				( attribute "ROOM" "ST_SATA"
					( Origin gFrontEnd )
				)
				( attribute "ROT" "2"
					( Origin gFrontEnd )
				)
				( attribute "SEC" "1"
					( Origin gFrontEnd )
				)
				( attribute "SEC_TYPE" "0402"
					( Origin gFrontEnd )
				)
				( attribute "TOLERANCE" "1%"
					( Origin gFrontEnd )
				)
				( attribute "VALUE" "2.0K"
					( Origin gFrontEnd )
				)
				( attribute "VER" "2"
					( Origin gFrontEnd )
				)
				( attribute "WATTAGE" "1/16W"
					( Origin gFrontEnd )
				)
				( attribute "XY" "(225,4125)"
					( Origin gFrontEnd )
				)
				( attribute "CHIPS_PART_NAME" "RES"
					( Origin gPackager )
				)
				( attribute "CDS_PART_NAME" "RES_0402-2.0K,1%,1/16W,CHIP,G2A"
					( Origin gPackager )
				)
				( objectStatus "R2L15" )
				( pin "a"
					( attribute "PN" "1"
						( Origin gPackager )
					)
					( objectStatus "R2L15.1" )
				)
				( pin "b"
					( attribute "PN" "2"
						( Origin gPackager )
					)
					( objectStatus "R2L15.2" )
				)
			)
			( gate "@baseboard_fab2_lib.baseboard_fab2(sch_1):page178_i13"
				( attribute "BOM_COST" "ST_SATA"
					( Origin gFrontEnd )
				)
				( attribute "CDS_LIB" "mstr_discrete"
					( Origin gPackager )
				)
				( attribute "CDS_LOCATION" "R2L11"
					( Origin gPackager )
				)
				( attribute "CDS_SEC" "1"
					( Origin gPackager )
				)
				( attribute "LOCATION" "R2L11"
					( Origin gFrontEnd )
				)
				( attribute "MATERIAL" "CHIP"
					( Origin gFrontEnd )
				)
				( attribute "PACK_TYPE" "0402"
					( Origin gFrontEnd )
				)
				( attribute "PART_NUMBER" "G21796-001"
					( Origin gFrontEnd )
				)
				( attribute "PHYS_PAGE" "178"
					( Origin gFrontEnd )
				)
				( attribute "ROOM" "ST_SATA"
					( Origin gFrontEnd )
				)
				( attribute "ROT" "2"
					( Origin gFrontEnd )
				)
				( attribute "SEC" "1"
					( Origin gFrontEnd )
				)
				( attribute "SEC_TYPE" "0402"
					( Origin gFrontEnd )
				)
				( attribute "TOLERANCE" "1%"
					( Origin gFrontEnd )
				)
				( attribute "VALUE" "2.0K"
					( Origin gFrontEnd )
				)
				( attribute "VER" "2"
					( Origin gFrontEnd )
				)
				( attribute "WATTAGE" "1/16W"
					( Origin gFrontEnd )
				)
				( attribute "XY" "(575,4125)"
					( Origin gFrontEnd )
				)
				( attribute "CHIPS_PART_NAME" "RES"
					( Origin gPackager )
				)
				( attribute "CDS_PART_NAME" "RES_0402-2.0K,1%,1/16W,CHIP,G2A"
					( Origin gPackager )
				)
				( objectStatus "R2L11" )
				( pin "a"
					( attribute "PN" "1"
						( Origin gPackager )
					)
					( objectStatus "R2L11.1" )
				)
				( pin "b"
					( attribute "PN" "2"
						( Origin gPackager )
					)
					( objectStatus "R2L11.2" )
				)
			)
			( gate "@baseboard_fab2_lib.baseboard_fab2(sch_1):page178_i17"
				( attribute "BOM_COST" "ST_SATA"
					( Origin gFrontEnd )
				)
				( attribute "CDS_LIB" "mstr_discrete"
					( Origin gPackager )
				)
				( attribute "CDS_LOCATION" "R2L6"
					( Origin gPackager )
				)
				( attribute "CDS_SEC" "1"
					( Origin gPackager )
				)
				( attribute "LOCATION" "R2L6"
					( Origin gFrontEnd )
				)
				( attribute "MATERIAL" "CHIP"
					( Origin gFrontEnd )
				)
				( attribute "PACK_TYPE" "0402"
					( Origin gFrontEnd )
				)
				( attribute "PART_NUMBER" "G21796-001"
					( Origin gFrontEnd )
				)
				( attribute "PHYS_PAGE" "178"
					( Origin gFrontEnd )
				)
				( attribute "ROOM" "ST_SATA"
					( Origin gFrontEnd )
				)
				( attribute "ROT" "2"
					( Origin gFrontEnd )
				)
				( attribute "SEC" "1"
					( Origin gFrontEnd )
				)
				( attribute "SEC_TYPE" "0402"
					( Origin gFrontEnd )
				)
				( attribute "TOLERANCE" "1%"
					( Origin gFrontEnd )
				)
				( attribute "VALUE" "2.0K"
					( Origin gFrontEnd )
				)
				( attribute "VER" "2"
					( Origin gFrontEnd )
				)
				( attribute "WATTAGE" "1/16W"
					( Origin gFrontEnd )
				)
				( attribute "XY" "(475,2225)"
					( Origin gFrontEnd )
				)
				( attribute "CHIPS_PART_NAME" "RES"
					( Origin gPackager )
				)
				( attribute "CDS_PART_NAME" "RES_0402-2.0K,1%,1/16W,CHIP,G2A"
					( Origin gPackager )
				)
				( objectStatus "R2L6" )
				( pin "a"
					( attribute "PN" "1"
						( Origin gPackager )
					)
					( objectStatus "R2L6.1" )
				)
				( pin "b"
					( attribute "PN" "2"
						( Origin gPackager )
					)
					( objectStatus "R2L6.2" )
				)
			)
			( gate "@baseboard_fab2_lib.baseboard_fab2(sch_1):page178_i18"
				( attribute "BOM_COST" "ST_SATA"
					( Origin gFrontEnd )
				)
				( attribute "CDS_LIB" "mstr_discrete"
					( Origin gPackager )
				)
				( attribute "CDS_LOCATION" "R2L4"
					( Origin gPackager )
				)
				( attribute "CDS_SEC" "1"
					( Origin gPackager )
				)
				( attribute "LOCATION" "R2L4"
					( Origin gFrontEnd )
				)
				( attribute "MATERIAL" "CHIP"
					( Origin gFrontEnd )
				)
				( attribute "PACK_TYPE" "0402"
					( Origin gFrontEnd )
				)
				( attribute "PART_NUMBER" "G21796-001"
					( Origin gFrontEnd )
				)
				( attribute "PHYS_PAGE" "178"
					( Origin gFrontEnd )
				)
				( attribute "ROOM" "ST_SATA"
					( Origin gFrontEnd )
				)
				( attribute "ROT" "2"
					( Origin gFrontEnd )
				)
				( attribute "SEC" "1"
					( Origin gFrontEnd )
				)
				( attribute "SEC_TYPE" "0402"
					( Origin gFrontEnd )
				)
				( attribute "TOLERANCE" "1%"
					( Origin gFrontEnd )
				)
				( attribute "VALUE" "2.0K"
					( Origin gFrontEnd )
				)
				( attribute "VER" "2"
					( Origin gFrontEnd )
				)
				( attribute "WATTAGE" "1/16W"
					( Origin gFrontEnd )
				)
				( attribute "XY" "(125,2225)"
					( Origin gFrontEnd )
				)
				( attribute "CHIPS_PART_NAME" "RES"
					( Origin gPackager )
				)
				( attribute "CDS_PART_NAME" "RES_0402-2.0K,1%,1/16W,CHIP,G2A"
					( Origin gPackager )
				)
				( objectStatus "R2L4" )
				( pin "a"
					( attribute "PN" "1"
						( Origin gPackager )
					)
					( objectStatus "R2L4.1" )
				)
				( pin "b"
					( attribute "PN" "2"
						( Origin gPackager )
					)
					( objectStatus "R2L4.2" )
				)
			)
			( gate "@baseboard_fab2_lib.baseboard_fab2(sch_1):page178_i20"
				( attribute "BOM_COST" "ST_SATA"
					( Origin gFrontEnd )
				)
				( attribute "CDS_LIB" "mstr_discrete"
					( Origin gPackager )
				)
				( attribute "CDS_LOCATION" "R2L5"
					( Origin gPackager )
				)
				( attribute "CDS_SEC" "1"
					( Origin gPackager )
				)
				( attribute "LOCATION" "R2L5"
					( Origin gFrontEnd )
				)
				( attribute "MATERIAL" "CHIP"
					( Origin gFrontEnd )
				)
				( attribute "PACK_TYPE" "0402"
					( Origin gFrontEnd )
				)
				( attribute "PART_NUMBER" "G21796-001"
					( Origin gFrontEnd )
				)
				( attribute "PHYS_PAGE" "178"
					( Origin gFrontEnd )
				)
				( attribute "ROOM" "ST_SATA"
					( Origin gFrontEnd )
				)
				( attribute "ROT" "2"
					( Origin gFrontEnd )
				)
				( attribute "SEC" "1"
					( Origin gFrontEnd )
				)
				( attribute "SEC_TYPE" "0402"
					( Origin gFrontEnd )
				)
				( attribute "TOLERANCE" "1%"
					( Origin gFrontEnd )
				)
				( attribute "VALUE" "2.0K"
					( Origin gFrontEnd )
				)
				( attribute "VER" "2"
					( Origin gFrontEnd )
				)
				( attribute "WATTAGE" "1/16W"
					( Origin gFrontEnd )
				)
				( attribute "XY" "(-200,2225)"
					( Origin gFrontEnd )
				)
				( attribute "CHIPS_PART_NAME" "RES"
					( Origin gPackager )
				)
				( attribute "CDS_PART_NAME" "RES_0402-2.0K,1%,1/16W,CHIP,G2A"
					( Origin gPackager )
				)
				( objectStatus "R2L5" )
				( pin "a"
					( attribute "PN" "1"
						( Origin gPackager )
					)
					( objectStatus "R2L5.1" )
				)
				( pin "b"
					( attribute "PN" "2"
						( Origin gPackager )
					)
					( objectStatus "R2L5.2" )
				)
			)
			( gate "@baseboard_fab2_lib.baseboard_fab2(sch_1):page178_i21"
				( attribute "BOM_COST" "ST_SATA"
					( Origin gFrontEnd )
				)
				( attribute "CDS_LIB" "mstr_discrete"
					( Origin gPackager )
				)
				( attribute "CDS_LOCATION" "R8B29"
					( Origin gPackager )
				)
				( attribute "CDS_SEC" "1"
					( Origin gPackager )
				)
				( attribute "LOCATION" "R8B29"
					( Origin gFrontEnd )
				)
				( attribute "MATERIAL" "CHIP"
					( Origin gFrontEnd )
				)
				( attribute "PACK_TYPE" "0402"
					( Origin gFrontEnd )
				)
				( attribute "PART_NUMBER" "G21796-047"
					( Origin gFrontEnd )
				)
				( attribute "PHYS_PAGE" "178"
					( Origin gFrontEnd )
				)
				( attribute "ROOM" "ST_SATA"
					( Origin gFrontEnd )
				)
				( attribute "ROT" "0"
					( Origin gFrontEnd )
				)
				( attribute "SEC" "1"
					( Origin gFrontEnd )
				)
				( attribute "SEC_TYPE" "0402"
					( Origin gFrontEnd )
				)
				( attribute "TOLERANCE" "1%"
					( Origin gFrontEnd )
				)
				( attribute "VALUE" "49.9"
					( Origin gFrontEnd )
				)
				( attribute "VER" "1"
					( Origin gFrontEnd )
				)
				( attribute "WATTAGE" "1/16W"
					( Origin gFrontEnd )
				)
				( attribute "XY" "(-800,1675)"
					( Origin gFrontEnd )
				)
				( attribute "CHIPS_PART_NAME" "RES"
					( Origin gPackager )
				)
				( attribute "CDS_PART_NAME" "RES_0402-49.9,1%,1/16W,CHIP,G2A"
					( Origin gPackager )
				)
				( objectStatus "R8B29" )
				( pin "a"
					( attribute "PN" "1"
						( Origin gPackager )
					)
					( objectStatus "R8B29.1" )
				)
				( pin "b"
					( attribute "PN" "2"
						( Origin gPackager )
					)
					( objectStatus "R8B29.2" )
				)
			)
			( gate "@baseboard_fab2_lib.baseboard_fab2(sch_1):page178_i22"
				( attribute "BOM_COST" "ST_SATA"
					( Origin gFrontEnd )
				)
				( attribute "CDS_LIB" "mstr_discrete"
					( Origin gPackager )
				)
				( attribute "CDS_LOCATION" "R2N19"
					( Origin gPackager )
				)
				( attribute "CDS_SEC" "1"
					( Origin gPackager )
				)
				( attribute "LOCATION" "R2N19"
					( Origin gFrontEnd )
				)
				( attribute "MATERIAL" "CHIP"
					( Origin gFrontEnd )
				)
				( attribute "PACK_TYPE" "0402"
					( Origin gFrontEnd )
				)
				( attribute "PART_NUMBER" "G21796-047"
					( Origin gFrontEnd )
				)
				( attribute "PHYS_PAGE" "178"
					( Origin gFrontEnd )
				)
				( attribute "ROOM" "ST_SATA"
					( Origin gFrontEnd )
				)
				( attribute "ROT" "0"
					( Origin gFrontEnd )
				)
				( attribute "SEC" "1"
					( Origin gFrontEnd )
				)
				( attribute "SEC_TYPE" "0402"
					( Origin gFrontEnd )
				)
				( attribute "TOLERANCE" "1%"
					( Origin gFrontEnd )
				)
				( attribute "VALUE" "49.9"
					( Origin gFrontEnd )
				)
				( attribute "VER" "1"
					( Origin gFrontEnd )
				)
				( attribute "WATTAGE" "1/16W"
					( Origin gFrontEnd )
				)
				( attribute "XY" "(-800,1825)"
					( Origin gFrontEnd )
				)
				( attribute "CHIPS_PART_NAME" "RES"
					( Origin gPackager )
				)
				( attribute "CDS_PART_NAME" "RES_0402-49.9,1%,1/16W,CHIP,G2A"
					( Origin gPackager )
				)
				( objectStatus "R2N19" )
				( pin "a"
					( attribute "PN" "1"
						( Origin gPackager )
					)
					( objectStatus "R2N19.1" )
				)
				( pin "b"
					( attribute "PN" "2"
						( Origin gPackager )
					)
					( objectStatus "R2N19.2" )
				)
			)
			( gate "@baseboard_fab2_lib.baseboard_fab2(sch_1):page178_i23"
				( attribute "BOM_COST" "ST_SATA"
					( Origin gFrontEnd )
				)
				( attribute "CDS_LIB" "mstr_discrete"
					( Origin gPackager )
				)
				( attribute "CDS_LOCATION" "R2N22"
					( Origin gPackager )
				)
				( attribute "CDS_SEC" "1"
					( Origin gPackager )
				)
				( attribute "LOCATION" "R2N22"
					( Origin gFrontEnd )
				)
				( attribute "MATERIAL" "CHIP"
					( Origin gFrontEnd )
				)
				( attribute "PACK_TYPE" "0402"
					( Origin gFrontEnd )
				)
				( attribute "PART_NUMBER" "G21796-047"
					( Origin gFrontEnd )
				)
				( attribute "PHYS_PAGE" "178"
					( Origin gFrontEnd )
				)
				( attribute "ROOM" "ST_SATA"
					( Origin gFrontEnd )
				)
				( attribute "ROT" "0"
					( Origin gFrontEnd )
				)
				( attribute "SEC" "1"
					( Origin gFrontEnd )
				)
				( attribute "SEC_TYPE" "0402"
					( Origin gFrontEnd )
				)
				( attribute "TOLERANCE" "1%"
					( Origin gFrontEnd )
				)
				( attribute "VALUE" "49.9"
					( Origin gFrontEnd )
				)
				( attribute "VER" "1"
					( Origin gFrontEnd )
				)
				( attribute "WATTAGE" "1/16W"
					( Origin gFrontEnd )
				)
				( attribute "XY" "(-800,1525)"
					( Origin gFrontEnd )
				)
				( attribute "CHIPS_PART_NAME" "RES"
					( Origin gPackager )
				)
				( attribute "CDS_PART_NAME" "RES_0402-49.9,1%,1/16W,CHIP,G2A"
					( Origin gPackager )
				)
				( objectStatus "R2N22" )
				( pin "a"
					( attribute "PN" "1"
						( Origin gPackager )
					)
					( objectStatus "R2N22.1" )
				)
				( pin "b"
					( attribute "PN" "2"
						( Origin gPackager )
					)
					( objectStatus "R2N22.2" )
				)
			)
			( gate "@baseboard_fab2_lib.baseboard_fab2(sch_1):page181_i111"
				( attribute "BOM_COST" "IO_SLOT"
					( Origin gFrontEnd )
				)
				( attribute "CDS_LIB" "mstr_conn"
					( Origin gPackager )
				)
				( attribute "CDS_LOCATION" "J1F1"
					( Origin gPackager )
				)
				( attribute "CDS_SEC" "1"
					( Origin gPackager )
				)
				( attribute "LOCATION" "J1F1"
					( Origin gFrontEnd )
				)
				( attribute "MATERIAL" "CONN"
					( Origin gFrontEnd )
				)
				( attribute "PACK_TYPE" "THMT1"
					( Origin gFrontEnd )
				)
				( attribute "PART_NUMBER" "H22707-001"
					( Origin gFrontEnd )
				)
				( attribute "PHYS_PAGE" "181"
					( Origin gFrontEnd )
				)
				( attribute "ROOM" "IO_SLOT"
					( Origin gFrontEnd )
				)
				( attribute "ROT" "0"
					( Origin gFrontEnd )
				)
				( attribute "SEC" "1"
					( Origin gFrontEnd )
				)
				( attribute "SEC_TYPE" "THMT1"
					( Origin gFrontEnd )
				)
				( attribute "VER" "1"
					( Origin gFrontEnd )
				)
				( attribute "XY" "(-625,3800)"
					( Origin gFrontEnd )
				)
				( attribute "CHIPS_PART_NAME" "CONN76_H22707001"
					( Origin gPackager )
				)
				( attribute "CDS_PART_NAME" "CONN76_H22707001_THMT1-CONN,H2A"
					( Origin gPackager )
				)
				( objectStatus "J1F1" )
				( pin "gnda2"
					( attribute "PN" "A2"
						( Origin gPackager )
					)
					( objectStatus "J1F1.A2" )
				)
				( pin "gnda4"
					( attribute "PN" "A4"
						( Origin gPackager )
					)
					( objectStatus "J1F1.A4" )
				)
				( pin "gnda6"
					( attribute "PN" "A6"
						( Origin gPackager )
					)
					( objectStatus "J1F1.A6" )
				)
				( pin "gnda8"
					( attribute "PN" "A8"
						( Origin gPackager )
					)
					( objectStatus "J1F1.A8" )
				)
				( pin "gndc1"
					( attribute "PN" "C1"
						( Origin gPackager )
					)
					( objectStatus "J1F1.C1" )
				)
				( pin "gndc3"
					( attribute "PN" "C3"
						( Origin gPackager )
					)
					( objectStatus "J1F1.C3" )
				)
				( pin "gndc5"
					( attribute "PN" "C5"
						( Origin gPackager )
					)
					( objectStatus "J1F1.C5" )
				)
				( pin "gndc7"
					( attribute "PN" "C7"
						( Origin gPackager )
					)
					( objectStatus "J1F1.C7" )
				)
				( pin "gndd2"
					( attribute "PN" "D2"
						( Origin gPackager )
					)
					( objectStatus "J1F1.D2" )
				)
				( pin "gndd4"
					( attribute "PN" "D4"
						( Origin gPackager )
					)
					( objectStatus "J1F1.D4" )
				)
				( pin "gndd6"
					( attribute "PN" "D6"
						( Origin gPackager )
					)
					( objectStatus "J1F1.D6" )
				)
				( pin "gndd8"
					( attribute "PN" "D8"
						( Origin gPackager )
					)
					( objectStatus "J1F1.D8" )
				)
				( pin "gndf1"
					( attribute "PN" "F1"
						( Origin gPackager )
					)
					( objectStatus "J1F1.F1" )
				)
				( pin "gndf3"
					( attribute "PN" "F3"
						( Origin gPackager )
					)
					( objectStatus "J1F1.F3" )
				)
				( pin "gndf5"
					( attribute "PN" "F5"
						( Origin gPackager )
					)
					( objectStatus "J1F1.F5" )
				)
				( pin "gndf7"
					( attribute "PN" "F7"
						( Origin gPackager )
					)
					( objectStatus "J1F1.F7" )
				)
				( pin "gndg2"
					( attribute "PN" "G2"
						( Origin gPackager )
					)
					( objectStatus "J1F1.G2" )
				)
				( pin "gndg4"
					( attribute "PN" "G4"
						( Origin gPackager )
					)
					( objectStatus "J1F1.G4" )
				)
				( pin "gndg6"
					( attribute "PN" "G6"
						( Origin gPackager )
					)
					( objectStatus "J1F1.G6" )
				)
				( pin "gndg8"
					( attribute "PN" "G8"
						( Origin gPackager )
					)
					( objectStatus "J1F1.G8" )
				)
				( pin "gndi1"
					( attribute "PN" "I1"
						( Origin gPackager )
					)
					( objectStatus "J1F1.I1" )
				)
				( pin "gndi3"
					( attribute "PN" "I3"
						( Origin gPackager )
					)
					( objectStatus "J1F1.I3" )
				)
				( pin "gndi5"
					( attribute "PN" "I5"
						( Origin gPackager )
					)
					( objectStatus "J1F1.I5" )
				)
				( pin "gndi7"
					( attribute "PN" "I7"
						( Origin gPackager )
					)
					( objectStatus "J1F1.I7" )
				)
				( pin "gndj2"
					( attribute "PN" "J2"
						( Origin gPackager )
					)
					( objectStatus "J1F1.J2" )
				)
				( pin "gndj4"
					( attribute "PN" "J4"
						( Origin gPackager )
					)
					( objectStatus "J1F1.J4" )
				)
				( pin "gndj6"
					( attribute "PN" "J6"
						( Origin gPackager )
					)
					( objectStatus "J1F1.J6" )
				)
				( pin "gndj8"
					( attribute "PN" "J8"
						( Origin gPackager )
					)
					( objectStatus "J1F1.J8" )
				)
				( pin "ioa1"
					( attribute "PN" "A1"
						( Origin gPackager )
					)
					( objectStatus "J1F1.A1" )
				)
				( pin "ioa3"
					( attribute "PN" "A3"
						( Origin gPackager )
					)
					( objectStatus "J1F1.A3" )
				)
				( pin "ioa5"
					( attribute "PN" "A5"
						( Origin gPackager )
					)
					( objectStatus "J1F1.A5" )
				)
				( pin "ioa7"
					( attribute "PN" "A7"
						( Origin gPackager )
					)
					( objectStatus "J1F1.A7" )
				)
				( pin "iob1"
					( attribute "PN" "B1"
						( Origin gPackager )
					)
					( objectStatus "J1F1.B1" )
				)
				( pin "iob2"
					( attribute "PN" "B2"
						( Origin gPackager )
					)
					( objectStatus "J1F1.B2" )
				)
				( pin "iob3"
					( attribute "PN" "B3"
						( Origin gPackager )
					)
					( objectStatus "J1F1.B3" )
				)
				( pin "iob4"
					( attribute "PN" "B4"
						( Origin gPackager )
					)
					( objectStatus "J1F1.B4" )
				)
				( pin "iob5"
					( attribute "PN" "B5"
						( Origin gPackager )
					)
					( objectStatus "J1F1.B5" )
				)
				( pin "iob6"
					( attribute "PN" "B6"
						( Origin gPackager )
					)
					( objectStatus "J1F1.B6" )
				)
				( pin "iob7"
					( attribute "PN" "B7"
						( Origin gPackager )
					)
					( objectStatus "J1F1.B7" )
				)
				( pin "iob8"
					( attribute "PN" "B8"
						( Origin gPackager )
					)
					( objectStatus "J1F1.B8" )
				)
				( pin "ioc2"
					( attribute "PN" "C2"
						( Origin gPackager )
					)
					( objectStatus "J1F1.C2" )
				)
				( pin "ioc4"
					( attribute "PN" "C4"
						( Origin gPackager )
					)
					( objectStatus "J1F1.C4" )
				)
				( pin "ioc6"
					( attribute "PN" "C6"
						( Origin gPackager )
					)
					( objectStatus "J1F1.C6" )
				)
				( pin "ioc8"
					( attribute "PN" "C8"
						( Origin gPackager )
					)
					( objectStatus "J1F1.C8" )
				)
				( pin "iod1"
					( attribute "PN" "D1"
						( Origin gPackager )
					)
					( objectStatus "J1F1.D1" )
				)
				( pin "iod3"
					( attribute "PN" "D3"
						( Origin gPackager )
					)
					( objectStatus "J1F1.D3" )
				)
				( pin "iod5"
					( attribute "PN" "D5"
						( Origin gPackager )
					)
					( objectStatus "J1F1.D5" )
				)
				( pin "iod7"
					( attribute "PN" "D7"
						( Origin gPackager )
					)
					( objectStatus "J1F1.D7" )
				)
				( pin "ioe1"
					( attribute "PN" "E1"
						( Origin gPackager )
					)
					( objectStatus "J1F1.E1" )
				)
				( pin "ioe2"
					( attribute "PN" "E2"
						( Origin gPackager )
					)
					( objectStatus "J1F1.E2" )
				)
				( pin "ioe3"
					( attribute "PN" "E3"
						( Origin gPackager )
					)
					( objectStatus "J1F1.E3" )
				)
				( pin "ioe4"
					( attribute "PN" "E4"
						( Origin gPackager )
					)
					( objectStatus "J1F1.E4" )
				)
				( pin "ioe5"
					( attribute "PN" "E5"
						( Origin gPackager )
					)
					( objectStatus "J1F1.E5" )
				)
				( pin "ioe6"
					( attribute "PN" "E6"
						( Origin gPackager )
					)
					( objectStatus "J1F1.E6" )
				)
				( pin "ioe7"
					( attribute "PN" "E7"
						( Origin gPackager )
					)
					( objectStatus "J1F1.E7" )
				)
				( pin "ioe8"
					( attribute "PN" "E8"
						( Origin gPackager )
					)
					( objectStatus "J1F1.E8" )
				)
				( pin "iof2"
					( attribute "PN" "F2"
						( Origin gPackager )
					)
					( objectStatus "J1F1.F2" )
				)
				( pin "iof4"
					( attribute "PN" "F4"
						( Origin gPackager )
					)
					( objectStatus "J1F1.F4" )
				)
				( pin "iof6"
					( attribute "PN" "F6"
						( Origin gPackager )
					)
					( objectStatus "J1F1.F6" )
				)
				( pin "iof8"
					( attribute "PN" "F8"
						( Origin gPackager )
					)
					( objectStatus "J1F1.F8" )
				)
				( pin "iog1"
					( attribute "PN" "G1"
						( Origin gPackager )
					)
					( objectStatus "J1F1.G1" )
				)
				( pin "iog3"
					( attribute "PN" "G3"
						( Origin gPackager )
					)
					( objectStatus "J1F1.G3" )
				)
				( pin "iog5"
					( attribute "PN" "G5"
						( Origin gPackager )
					)
					( objectStatus "J1F1.G5" )
				)
				( pin "iog7"
					( attribute "PN" "G7"
						( Origin gPackager )
					)
					( objectStatus "J1F1.G7" )
				)
				( pin "ioh1"
					( attribute "PN" "H1"
						( Origin gPackager )
					)
					( objectStatus "J1F1.H1" )
				)
				( pin "ioh2"
					( attribute "PN" "H2"
						( Origin gPackager )
					)
					( objectStatus "J1F1.H2" )
				)
				( pin "ioh3"
					( attribute "PN" "H3"
						( Origin gPackager )
					)
					( objectStatus "J1F1.H3" )
				)
				( pin "ioh4"
					( attribute "PN" "H4"
						( Origin gPackager )
					)
					( objectStatus "J1F1.H4" )
				)
				( pin "ioh5"
					( attribute "PN" "H5"
						( Origin gPackager )
					)
					( objectStatus "J1F1.H5" )
				)
				( pin "ioh6"
					( attribute "PN" "H6"
						( Origin gPackager )
					)
					( objectStatus "J1F1.H6" )
				)
				( pin "ioh7"
					( attribute "PN" "H7"
						( Origin gPackager )
					)
					( objectStatus "J1F1.H7" )
				)
				( pin "ioh8"
					( attribute "PN" "H8"
						( Origin gPackager )
					)
					( objectStatus "J1F1.H8" )
				)
				( pin "ioi2"
					( attribute "PN" "I2"
						( Origin gPackager )
					)
					( objectStatus "J1F1.I2" )
				)
				( pin "ioi4"
					( attribute "PN" "I4"
						( Origin gPackager )
					)
					( objectStatus "J1F1.I4" )
				)
				( pin "ioi6"
					( attribute "PN" "I6"
						( Origin gPackager )
					)
					( objectStatus "J1F1.I6" )
				)
				( pin "ioi8"
					( attribute "PN" "I8"
						( Origin gPackager )
					)
					( objectStatus "J1F1.I8" )
				)
			)
			( gate "@baseboard_fab2_lib.baseboard_fab2(sch_1):page181_i160"
				( attribute "BOM_COST" "IO_SLOT"
					( Origin gFrontEnd )
				)
				( attribute "CDS_LIB" "mstr_discrete"
					( Origin gPackager )
				)
				( attribute "CDS_LOCATION" "C1F4"
					( Origin gPackager )
				)
				( attribute "CDS_SEC" "1"
					( Origin gPackager )
				)
				( attribute "LOCATION" "C1F4"
					( Origin gFrontEnd )
				)
				( attribute "MATERIAL" "X7R"
					( Origin gFrontEnd )
				)
				( attribute "PACK_TYPE" "0402"
					( Origin gFrontEnd )
				)
				( attribute "PART_NUMBER" "A36096-155"
					( Origin gFrontEnd )
				)
				( attribute "PHYS_PAGE" "181"
					( Origin gFrontEnd )
				)
				( attribute "ROOM" "IO_SLOT"
					( Origin gFrontEnd )
				)
				( attribute "ROT" "0"
					( Origin gFrontEnd )
				)
				( attribute "SEC" "1"
					( Origin gFrontEnd )
				)
				( attribute "SEC_TYPE" "0402"
					( Origin gFrontEnd )
				)
				( attribute "TOLERANCE" "10%"
					( Origin gFrontEnd )
				)
				( attribute "VALUE" "0.22UF"
					( Origin gFrontEnd )
				)
				( attribute "VER" "2"
					( Origin gFrontEnd )
				)
				( attribute "VOLTAGE" "16V"
					( Units "uVoltage" "V" 1.000000)
					( Origin gFrontEnd )
				)
				( attribute "XY" "(1025,4050)"
					( Origin gFrontEnd )
				)
				( attribute "CHIPS_PART_NAME" "CAP"
					( Origin gPackager )
				)
				( attribute "CDS_PART_NAME" "CAP_0402-0.22UF,16V,10%,X7R,A3A"
					( Origin gPackager )
				)
				( objectStatus "C1F4" )
				( pin "a"
					( attribute "PN" "1"
						( Origin gPackager )
					)
					( objectStatus "C1F4.1" )
				)
				( pin "b"
					( attribute "PN" "2"
						( Origin gPackager )
					)
					( objectStatus "C1F4.2" )
				)
			)
			( gate "@baseboard_fab2_lib.baseboard_fab2(sch_1):page181_i161"
				( attribute "BOM_COST" "IO_SLOT"
					( Origin gFrontEnd )
				)
				( attribute "CDS_LIB" "mstr_discrete"
					( Origin gPackager )
				)
				( attribute "CDS_LOCATION" "C1F5"
					( Origin gPackager )
				)
				( attribute "CDS_SEC" "1"
					( Origin gPackager )
				)
				( attribute "LOCATION" "C1F5"
					( Origin gFrontEnd )
				)
				( attribute "MATERIAL" "X7R"
					( Origin gFrontEnd )
				)
				( attribute "PACK_TYPE" "0402"
					( Origin gFrontEnd )
				)
				( attribute "PART_NUMBER" "A36096-155"
					( Origin gFrontEnd )
				)
				( attribute "PHYS_PAGE" "181"
					( Origin gFrontEnd )
				)
				( attribute "ROOM" "IO_SLOT"
					( Origin gFrontEnd )
				)
				( attribute "ROT" "0"
					( Origin gFrontEnd )
				)
				( attribute "SEC" "1"
					( Origin gFrontEnd )
				)
				( attribute "SEC_TYPE" "0402"
					( Origin gFrontEnd )
				)
				( attribute "TOLERANCE" "10%"
					( Origin gFrontEnd )
				)
				( attribute "VALUE" "0.22UF"
					( Origin gFrontEnd )
				)
				( attribute "VER" "2"
					( Origin gFrontEnd )
				)
				( attribute "VOLTAGE" "16V"
					( Units "uVoltage" "V" 1.000000)
					( Origin gFrontEnd )
				)
				( attribute "XY" "(600,4000)"
					( Origin gFrontEnd )
				)
				( attribute "CHIPS_PART_NAME" "CAP"
					( Origin gPackager )
				)
				( attribute "CDS_PART_NAME" "CAP_0402-0.22UF,16V,10%,X7R,A3A"
					( Origin gPackager )
				)
				( objectStatus "C1F5" )
				( pin "a"
					( attribute "PN" "1"
						( Origin gPackager )
					)
					( objectStatus "C1F5.1" )
				)
				( pin "b"
					( attribute "PN" "2"
						( Origin gPackager )
					)
					( objectStatus "C1F5.2" )
				)
			)
			( gate "@baseboard_fab2_lib.baseboard_fab2(sch_1):page181_i162"
				( attribute "BOM_COST" "IO_SLOT"
					( Origin gFrontEnd )
				)
				( attribute "CDS_LIB" "mstr_discrete"
					( Origin gPackager )
				)
				( attribute "CDS_LOCATION" "C1F2"
					( Origin gPackager )
				)
				( attribute "CDS_SEC" "1"
					( Origin gPackager )
				)
				( attribute "LOCATION" "C1F2"
					( Origin gFrontEnd )
				)
				( attribute "MATERIAL" "X7R"
					( Origin gFrontEnd )
				)
				( attribute "PACK_TYPE" "0402"
					( Origin gFrontEnd )
				)
				( attribute "PART_NUMBER" "A36096-155"
					( Origin gFrontEnd )
				)
				( attribute "PHYS_PAGE" "181"
					( Origin gFrontEnd )
				)
				( attribute "ROOM" "IO_SLOT"
					( Origin gFrontEnd )
				)
				( attribute "ROT" "0"
					( Origin gFrontEnd )
				)
				( attribute "SEC" "1"
					( Origin gFrontEnd )
				)
				( attribute "SEC_TYPE" "0402"
					( Origin gFrontEnd )
				)
				( attribute "TOLERANCE" "10%"
					( Origin gFrontEnd )
				)
				( attribute "VALUE" "0.22UF"
					( Origin gFrontEnd )
				)
				( attribute "VER" "2"
					( Origin gFrontEnd )
				)
				( attribute "VOLTAGE" "16V"
					( Units "uVoltage" "V" 1.000000)
					( Origin gFrontEnd )
				)
				( attribute "XY" "(1025,3900)"
					( Origin gFrontEnd )
				)
				( attribute "CHIPS_PART_NAME" "CAP"
					( Origin gPackager )
				)
				( attribute "CDS_PART_NAME" "CAP_0402-0.22UF,16V,10%,X7R,A3A"
					( Origin gPackager )
				)
				( objectStatus "C1F2" )
				( pin "a"
					( attribute "PN" "1"
						( Origin gPackager )
					)
					( objectStatus "C1F2.1" )
				)
				( pin "b"
					( attribute "PN" "2"
						( Origin gPackager )
					)
					( objectStatus "C1F2.2" )
				)
			)
			( gate "@baseboard_fab2_lib.baseboard_fab2(sch_1):page181_i163"
				( attribute "BOM_COST" "IO_SLOT"
					( Origin gFrontEnd )
				)
				( attribute "CDS_LIB" "mstr_discrete"
					( Origin gPackager )
				)
				( attribute "CDS_LOCATION" "C1F13"
					( Origin gPackager )
				)
				( attribute "CDS_SEC" "1"
					( Origin gPackager )
				)
				( attribute "LOCATION" "C1F13"
					( Origin gFrontEnd )
				)
				( attribute "MATERIAL" "X7R"
					( Origin gFrontEnd )
				)
				( attribute "PACK_TYPE" "0402"
					( Origin gFrontEnd )
				)
				( attribute "PART_NUMBER" "A36096-155"
					( Origin gFrontEnd )
				)
				( attribute "PHYS_PAGE" "181"
					( Origin gFrontEnd )
				)
				( attribute "ROOM" "IO_SLOT"
					( Origin gFrontEnd )
				)
				( attribute "ROT" "0"
					( Origin gFrontEnd )
				)
				( attribute "SEC" "1"
					( Origin gFrontEnd )
				)
				( attribute "SEC_TYPE" "0402"
					( Origin gFrontEnd )
				)
				( attribute "TOLERANCE" "10%"
					( Origin gFrontEnd )
				)
				( attribute "VALUE" "0.22UF"
					( Origin gFrontEnd )
				)
				( attribute "VER" "2"
					( Origin gFrontEnd )
				)
				( attribute "VOLTAGE" "16V"
					( Units "uVoltage" "V" 1.000000)
					( Origin gFrontEnd )
				)
				( attribute "XY" "(1025,3700)"
					( Origin gFrontEnd )
				)
				( attribute "CHIPS_PART_NAME" "CAP"
					( Origin gPackager )
				)
				( attribute "CDS_PART_NAME" "CAP_0402-0.22UF,16V,10%,X7R,A3A"
					( Origin gPackager )
				)
				( objectStatus "C1F13" )
				( pin "a"
					( attribute "PN" "1"
						( Origin gPackager )
					)
					( objectStatus "C1F13.1" )
				)
				( pin "b"
					( attribute "PN" "2"
						( Origin gPackager )
					)
					( objectStatus "C1F13.2" )
				)
			)
			( gate "@baseboard_fab2_lib.baseboard_fab2(sch_1):page181_i164"
				( attribute "BOM_COST" "IO_SLOT"
					( Origin gFrontEnd )
				)
				( attribute "CDS_LIB" "mstr_discrete"
					( Origin gPackager )
				)
				( attribute "CDS_LOCATION" "C1F10"
					( Origin gPackager )
				)
				( attribute "CDS_SEC" "1"
					( Origin gPackager )
				)
				( attribute "LOCATION" "C1F10"
					( Origin gFrontEnd )
				)
				( attribute "MATERIAL" "X7R"
					( Origin gFrontEnd )
				)
				( attribute "PACK_TYPE" "0402"
					( Origin gFrontEnd )
				)
				( attribute "PART_NUMBER" "A36096-155"
					( Origin gFrontEnd )
				)
				( attribute "PHYS_PAGE" "181"
					( Origin gFrontEnd )
				)
				( attribute "ROOM" "IO_SLOT"
					( Origin gFrontEnd )
				)
				( attribute "ROT" "0"
					( Origin gFrontEnd )
				)
				( attribute "SEC" "1"
					( Origin gFrontEnd )
				)
				( attribute "SEC_TYPE" "0402"
					( Origin gFrontEnd )
				)
				( attribute "TOLERANCE" "10%"
					( Origin gFrontEnd )
				)
				( attribute "VALUE" "0.22UF"
					( Origin gFrontEnd )
				)
				( attribute "VER" "2"
					( Origin gFrontEnd )
				)
				( attribute "VOLTAGE" "16V"
					( Units "uVoltage" "V" 1.000000)
					( Origin gFrontEnd )
				)
				( attribute "XY" "(1050,3550)"
					( Origin gFrontEnd )
				)
				( attribute "CHIPS_PART_NAME" "CAP"
					( Origin gPackager )
				)
				( attribute "CDS_PART_NAME" "CAP_0402-0.22UF,16V,10%,X7R,A3A"
					( Origin gPackager )
				)
				( objectStatus "C1F10" )
				( pin "a"
					( attribute "PN" "1"
						( Origin gPackager )
					)
					( objectStatus "C1F10.1" )
				)
				( pin "b"
					( attribute "PN" "2"
						( Origin gPackager )
					)
					( objectStatus "C1F10.2" )
				)
			)
			( gate "@baseboard_fab2_lib.baseboard_fab2(sch_1):page181_i165"
				( attribute "BOM_COST" "IO_SLOT"
					( Origin gFrontEnd )
				)
				( attribute "CDS_LIB" "mstr_discrete"
					( Origin gPackager )
				)
				( attribute "CDS_LOCATION" "C1F6"
					( Origin gPackager )
				)
				( attribute "CDS_SEC" "1"
					( Origin gPackager )
				)
				( attribute "LOCATION" "C1F6"
					( Origin gFrontEnd )
				)
				( attribute "MATERIAL" "X7R"
					( Origin gFrontEnd )
				)
				( attribute "PACK_TYPE" "0402"
					( Origin gFrontEnd )
				)
				( attribute "PART_NUMBER" "A36096-155"
					( Origin gFrontEnd )
				)
				( attribute "PHYS_PAGE" "181"
					( Origin gFrontEnd )
				)
				( attribute "ROOM" "IO_SLOT"
					( Origin gFrontEnd )
				)
				( attribute "ROT" "0"
					( Origin gFrontEnd )
				)
				( attribute "SEC" "1"
					( Origin gFrontEnd )
				)
				( attribute "SEC_TYPE" "0402"
					( Origin gFrontEnd )
				)
				( attribute "TOLERANCE" "10%"
					( Origin gFrontEnd )
				)
				( attribute "VALUE" "0.22UF"
					( Origin gFrontEnd )
				)
				( attribute "VER" "2"
					( Origin gFrontEnd )
				)
				( attribute "VOLTAGE" "16V"
					( Units "uVoltage" "V" 1.000000)
					( Origin gFrontEnd )
				)
				( attribute "XY" "(1050,3400)"
					( Origin gFrontEnd )
				)
				( attribute "CHIPS_PART_NAME" "CAP"
					( Origin gPackager )
				)
				( attribute "CDS_PART_NAME" "CAP_0402-0.22UF,16V,10%,X7R,A3A"
					( Origin gPackager )
				)
				( objectStatus "C1F6" )
				( pin "a"
					( attribute "PN" "1"
						( Origin gPackager )
					)
					( objectStatus "C1F6.1" )
				)
				( pin "b"
					( attribute "PN" "2"
						( Origin gPackager )
					)
					( objectStatus "C1F6.2" )
				)
			)
			( gate "@baseboard_fab2_lib.baseboard_fab2(sch_1):page181_i166"
				( attribute "BOM_COST" "IO_SLOT"
					( Origin gFrontEnd )
				)
				( attribute "CDS_LIB" "mstr_discrete"
					( Origin gPackager )
				)
				( attribute "CDS_LOCATION" "C1F20"
					( Origin gPackager )
				)
				( attribute "CDS_SEC" "1"
					( Origin gPackager )
				)
				( attribute "LOCATION" "C1F20"
					( Origin gFrontEnd )
				)
				( attribute "MATERIAL" "X7R"
					( Origin gFrontEnd )
				)
				( attribute "PACK_TYPE" "0402"
					( Origin gFrontEnd )
				)
				( attribute "PART_NUMBER" "A36096-155"
					( Origin gFrontEnd )
				)
				( attribute "PHYS_PAGE" "181"
					( Origin gFrontEnd )
				)
				( attribute "ROOM" "IO_SLOT"
					( Origin gFrontEnd )
				)
				( attribute "ROT" "0"
					( Origin gFrontEnd )
				)
				( attribute "SEC" "1"
					( Origin gFrontEnd )
				)
				( attribute "SEC_TYPE" "0402"
					( Origin gFrontEnd )
				)
				( attribute "TOLERANCE" "10%"
					( Origin gFrontEnd )
				)
				( attribute "VALUE" "0.22UF"
					( Origin gFrontEnd )
				)
				( attribute "VER" "2"
					( Origin gFrontEnd )
				)
				( attribute "VOLTAGE" "16V"
					( Units "uVoltage" "V" 1.000000)
					( Origin gFrontEnd )
				)
				( attribute "XY" "(1050,3150)"
					( Origin gFrontEnd )
				)
				( attribute "CHIPS_PART_NAME" "CAP"
					( Origin gPackager )
				)
				( attribute "CDS_PART_NAME" "CAP_0402-0.22UF,16V,10%,X7R,A3A"
					( Origin gPackager )
				)
				( objectStatus "C1F20" )
				( pin "a"
					( attribute "PN" "1"
						( Origin gPackager )
					)
					( objectStatus "C1F20.1" )
				)
				( pin "b"
					( attribute "PN" "2"
						( Origin gPackager )
					)
					( objectStatus "C1F20.2" )
				)
			)
			( gate "@baseboard_fab2_lib.baseboard_fab2(sch_1):page181_i167"
				( attribute "BOM_COST" "IO_SLOT"
					( Origin gFrontEnd )
				)
				( attribute "CDS_LIB" "mstr_discrete"
					( Origin gPackager )
				)
				( attribute "CDS_LOCATION" "C1F3"
					( Origin gPackager )
				)
				( attribute "CDS_SEC" "1"
					( Origin gPackager )
				)
				( attribute "LOCATION" "C1F3"
					( Origin gFrontEnd )
				)
				( attribute "MATERIAL" "X7R"
					( Origin gFrontEnd )
				)
				( attribute "PACK_TYPE" "0402"
					( Origin gFrontEnd )
				)
				( attribute "PART_NUMBER" "A36096-155"
					( Origin gFrontEnd )
				)
				( attribute "PHYS_PAGE" "181"
					( Origin gFrontEnd )
				)
				( attribute "ROOM" "IO_SLOT"
					( Origin gFrontEnd )
				)
				( attribute "ROT" "0"
					( Origin gFrontEnd )
				)
				( attribute "SEC" "1"
					( Origin gFrontEnd )
				)
				( attribute "SEC_TYPE" "0402"
					( Origin gFrontEnd )
				)
				( attribute "TOLERANCE" "10%"
					( Origin gFrontEnd )
				)
				( attribute "VALUE" "0.22UF"
					( Origin gFrontEnd )
				)
				( attribute "VER" "2"
					( Origin gFrontEnd )
				)
				( attribute "VOLTAGE" "16V"
					( Units "uVoltage" "V" 1.000000)
					( Origin gFrontEnd )
				)
				( attribute "XY" "(600,3850)"
					( Origin gFrontEnd )
				)
				( attribute "CHIPS_PART_NAME" "CAP"
					( Origin gPackager )
				)
				( attribute "CDS_PART_NAME" "CAP_0402-0.22UF,16V,10%,X7R,A3A"
					( Origin gPackager )
				)
				( objectStatus "C1F3" )
				( pin "a"
					( attribute "PN" "1"
						( Origin gPackager )
					)
					( objectStatus "C1F3.1" )
				)
				( pin "b"
					( attribute "PN" "2"
						( Origin gPackager )
					)
					( objectStatus "C1F3.2" )
				)
			)
			( gate "@baseboard_fab2_lib.baseboard_fab2(sch_1):page181_i168"
				( attribute "BOM_COST" "IO_SLOT"
					( Origin gFrontEnd )
				)
				( attribute "CDS_LIB" "mstr_discrete"
					( Origin gPackager )
				)
				( attribute "CDS_LOCATION" "C1F12"
					( Origin gPackager )
				)
				( attribute "CDS_SEC" "1"
					( Origin gPackager )
				)
				( attribute "LOCATION" "C1F12"
					( Origin gFrontEnd )
				)
				( attribute "MATERIAL" "X7R"
					( Origin gFrontEnd )
				)
				( attribute "PACK_TYPE" "0402"
					( Origin gFrontEnd )
				)
				( attribute "PART_NUMBER" "A36096-155"
					( Origin gFrontEnd )
				)
				( attribute "PHYS_PAGE" "181"
					( Origin gFrontEnd )
				)
				( attribute "ROOM" "IO_SLOT"
					( Origin gFrontEnd )
				)
				( attribute "ROT" "0"
					( Origin gFrontEnd )
				)
				( attribute "SEC" "1"
					( Origin gFrontEnd )
				)
				( attribute "SEC_TYPE" "0402"
					( Origin gFrontEnd )
				)
				( attribute "TOLERANCE" "10%"
					( Origin gFrontEnd )
				)
				( attribute "VALUE" "0.22UF"
					( Origin gFrontEnd )
				)
				( attribute "VER" "2"
					( Origin gFrontEnd )
				)
				( attribute "VOLTAGE" "16V"
					( Units "uVoltage" "V" 1.000000)
					( Origin gFrontEnd )
				)
				( attribute "XY" "(600,3650)"
					( Origin gFrontEnd )
				)
				( attribute "CHIPS_PART_NAME" "CAP"
					( Origin gPackager )
				)
				( attribute "CDS_PART_NAME" "CAP_0402-0.22UF,16V,10%,X7R,A3A"
					( Origin gPackager )
				)
				( objectStatus "C1F12" )
				( pin "a"
					( attribute "PN" "1"
						( Origin gPackager )
					)
					( objectStatus "C1F12.1" )
				)
				( pin "b"
					( attribute "PN" "2"
						( Origin gPackager )
					)
					( objectStatus "C1F12.2" )
				)
			)
			( gate "@baseboard_fab2_lib.baseboard_fab2(sch_1):page181_i169"
				( attribute "BOM_COST" "IO_SLOT"
					( Origin gFrontEnd )
				)
				( attribute "CDS_LIB" "mstr_discrete"
					( Origin gPackager )
				)
				( attribute "CDS_LOCATION" "C1F11"
					( Origin gPackager )
				)
				( attribute "CDS_SEC" "1"
					( Origin gPackager )
				)
				( attribute "LOCATION" "C1F11"
					( Origin gFrontEnd )
				)
				( attribute "MATERIAL" "X7R"
					( Origin gFrontEnd )
				)
				( attribute "PACK_TYPE" "0402"
					( Origin gFrontEnd )
				)
				( attribute "PART_NUMBER" "A36096-155"
					( Origin gFrontEnd )
				)
				( attribute "PHYS_PAGE" "181"
					( Origin gFrontEnd )
				)
				( attribute "ROOM" "IO_SLOT"
					( Origin gFrontEnd )
				)
				( attribute "ROT" "0"
					( Origin gFrontEnd )
				)
				( attribute "SEC" "1"
					( Origin gFrontEnd )
				)
				( attribute "SEC_TYPE" "0402"
					( Origin gFrontEnd )
				)
				( attribute "TOLERANCE" "10%"
					( Origin gFrontEnd )
				)
				( attribute "VALUE" "0.22UF"
					( Origin gFrontEnd )
				)
				( attribute "VER" "2"
					( Origin gFrontEnd )
				)
				( attribute "VOLTAGE" "16V"
					( Units "uVoltage" "V" 1.000000)
					( Origin gFrontEnd )
				)
				( attribute "XY" "(600,3500)"
					( Origin gFrontEnd )
				)
				( attribute "CHIPS_PART_NAME" "CAP"
					( Origin gPackager )
				)
				( attribute "CDS_PART_NAME" "CAP_0402-0.22UF,16V,10%,X7R,A3A"
					( Origin gPackager )
				)
				( objectStatus "C1F11" )
				( pin "a"
					( attribute "PN" "1"
						( Origin gPackager )
					)
					( objectStatus "C1F11.1" )
				)
				( pin "b"
					( attribute "PN" "2"
						( Origin gPackager )
					)
					( objectStatus "C1F11.2" )
				)
			)
			( gate "@baseboard_fab2_lib.baseboard_fab2(sch_1):page181_i170"
				( attribute "BOM_COST" "IO_SLOT"
					( Origin gFrontEnd )
				)
				( attribute "CDS_LIB" "mstr_discrete"
					( Origin gPackager )
				)
				( attribute "CDS_LOCATION" "C1F8"
					( Origin gPackager )
				)
				( attribute "CDS_SEC" "1"
					( Origin gPackager )
				)
				( attribute "LOCATION" "C1F8"
					( Origin gFrontEnd )
				)
				( attribute "MATERIAL" "X7R"
					( Origin gFrontEnd )
				)
				( attribute "PACK_TYPE" "0402"
					( Origin gFrontEnd )
				)
				( attribute "PART_NUMBER" "A36096-155"
					( Origin gFrontEnd )
				)
				( attribute "PHYS_PAGE" "181"
					( Origin gFrontEnd )
				)
				( attribute "ROOM" "IO_SLOT"
					( Origin gFrontEnd )
				)
				( attribute "ROT" "0"
					( Origin gFrontEnd )
				)
				( attribute "SEC" "1"
					( Origin gFrontEnd )
				)
				( attribute "SEC_TYPE" "0402"
					( Origin gFrontEnd )
				)
				( attribute "TOLERANCE" "10%"
					( Origin gFrontEnd )
				)
				( attribute "VALUE" "0.22UF"
					( Origin gFrontEnd )
				)
				( attribute "VER" "2"
					( Origin gFrontEnd )
				)
				( attribute "VOLTAGE" "16V"
					( Units "uVoltage" "V" 1.000000)
					( Origin gFrontEnd )
				)
				( attribute "XY" "(600,3350)"
					( Origin gFrontEnd )
				)
				( attribute "CHIPS_PART_NAME" "CAP"
					( Origin gPackager )
				)
				( attribute "CDS_PART_NAME" "CAP_0402-0.22UF,16V,10%,X7R,A3A"
					( Origin gPackager )
				)
				( objectStatus "C1F8" )
				( pin "a"
					( attribute "PN" "1"
						( Origin gPackager )
					)
					( objectStatus "C1F8.1" )
				)
				( pin "b"
					( attribute "PN" "2"
						( Origin gPackager )
					)
					( objectStatus "C1F8.2" )
				)
			)
			( gate "@baseboard_fab2_lib.baseboard_fab2(sch_1):page181_i171"
				( attribute "BOM_COST" "IO_SLOT"
					( Origin gFrontEnd )
				)
				( attribute "CDS_LIB" "mstr_discrete"
					( Origin gPackager )
				)
				( attribute "CDS_LOCATION" "C1F18"
					( Origin gPackager )
				)
				( attribute "CDS_SEC" "1"
					( Origin gPackager )
				)
				( attribute "LOCATION" "C1F18"
					( Origin gFrontEnd )
				)
				( attribute "MATERIAL" "X7R"
					( Origin gFrontEnd )
				)
				( attribute "PACK_TYPE" "0402"
					( Origin gFrontEnd )
				)
				( attribute "PART_NUMBER" "A36096-155"
					( Origin gFrontEnd )
				)
				( attribute "PHYS_PAGE" "181"
					( Origin gFrontEnd )
				)
				( attribute "ROOM" "IO_SLOT"
					( Origin gFrontEnd )
				)
				( attribute "ROT" "0"
					( Origin gFrontEnd )
				)
				( attribute "SEC" "1"
					( Origin gFrontEnd )
				)
				( attribute "SEC_TYPE" "0402"
					( Origin gFrontEnd )
				)
				( attribute "TOLERANCE" "10%"
					( Origin gFrontEnd )
				)
				( attribute "VALUE" "0.22UF"
					( Origin gFrontEnd )
				)
				( attribute "VER" "2"
					( Origin gFrontEnd )
				)
				( attribute "VOLTAGE" "16V"
					( Units "uVoltage" "V" 1.000000)
					( Origin gFrontEnd )
				)
				( attribute "XY" "(550,3100)"
					( Origin gFrontEnd )
				)
				( attribute "CHIPS_PART_NAME" "CAP"
					( Origin gPackager )
				)
				( attribute "CDS_PART_NAME" "CAP_0402-0.22UF,16V,10%,X7R,A3A"
					( Origin gPackager )
				)
				( objectStatus "C1F18" )
				( pin "a"
					( attribute "PN" "1"
						( Origin gPackager )
					)
					( objectStatus "C1F18.1" )
				)
				( pin "b"
					( attribute "PN" "2"
						( Origin gPackager )
					)
					( objectStatus "C1F18.2" )
				)
			)
			( gate "@baseboard_fab2_lib.baseboard_fab2(sch_1):page181_i172"
				( attribute "BOM_COST" "IO_SLOT"
					( Origin gFrontEnd )
				)
				( attribute "CDS_LIB" "mstr_discrete"
					( Origin gPackager )
				)
				( attribute "CDS_LOCATION" "C1F16"
					( Origin gPackager )
				)
				( attribute "CDS_SEC" "1"
					( Origin gPackager )
				)
				( attribute "LOCATION" "C1F16"
					( Origin gFrontEnd )
				)
				( attribute "MATERIAL" "X7R"
					( Origin gFrontEnd )
				)
				( attribute "PACK_TYPE" "0402"
					( Origin gFrontEnd )
				)
				( attribute "PART_NUMBER" "A36096-155"
					( Origin gFrontEnd )
				)
				( attribute "PHYS_PAGE" "181"
					( Origin gFrontEnd )
				)
				( attribute "ROOM" "IO_SLOT"
					( Origin gFrontEnd )
				)
				( attribute "ROT" "0"
					( Origin gFrontEnd )
				)
				( attribute "SEC" "1"
					( Origin gFrontEnd )
				)
				( attribute "SEC_TYPE" "0402"
					( Origin gFrontEnd )
				)
				( attribute "TOLERANCE" "10%"
					( Origin gFrontEnd )
				)
				( attribute "VALUE" "0.22UF"
					( Origin gFrontEnd )
				)
				( attribute "VER" "2"
					( Origin gFrontEnd )
				)
				( attribute "VOLTAGE" "16V"
					( Units "uVoltage" "V" 1.000000)
					( Origin gFrontEnd )
				)
				( attribute "XY" "(1050,3000)"
					( Origin gFrontEnd )
				)
				( attribute "CHIPS_PART_NAME" "CAP"
					( Origin gPackager )
				)
				( attribute "CDS_PART_NAME" "CAP_0402-0.22UF,16V,10%,X7R,A3A"
					( Origin gPackager )
				)
				( objectStatus "C1F16" )
				( pin "a"
					( attribute "PN" "1"
						( Origin gPackager )
					)
					( objectStatus "C1F16.1" )
				)
				( pin "b"
					( attribute "PN" "2"
						( Origin gPackager )
					)
					( objectStatus "C1F16.2" )
				)
			)
			( gate "@baseboard_fab2_lib.baseboard_fab2(sch_1):page181_i173"
				( attribute "BOM_COST" "IO_SLOT"
					( Origin gFrontEnd )
				)
				( attribute "CDS_LIB" "mstr_discrete"
					( Origin gPackager )
				)
				( attribute "CDS_LOCATION" "C1F17"
					( Origin gPackager )
				)
				( attribute "CDS_SEC" "1"
					( Origin gPackager )
				)
				( attribute "LOCATION" "C1F17"
					( Origin gFrontEnd )
				)
				( attribute "MATERIAL" "X7R"
					( Origin gFrontEnd )
				)
				( attribute "PACK_TYPE" "0402"
					( Origin gFrontEnd )
				)
				( attribute "PART_NUMBER" "A36096-155"
					( Origin gFrontEnd )
				)
				( attribute "PHYS_PAGE" "181"
					( Origin gFrontEnd )
				)
				( attribute "ROOM" "IO_SLOT"
					( Origin gFrontEnd )
				)
				( attribute "ROT" "0"
					( Origin gFrontEnd )
				)
				( attribute "SEC" "1"
					( Origin gFrontEnd )
				)
				( attribute "SEC_TYPE" "0402"
					( Origin gFrontEnd )
				)
				( attribute "TOLERANCE" "10%"
					( Origin gFrontEnd )
				)
				( attribute "VALUE" "0.22UF"
					( Origin gFrontEnd )
				)
				( attribute "VER" "2"
					( Origin gFrontEnd )
				)
				( attribute "VOLTAGE" "16V"
					( Units "uVoltage" "V" 1.000000)
					( Origin gFrontEnd )
				)
				( attribute "XY" "(550,2950)"
					( Origin gFrontEnd )
				)
				( attribute "CHIPS_PART_NAME" "CAP"
					( Origin gPackager )
				)
				( attribute "CDS_PART_NAME" "CAP_0402-0.22UF,16V,10%,X7R,A3A"
					( Origin gPackager )
				)
				( objectStatus "C1F17" )
				( pin "a"
					( attribute "PN" "1"
						( Origin gPackager )
					)
					( objectStatus "C1F17.1" )
				)
				( pin "b"
					( attribute "PN" "2"
						( Origin gPackager )
					)
					( objectStatus "C1F17.2" )
				)
			)
			( gate "@baseboard_fab2_lib.baseboard_fab2(sch_1):page181_i174"
				( attribute "BOM_COST" "IO_SLOT"
					( Origin gFrontEnd )
				)
				( attribute "CDS_LIB" "mstr_discrete"
					( Origin gPackager )
				)
				( attribute "CDS_LOCATION" "C1F15"
					( Origin gPackager )
				)
				( attribute "CDS_SEC" "1"
					( Origin gPackager )
				)
				( attribute "LOCATION" "C1F15"
					( Origin gFrontEnd )
				)
				( attribute "MATERIAL" "X7R"
					( Origin gFrontEnd )
				)
				( attribute "PACK_TYPE" "0402"
					( Origin gFrontEnd )
				)
				( attribute "PART_NUMBER" "A36096-155"
					( Origin gFrontEnd )
				)
				( attribute "PHYS_PAGE" "181"
					( Origin gFrontEnd )
				)
				( attribute "ROOM" "IO_SLOT"
					( Origin gFrontEnd )
				)
				( attribute "ROT" "0"
					( Origin gFrontEnd )
				)
				( attribute "SEC" "1"
					( Origin gFrontEnd )
				)
				( attribute "SEC_TYPE" "0402"
					( Origin gFrontEnd )
				)
				( attribute "TOLERANCE" "10%"
					( Origin gFrontEnd )
				)
				( attribute "VALUE" "0.22UF"
					( Origin gFrontEnd )
				)
				( attribute "VER" "2"
					( Origin gFrontEnd )
				)
				( attribute "VOLTAGE" "16V"
					( Units "uVoltage" "V" 1.000000)
					( Origin gFrontEnd )
				)
				( attribute "XY" "(1050,2850)"
					( Origin gFrontEnd )
				)
				( attribute "CHIPS_PART_NAME" "CAP"
					( Origin gPackager )
				)
				( attribute "CDS_PART_NAME" "CAP_0402-0.22UF,16V,10%,X7R,A3A"
					( Origin gPackager )
				)
				( objectStatus "C1F15" )
				( pin "a"
					( attribute "PN" "1"
						( Origin gPackager )
					)
					( objectStatus "C1F15.1" )
				)
				( pin "b"
					( attribute "PN" "2"
						( Origin gPackager )
					)
					( objectStatus "C1F15.2" )
				)
			)
			( gate "@baseboard_fab2_lib.baseboard_fab2(sch_1):page181_i175"
				( attribute "BOM_COST" "IO_SLOT"
					( Origin gFrontEnd )
				)
				( attribute "CDS_LIB" "mstr_discrete"
					( Origin gPackager )
				)
				( attribute "CDS_LOCATION" "C1F14"
					( Origin gPackager )
				)
				( attribute "CDS_SEC" "1"
					( Origin gPackager )
				)
				( attribute "LOCATION" "C1F14"
					( Origin gFrontEnd )
				)
				( attribute "MATERIAL" "X7R"
					( Origin gFrontEnd )
				)
				( attribute "PACK_TYPE" "0402"
					( Origin gFrontEnd )
				)
				( attribute "PART_NUMBER" "A36096-155"
					( Origin gFrontEnd )
				)
				( attribute "PHYS_PAGE" "181"
					( Origin gFrontEnd )
				)
				( attribute "ROOM" "IO_SLOT"
					( Origin gFrontEnd )
				)
				( attribute "ROT" "0"
					( Origin gFrontEnd )
				)
				( attribute "SEC" "1"
					( Origin gFrontEnd )
				)
				( attribute "SEC_TYPE" "0402"
					( Origin gFrontEnd )
				)
				( attribute "TOLERANCE" "10%"
					( Origin gFrontEnd )
				)
				( attribute "VALUE" "0.22UF"
					( Origin gFrontEnd )
				)
				( attribute "VER" "2"
					( Origin gFrontEnd )
				)
				( attribute "VOLTAGE" "16V"
					( Units "uVoltage" "V" 1.000000)
					( Origin gFrontEnd )
				)
				( attribute "XY" "(550,2800)"
					( Origin gFrontEnd )
				)
				( attribute "CHIPS_PART_NAME" "CAP"
					( Origin gPackager )
				)
				( attribute "CDS_PART_NAME" "CAP_0402-0.22UF,16V,10%,X7R,A3A"
					( Origin gPackager )
				)
				( objectStatus "C1F14" )
				( pin "a"
					( attribute "PN" "1"
						( Origin gPackager )
					)
					( objectStatus "C1F14.1" )
				)
				( pin "b"
					( attribute "PN" "2"
						( Origin gPackager )
					)
					( objectStatus "C1F14.2" )
				)
			)
			( gate "@baseboard_fab2_lib.baseboard_fab2(sch_1):page181_i177"
				( attribute "BOM_COST" "IO_SLOT"
					( Origin gFrontEnd )
				)
				( attribute "CDS_LIB" "mstr_discrete"
					( Origin gPackager )
				)
				( attribute "CDS_LOCATION" "R9T9"
					( Origin gPackager )
				)
				( attribute "CDS_SEC" "1"
					( Origin gPackager )
				)
				( attribute "LOCATION" "R9T9"
					( Origin gFrontEnd )
				)
				( attribute "MATERIAL" "CHIP"
					( Origin gFrontEnd )
				)
				( attribute "PACK_TYPE" "0402"
					( Origin gFrontEnd )
				)
				( attribute "PART_NUMBER" "G21796-072"
					( Origin gFrontEnd )
				)
				( attribute "PHYS_PAGE" "181"
					( Origin gFrontEnd )
				)
				( attribute "ROOM" "IO_SLOT"
					( Origin gFrontEnd )
				)
				( attribute "ROT" "0"
					( Origin gFrontEnd )
				)
				( attribute "SEC" "1"
					( Origin gFrontEnd )
				)
				( attribute "SEC_TYPE" "0402"
					( Origin gFrontEnd )
				)
				( attribute "TOLERANCE" "1%"
					( Origin gFrontEnd )
				)
				( attribute "VALUE" "4.75K"
					( Origin gFrontEnd )
				)
				( attribute "VER" "2"
					( Origin gFrontEnd )
				)
				( attribute "WATTAGE" "1/16W"
					( Origin gFrontEnd )
				)
				( attribute "XY" "(-2600,2100)"
					( Origin gFrontEnd )
				)
				( attribute "CHIPS_PART_NAME" "RES"
					( Origin gPackager )
				)
				( attribute "CDS_PART_NAME" "RES_0402-4.75K,1%,1/16W,CHIP,GA"
					( Origin gPackager )
				)
				( objectStatus "R9T9" )
				( pin "a"
					( attribute "PN" "1"
						( Origin gPackager )
					)
					( objectStatus "R9T9.1" )
				)
				( pin "b"
					( attribute "PN" "2"
						( Origin gPackager )
					)
					( objectStatus "R9T9.2" )
				)
			)
			( gate "@baseboard_fab2_lib.baseboard_fab2(sch_1):page181_i178"
				( attribute "BOM_COST" "IO_SLOT"
					( Origin gFrontEnd )
				)
				( attribute "CDS_LIB" "mstr_discrete"
					( Origin gPackager )
				)
				( attribute "CDS_LOCATION" "CR1F4"
					( Origin gPackager )
				)
				( attribute "CDS_SEC" "1"
					( Origin gPackager )
				)
				( attribute "LOCATION" "CR1F4"
					( Origin gFrontEnd )
				)
				( attribute "MATERIAL" "IC"
					( Origin gFrontEnd )
				)
				( attribute "PACK_TYPE" "SM"
					( Origin gFrontEnd )
				)
				( attribute "PART_NUMBER" "H71799-001"
					( Origin gFrontEnd )
				)
				( attribute "PHYS_PAGE" "181"
					( Origin gFrontEnd )
				)
				( attribute "ROOM" "IO_SLOT"
					( Origin gFrontEnd )
				)
				( attribute "ROT" "0"
					( Origin gFrontEnd )
				)
				( attribute "SEC" "1"
					( Origin gFrontEnd )
				)
				( attribute "SEC_TYPE" "SM"
					( Origin gFrontEnd )
				)
				( attribute "VALUE" "SDMK0340L"
					( Origin gFrontEnd )
				)
				( attribute "VER" "1"
					( Origin gFrontEnd )
				)
				( attribute "XY" "(-2275,1800)"
					( Origin gFrontEnd )
				)
				( attribute "CHIPS_PART_NAME" "DIODE"
					( Origin gPackager )
				)
				( attribute "CDS_PART_NAME" "DIODE_SM-SDMK0340L,IC,H71799-0A"
					( Origin gPackager )
				)
				( objectStatus "CR1F4" )
				( pin "a"
					( attribute "PN" "2"
						( Origin gPackager )
					)
					( objectStatus "CR1F4.2" )
				)
				( pin "c"
					( attribute "PN" "1"
						( Origin gPackager )
					)
					( objectStatus "CR1F4.1" )
				)
			)
			( gate "@baseboard_fab2_lib.baseboard_fab2(sch_1):page181_i180"
				( attribute "BOM_COST" "IO_SLOT"
					( Origin gFrontEnd )
				)
				( attribute "CDS_LIB" "mstr_discrete"
					( Origin gPackager )
				)
				( attribute "CDS_LOCATION" "CR1F3"
					( Origin gPackager )
				)
				( attribute "CDS_SEC" "1"
					( Origin gPackager )
				)
				( attribute "LOCATION" "CR1F3"
					( Origin gFrontEnd )
				)
				( attribute "MATERIAL" "IC"
					( Origin gFrontEnd )
				)
				( attribute "PACK_TYPE" "SM"
					( Origin gFrontEnd )
				)
				( attribute "PART_NUMBER" "H71799-001"
					( Origin gFrontEnd )
				)
				( attribute "PHYS_PAGE" "181"
					( Origin gFrontEnd )
				)
				( attribute "ROOM" "IO_SLOT"
					( Origin gFrontEnd )
				)
				( attribute "ROT" "0"
					( Origin gFrontEnd )
				)
				( attribute "SEC" "1"
					( Origin gFrontEnd )
				)
				( attribute "SEC_TYPE" "SM"
					( Origin gFrontEnd )
				)
				( attribute "VALUE" "SDMK0340L"
					( Origin gFrontEnd )
				)
				( attribute "VER" "1"
					( Origin gFrontEnd )
				)
				( attribute "XY" "(-1025,1800)"
					( Origin gFrontEnd )
				)
				( attribute "CHIPS_PART_NAME" "DIODE"
					( Origin gPackager )
				)
				( attribute "CDS_PART_NAME" "DIODE_SM-SDMK0340L,IC,H71799-0A"
					( Origin gPackager )
				)
				( objectStatus "CR1F3" )
				( pin "a"
					( attribute "PN" "2"
						( Origin gPackager )
					)
					( objectStatus "CR1F3.2" )
				)
				( pin "c"
					( attribute "PN" "1"
						( Origin gPackager )
					)
					( objectStatus "CR1F3.1" )
				)
			)
			( gate "@baseboard_fab2_lib.baseboard_fab2(sch_1):page181_i181"
				( attribute "CDS_LIB" "mstr_discrete"
					( Origin gPackager )
				)
				( attribute "CDS_LOCATION" "Q9T1"
					( Origin gPackager )
				)
				( attribute "CDS_SEC" "1"
					( Origin gPackager )
				)
				( attribute "LOCATION" "Q9T1"
					( Origin gFrontEnd )
				)
				( attribute "MATERIAL" "IC"
					( Origin gFrontEnd )
				)
				( attribute "PACK_TYPE" "SM"
					( Origin gFrontEnd )
				)
				( attribute "PART_NUMBER" "C52245-001"
					( Origin gFrontEnd )
				)
				( attribute "PHYS_PAGE" "181"
					( Origin gFrontEnd )
				)
				( attribute "ROOM" "SB"
					( Origin gFrontEnd )
				)
				( attribute "ROT" "0"
					( Origin gFrontEnd )
				)
				( attribute "SEC" "1"
					( Origin gFrontEnd )
				)
				( attribute "SEC_TYPE" "SM"
					( Origin gFrontEnd )
				)
				( attribute "VALUE" "MMBT3904"
					( Origin gFrontEnd )
				)
				( attribute "VER" "1"
					( Origin gFrontEnd )
				)
				( attribute "XY" "(50,1800)"
					( Origin gFrontEnd )
				)
				( attribute "CHIPS_PART_NAME" "NPN"
					( Origin gPackager )
				)
				( attribute "CDS_PART_NAME" "NPN_SM-MMBT3904,IC,C52245-001"
					( Origin gPackager )
				)
				( objectStatus "Q9T1" )
				( pin "b"
					( attribute "PN" "1"
						( Origin gPackager )
					)
					( objectStatus "Q9T1.1" )
				)
				( pin "c"
					( attribute "PN" "3"
						( Origin gPackager )
					)
					( objectStatus "Q9T1.3" )
				)
				( pin "e"
					( attribute "PN" "2"
						( Origin gPackager )
					)
					( objectStatus "Q9T1.2" )
				)
			)
			( gate "@baseboard_fab2_lib.baseboard_fab2(sch_1):page181_i183"
				( attribute "BOM_COST" "IO_SLOT"
					( Origin gFrontEnd )
				)
				( attribute "CDS_LIB" "mstr_discrete"
					( Origin gPackager )
				)
				( attribute "CDS_LOCATION" "R9T6"
					( Origin gPackager )
				)
				( attribute "CDS_SEC" "1"
					( Origin gPackager )
				)
				( attribute "LOCATION" "R9T6"
					( Origin gFrontEnd )
				)
				( attribute "MATERIAL" "CHIP"
					( Origin gFrontEnd )
				)
				( attribute "PACK_TYPE" "0402"
					( Origin gFrontEnd )
				)
				( attribute "PART_NUMBER" "G21796-107"
					( Origin gFrontEnd )
				)
				( attribute "PHYS_PAGE" "181"
					( Origin gFrontEnd )
				)
				( attribute "ROOM" "IO_SLOT"
					( Origin gFrontEnd )
				)
				( attribute "ROT" "2"
					( Origin gFrontEnd )
				)
				( attribute "SEC" "1"
					( Origin gFrontEnd )
				)
				( attribute "SEC_TYPE" "0402"
					( Origin gFrontEnd )
				)
				( attribute "TOLERANCE" "1%"
					( Origin gFrontEnd )
				)
				( attribute "VALUE" "15.0K"
					( Origin gFrontEnd )
				)
				( attribute "VER" "2"
					( Origin gFrontEnd )
				)
				( attribute "WATTAGE" "1/16W"
					( Origin gFrontEnd )
				)
				( attribute "XY" "(450,2150)"
					( Origin gFrontEnd )
				)
				( attribute "CHIPS_PART_NAME" "RES"
					( Origin gPackager )
				)
				( attribute "CDS_PART_NAME" "RES_0402-15.0K,1%,1/16W,CHIP,GA"
					( Origin gPackager )
				)
				( objectStatus "R9T6" )
				( pin "a"
					( attribute "PN" "1"
						( Origin gPackager )
					)
					( objectStatus "R9T6.1" )
				)
				( pin "b"
					( attribute "PN" "2"
						( Origin gPackager )
					)
					( objectStatus "R9T6.2" )
				)
			)
			( gate "@baseboard_fab2_lib.baseboard_fab2(sch_1):page181_i185"
				( attribute "BOM_COST" "IO_SLOT"
					( Origin gFrontEnd )
				)
				( attribute "CDS_LIB" "mstr_discrete"
					( Origin gPackager )
				)
				( attribute "CDS_LOCATION" "R9T3"
					( Origin gPackager )
				)
				( attribute "CDS_SEC" "1"
					( Origin gPackager )
				)
				( attribute "LOCATION" "R9T3"
					( Origin gFrontEnd )
				)
				( attribute "MATERIAL" "CHIP"
					( Origin gFrontEnd )
				)
				( attribute "PACK_TYPE" "0402"
					( Origin gFrontEnd )
				)
				( attribute "PART_NUMBER" "G21796-161"
					( Origin gFrontEnd )
				)
				( attribute "PHYS_PAGE" "181"
					( Origin gFrontEnd )
				)
				( attribute "ROOM" "IO_SLOT"
					( Origin gFrontEnd )
				)
				( attribute "ROT" "0"
					( Origin gFrontEnd )
				)
				( attribute "SEC" "1"
					( Origin gFrontEnd )
				)
				( attribute "SEC_TYPE" "0402"
					( Origin gFrontEnd )
				)
				( attribute "TOLERANCE" "1%"
					( Origin gFrontEnd )
				)
				( attribute "VALUE" "6.19K"
					( Origin gFrontEnd )
				)
				( attribute "VER" "2"
					( Origin gFrontEnd )
				)
				( attribute "WATTAGE" "1/16W"
					( Origin gFrontEnd )
				)
				( attribute "XY" "(550,1800)"
					( Origin gFrontEnd )
				)
				( attribute "CHIPS_PART_NAME" "RES"
					( Origin gPackager )
				)
				( attribute "CDS_PART_NAME" "RES_0402-6.19K,1%,1/16W,CHIP,GA"
					( Origin gPackager )
				)
				( objectStatus "R9T3" )
				( pin "a"
					( attribute "PN" "1"
						( Origin gPackager )
					)
					( objectStatus "R9T3.1" )
				)
				( pin "b"
					( attribute "PN" "2"
						( Origin gPackager )
					)
					( objectStatus "R9T3.2" )
				)
			)
			( gate "@baseboard_fab2_lib.baseboard_fab2(sch_1):page181_i189"
				( attribute "CDS_LIB" "mstr_conn"
					( Origin gPackager )
				)
				( attribute "CDS_LOCATION" "J1F3"
					( Origin gPackager )
				)
				( attribute "CDS_SEC" "1"
					( Origin gPackager )
				)
				( attribute "LOCATION" "J1F3"
					( Origin gFrontEnd )
				)
				( attribute "MATERIAL" "CONN"
					( Origin gFrontEnd )
				)
				( attribute "PACK_TYPE" "PIP"
					( Origin gFrontEnd )
				)
				( attribute "PART_NUMBER" "H62179-001"
					( Origin gFrontEnd )
				)
				( attribute "PHYS_PAGE" "181"
					( Origin gFrontEnd )
				)
				( attribute "ROOM" "IO_SLOT"
					( Origin gFrontEnd )
				)
				( attribute "ROT" "0"
					( Origin gFrontEnd )
				)
				( attribute "SEC" "1"
					( Origin gPackager )
				)
				( attribute "VER" "1"
					( Origin gFrontEnd )
				)
				( attribute "XY" "(3500,1500)"
					( Origin gFrontEnd )
				)
				( attribute "CHIPS_PART_NAME" "CONN8_H62179001"
					( Origin gPackager )
				)
				( attribute "CDS_PART_NAME" "CONN8_H62179001_PIP-CONN,H6217A"
					( Origin gPackager )
				)
				( objectStatus "J1F3" )
				( pin "io1"
					( attribute "PN" "1"
						( Origin gPackager )
					)
					( objectStatus "J1F3.1" )
				)
				( pin "io2"
					( attribute "PN" "2"
						( Origin gPackager )
					)
					( objectStatus "J1F3.2" )
				)
				( pin "io3"
					( attribute "PN" "3"
						( Origin gPackager )
					)
					( objectStatus "J1F3.3" )
				)
				( pin "io4"
					( attribute "PN" "4"
						( Origin gPackager )
					)
					( objectStatus "J1F3.4" )
				)
				( pin "io5"
					( attribute "PN" "5"
						( Origin gPackager )
					)
					( objectStatus "J1F3.5" )
				)
				( pin "io6"
					( attribute "PN" "6"
						( Origin gPackager )
					)
					( objectStatus "J1F3.6" )
				)
				( pin "io7"
					( attribute "PN" "7"
						( Origin gPackager )
					)
					( objectStatus "J1F3.7" )
				)
				( pin "io8"
					( attribute "PN" "8"
						( Origin gPackager )
					)
					( objectStatus "J1F3.8" )
				)
			)
			( gate "@baseboard_fab2_lib.baseboard_fab2(sch_1):page181_i199"
				( attribute "CDS_LIB" "mstr_discrete"
					( Origin gPackager )
				)
				( attribute "CDS_LOCATION" "R7D5"
					( Origin gPackager )
				)
				( attribute "CDS_SEC" "1"
					( Origin gPackager )
				)
				( attribute "LOCATION" "R7D5"
					( Origin gFrontEnd )
				)
				( attribute "MATERIAL" "CHIP"
					( Origin gFrontEnd )
				)
				( attribute "PACK_TYPE" "0402"
					( Origin gFrontEnd )
				)
				( attribute "PART_NUMBER" "G21796-311"
					( Origin gFrontEnd )
				)
				( attribute "PHYS_PAGE" "181"
					( Origin gFrontEnd )
				)
				( attribute "ROOM" "IO_SLOT"
					( Origin gFrontEnd )
				)
				( attribute "ROT" "0"
					( Origin gFrontEnd )
				)
				( attribute "SEC" "1"
					( Origin gFrontEnd )
				)
				( attribute "SEC_TYPE" "0402"
					( Origin gFrontEnd )
				)
				( attribute "TOLERANCE" "1.0%"
					( Origin gFrontEnd )
				)
				( attribute "VALUE" "2.26K"
					( Origin gFrontEnd )
				)
				( attribute "VER" "1"
					( Origin gFrontEnd )
				)
				( attribute "WATTAGE" "1/16W"
					( Origin gFrontEnd )
				)
				( attribute "XY" "(2050,2475)"
					( Origin gFrontEnd )
				)
				( attribute "CHIPS_PART_NAME" "RES"
					( Origin gPackager )
				)
				( attribute "CDS_PART_NAME" "RES_0402-2.26K,1.0%,1/16W,CHIPA"
					( Origin gPackager )
				)
				( objectStatus "R7D5" )
				( pin "a"
					( attribute "PN" "1"
						( Origin gPackager )
					)
					( objectStatus "R7D5.1" )
				)
				( pin "b"
					( attribute "PN" "2"
						( Origin gPackager )
					)
					( objectStatus "R7D5.2" )
				)
			)
			( gate "@baseboard_fab2_lib.baseboard_fab2(sch_1):page181_i200"
				( attribute "CDS_LIB" "mstr_discrete"
					( Origin gPackager )
				)
				( attribute "CDS_LOCATION" "R7D9"
					( Origin gPackager )
				)
				( attribute "CDS_SEC" "1"
					( Origin gPackager )
				)
				( attribute "LOCATION" "R7D9"
					( Origin gFrontEnd )
				)
				( attribute "MATERIAL" "CHIP"
					( Origin gFrontEnd )
				)
				( attribute "PACK_TYPE" "0402"
					( Origin gFrontEnd )
				)
				( attribute "PART_NUMBER" "G21796-311"
					( Origin gFrontEnd )
				)
				( attribute "PHYS_PAGE" "181"
					( Origin gFrontEnd )
				)
				( attribute "ROOM" "IO_SLOT"
					( Origin gFrontEnd )
				)
				( attribute "ROT" "0"
					( Origin gFrontEnd )
				)
				( attribute "SEC" "1"
					( Origin gFrontEnd )
				)
				( attribute "SEC_TYPE" "0402"
					( Origin gFrontEnd )
				)
				( attribute "TOLERANCE" "1.0%"
					( Origin gFrontEnd )
				)
				( attribute "VALUE" "2.26K"
					( Origin gFrontEnd )
				)
				( attribute "VER" "1"
					( Origin gFrontEnd )
				)
				( attribute "WATTAGE" "1/16W"
					( Origin gFrontEnd )
				)
				( attribute "XY" "(2050,2300)"
					( Origin gFrontEnd )
				)
				( attribute "CHIPS_PART_NAME" "RES"
					( Origin gPackager )
				)
				( attribute "CDS_PART_NAME" "RES_0402-2.26K,1.0%,1/16W,CHIPA"
					( Origin gPackager )
				)
				( objectStatus "R7D9" )
				( pin "a"
					( attribute "PN" "1"
						( Origin gPackager )
					)
					( objectStatus "R7D9.1" )
				)
				( pin "b"
					( attribute "PN" "2"
						( Origin gPackager )
					)
					( objectStatus "R7D9.2" )
				)
			)
			( gate "@baseboard_fab2_lib.baseboard_fab2(sch_1):page181_i201"
				( attribute "CDS_LIB" "mstr_discrete"
					( Origin gPackager )
				)
				( attribute "CDS_LOCATION" "R3P61"
					( Origin gPackager )
				)
				( attribute "CDS_SEC" "1"
					( Origin gPackager )
				)
				( attribute "LOCATION" "R3P61"
					( Origin gFrontEnd )
				)
				( attribute "MATERIAL" "CHIP"
					( Origin gFrontEnd )
				)
				( attribute "PACK_TYPE" "0402"
					( Origin gFrontEnd )
				)
				( attribute "PART_NUMBER" "G21796-311"
					( Origin gFrontEnd )
				)
				( attribute "PHYS_PAGE" "181"
					( Origin gFrontEnd )
				)
				( attribute "ROOM" "IO_SLOT"
					( Origin gFrontEnd )
				)
				( attribute "ROT" "0"
					( Origin gFrontEnd )
				)
				( attribute "SEC" "1"
					( Origin gFrontEnd )
				)
				( attribute "SEC_TYPE" "0402"
					( Origin gFrontEnd )
				)
				( attribute "TOLERANCE" "1.0%"
					( Origin gFrontEnd )
				)
				( attribute "VALUE" "2.26K"
					( Origin gFrontEnd )
				)
				( attribute "VER" "1"
					( Origin gFrontEnd )
				)
				( attribute "WATTAGE" "1/16W"
					( Origin gFrontEnd )
				)
				( attribute "XY" "(2050,2125)"
					( Origin gFrontEnd )
				)
				( attribute "CHIPS_PART_NAME" "RES"
					( Origin gPackager )
				)
				( attribute "CDS_PART_NAME" "RES_0402-2.26K,1.0%,1/16W,CHIPA"
					( Origin gPackager )
				)
				( objectStatus "R3P61" )
				( pin "a"
					( attribute "PN" "1"
						( Origin gPackager )
					)
					( objectStatus "R3P61.1" )
				)
				( pin "b"
					( attribute "PN" "2"
						( Origin gPackager )
					)
					( objectStatus "R3P61.2" )
				)
			)
			( gate "@baseboard_fab2_lib.baseboard_fab2(sch_1):page181_i218"
				( attribute "CDS_LIB" "mstr_discrete"
					( Origin gPackager )
				)
				( attribute "CDS_LOCATION" "R8E5"
					( Origin gPackager )
				)
				( attribute "CDS_SEC" "1"
					( Origin gPackager )
				)
				( attribute "LOCATION" "R8E5"
					( Origin gFrontEnd )
				)
				( attribute "MATERIAL" "CHIP"
					( Origin gFrontEnd )
				)
				( attribute "PACK_TYPE" "0402"
					( Origin gFrontEnd )
				)
				( attribute "PART_NUMBER" "G21796-074"
					( Origin gFrontEnd )
				)
				( attribute "PHYS_PAGE" "181"
					( Origin gFrontEnd )
				)
				( attribute "ROOM" "IO_SLOT"
					( Origin gFrontEnd )
				)
				( attribute "ROT" "0"
					( Origin gFrontEnd )
				)
				( attribute "SEC" "1"
					( Origin gFrontEnd )
				)
				( attribute "SEC_TYPE" "0402"
					( Origin gFrontEnd )
				)
				( attribute "TOLERANCE" "1%"
					( Origin gFrontEnd )
				)
				( attribute "VALUE" "33.2"
					( Origin gFrontEnd )
				)
				( attribute "VER" "1"
					( Origin gFrontEnd )
				)
				( attribute "WATTAGE" "1/16W"
					( Origin gFrontEnd )
				)
				( attribute "XY" "(1050,1075)"
					( Origin gFrontEnd )
				)
				( attribute "CHIPS_PART_NAME" "RES"
					( Origin gPackager )
				)
				( attribute "CDS_PART_NAME" "RES_0402-33.2,1%,1/16W,CHIP,G2A"
					( Origin gPackager )
				)
				( objectStatus "R8E5" )
				( pin "a"
					( attribute "PN" "1"
						( Origin gPackager )
					)
					( objectStatus "R8E5.1" )
				)
				( pin "b"
					( attribute "PN" "2"
						( Origin gPackager )
					)
					( objectStatus "R8E5.2" )
				)
			)
			( gate "@baseboard_fab2_lib.baseboard_fab2(sch_1):page181_i224"
				( attribute "CDS_LIB" "mstr_discrete"
					( Origin gPackager )
				)
				( attribute "CDS_LOCATION" "C2R6"
					( Origin gPackager )
				)
				( attribute "CDS_SEC" "1"
					( Origin gPackager )
				)
				( attribute "LOCATION" "C2R6"
					( Origin gFrontEnd )
				)
				( attribute "MATERIAL" "EMPTY"
					( Origin gFrontEnd )
				)
				( attribute "PACK_TYPE" "0402LF"
					( Origin gFrontEnd )
				)
				( attribute "PART_NUMBER" "A36096-049"
					( Origin gFrontEnd )
				)
				( attribute "PHYS_PAGE" "181"
					( Origin gFrontEnd )
				)
				( attribute "ROOM" "IO_SLOT"
					( Origin gFrontEnd )
				)
				( attribute "ROT" "0"
					( Origin gFrontEnd )
				)
				( attribute "SEC" "1"
					( Origin gFrontEnd )
				)
				( attribute "SEC_TYPE" "0402LF"
					( Origin gFrontEnd )
				)
				( attribute "TOLERANCE" "10%"
					( Origin gFrontEnd )
				)
				( attribute "VALUE" "470PF"
					( Origin gFrontEnd )
				)
				( attribute "VER" "1"
					( Origin gFrontEnd )
				)
				( attribute "VOLTAGE" "50V"
					( Units "uVoltage" "V" 1.000000)
					( Origin gFrontEnd )
				)
				( attribute "XY" "(-300,875)"
					( Origin gFrontEnd )
				)
				( attribute "CHIPS_PART_NAME" "CAP"
					( Origin gPackager )
				)
				( attribute "CDS_PART_NAME" "CAP_0402LF-470PF,50V,10%,EMPTYA"
					( Origin gPackager )
				)
				( objectStatus "C2R6" )
				( pin "a"
					( attribute "PN" "1"
						( Origin gPackager )
					)
					( objectStatus "C2R6.1" )
				)
				( pin "b"
					( attribute "PN" "2"
						( Origin gPackager )
					)
					( objectStatus "C2R6.2" )
				)
			)
			( gate "@baseboard_fab2_lib.baseboard_fab2(sch_1):page181_i243"
				( attribute "BOM_COST" "FAST_PROCHOT"
					( Origin gFrontEnd )
				)
				( attribute "CDS_LIB" "mstr_ttl"
					( Origin gPackager )
				)
				( attribute "CDS_LOCATION" "U8E1"
					( Origin gPackager )
				)
				( attribute "CDS_SEC" "2"
					( Origin gPackager )
				)
				( attribute "LOCATION" "U8E1"
					( Origin gFrontEnd )
				)
				( attribute "MATERIAL" "IC"
					( Origin gFrontEnd )
				)
				( attribute "PACK_TYPE" "QFN15"
					( Origin gFrontEnd )
				)
				( attribute "PART_NUMBER" "D90404-001"
					( Origin gFrontEnd )
				)
				( attribute "PHYS_PAGE" "181"
					( Origin gFrontEnd )
				)
				( attribute "ROOM" "FAST_PROCHOT"
					( Origin gFrontEnd )
				)
				( attribute "ROT" "0"
					( Origin gFrontEnd )
				)
				( attribute "SEC" "2"
					( Origin gFrontEnd )
				)
				( attribute "SEC_TYPE" "QFN15"
					( Origin gFrontEnd )
				)
				( attribute "VALUE" "74LVC08A"
					( Origin gFrontEnd )
				)
				( attribute "VER" "1"
					( Origin gFrontEnd )
				)
				( attribute "XY" "(250,1075)"
					( Origin gFrontEnd )
				)
				( attribute "CHIPS_PART_NAME" "TTL08"
					( Origin gPackager )
				)
				( attribute "CDS_PART_NAME" "TTL08_QFN15-74LVC08A,IC,D90404B"
					( Origin gPackager )
				)
				( objectStatus "U8E1" )
				( pin "a(0)"
					( attribute "PN" "9"
						( Origin gPackager )
					)
					( objectStatus "U8E1.9" )
				)
				( pin "b(0)"
					( attribute "PN" "10"
						( Origin gPackager )
					)
					( objectStatus "U8E1.10" )
				)
				( pin "y(0)"
					( attribute "PN" "8"
						( Origin gPackager )
					)
					( objectStatus "U8E1.8" )
				)
			)
			( gate "@baseboard_fab2_lib.baseboard_fab2(sch_1):page181_i253"
				( attribute "BOM_COST" "IO_SLOT"
					( Origin gFrontEnd )
				)
				( attribute "CDS_LIB" "dev_discrete"
					( Origin gPackager )
				)
				( attribute "CDS_LOCATION" "C8E1"
					( Origin gPackager )
				)
				( attribute "CDS_SEC" "1"
					( Origin gPackager )
				)
				( attribute "LOCATION" "C8E1"
					( Origin gFrontEnd )
				)
				( attribute "MATERIAL" "X7R"
					( Origin gFrontEnd )
				)
				( attribute "PACK_TYPE" "0402V"
					( Origin gFrontEnd )
				)
				( attribute "PART_NUMBER" "A36096-030"
					( Origin gFrontEnd )
				)
				( attribute "PHYS_PAGE" "181"
					( Origin gFrontEnd )
				)
				( attribute "ROOM" "IO_SLOT"
					( Origin gFrontEnd )
				)
				( attribute "ROT" "0"
					( Origin gFrontEnd )
				)
				( attribute "SEC" "1"
					( Origin gFrontEnd )
				)
				( attribute "SEC_TYPE" "0402V"
					( Origin gFrontEnd )
				)
				( attribute "TOLERANCE" "10%"
					( Origin gFrontEnd )
				)
				( attribute "VALUE" "0.1UF"
					( Origin gFrontEnd )
				)
				( attribute "VER" "1"
					( Origin gFrontEnd )
				)
				( attribute "VOLTAGE" "16V"
					( Units "uVoltage" "V" 1.000000)
					( Origin gFrontEnd )
				)
				( attribute "XY" "(-1525,1025)"
					( Origin gFrontEnd )
				)
				( attribute "CHIPS_PART_NAME" "CAP_A"
					( Origin gPackager )
				)
				( attribute "CDS_PART_NAME" "CAP_A_0402V-0.1UF,16V,10%,X7R,A"
					( Origin gPackager )
				)
				( objectStatus "C8E1" )
				( pin "a"
					( attribute "PN" "1"
						( Origin gPackager )
					)
					( objectStatus "C8E1.1" )
				)
				( pin "b"
					( attribute "PN" "2"
						( Origin gPackager )
					)
					( objectStatus "C8E1.2" )
				)
			)
			( gate "@baseboard_fab2_lib.baseboard_fab2(sch_1):page181_i254"
				( attribute "CDS_LIB" "mstr_discrete"
					( Origin gPackager )
				)
				( attribute "CDS_LOCATION" "R9R9"
					( Origin gPackager )
				)
				( attribute "CDS_SEC" "1"
					( Origin gPackager )
				)
				( attribute "LOCATION" "R9R9"
					( Origin gFrontEnd )
				)
				( attribute "MATERIAL" "CHIP"
					( Origin gFrontEnd )
				)
				( attribute "PACK_TYPE" "0402"
					( Origin gFrontEnd )
				)
				( attribute "PART_NUMBER" "G21497-005"
					( Origin gFrontEnd )
				)
				( attribute "PHYS_PAGE" "181"
					( Origin gFrontEnd )
				)
				( attribute "ROT" "0"
					( Origin gFrontEnd )
				)
				( attribute "SEC" "1"
					( Origin gFrontEnd )
				)
				( attribute "SEC_TYPE" "0402"
					( Origin gFrontEnd )
				)
				( attribute "TOLERANCE" "5%"
					( Origin gFrontEnd )
				)
				( attribute "VALUE" "0.0"
					( Origin gFrontEnd )
				)
				( attribute "VER" "1"
					( Origin gFrontEnd )
				)
				( attribute "WATTAGE" "1/16W"
					( Origin gFrontEnd )
				)
				( attribute "XY" "(-2125,3200)"
					( Origin gFrontEnd )
				)
				( attribute "CHIPS_PART_NAME" "RES"
					( Origin gPackager )
				)
				( attribute "CDS_PART_NAME" "RES_0402-0.0,5%,1/16W,CHIP,G21A"
					( Origin gPackager )
				)
				( objectStatus "R9R9" )
				( pin "a"
					( attribute "PN" "1"
						( Origin gPackager )
					)
					( objectStatus "R9R9.1" )
				)
				( pin "b"
					( attribute "PN" "2"
						( Origin gPackager )
					)
					( objectStatus "R9R9.2" )
				)
			)
			( gate "@baseboard_fab2_lib.baseboard_fab2(sch_1):page181_i255"
				( attribute "CDS_LIB" "mstr_discrete"
					( Origin gPackager )
				)
				( attribute "CDS_LOCATION" "R9R12"
					( Origin gPackager )
				)
				( attribute "CDS_SEC" "1"
					( Origin gPackager )
				)
				( attribute "LOCATION" "R9R12"
					( Origin gFrontEnd )
				)
				( attribute "MATERIAL" "CHIP"
					( Origin gFrontEnd )
				)
				( attribute "PACK_TYPE" "0402"
					( Origin gFrontEnd )
				)
				( attribute "PART_NUMBER" "G21497-005"
					( Origin gFrontEnd )
				)
				( attribute "PHYS_PAGE" "181"
					( Origin gFrontEnd )
				)
				( attribute "ROT" "0"
					( Origin gFrontEnd )
				)
				( attribute "SEC" "1"
					( Origin gFrontEnd )
				)
				( attribute "SEC_TYPE" "0402"
					( Origin gFrontEnd )
				)
				( attribute "TOLERANCE" "5%"
					( Origin gFrontEnd )
				)
				( attribute "VALUE" "0.0"
					( Origin gFrontEnd )
				)
				( attribute "VER" "1"
					( Origin gFrontEnd )
				)
				( attribute "WATTAGE" "1/16W"
					( Origin gFrontEnd )
				)
				( attribute "XY" "(-2825,3150)"
					( Origin gFrontEnd )
				)
				( attribute "CHIPS_PART_NAME" "RES"
					( Origin gPackager )
				)
				( attribute "CDS_PART_NAME" "RES_0402-0.0,5%,1/16W,CHIP,G21A"
					( Origin gPackager )
				)
				( objectStatus "R9R12" )
				( pin "a"
					( attribute "PN" "1"
						( Origin gPackager )
					)
					( objectStatus "R9R12.1" )
				)
				( pin "b"
					( attribute "PN" "2"
						( Origin gPackager )
					)
					( objectStatus "R9R12.2" )
				)
			)
			( gate "@baseboard_fab2_lib.baseboard_fab2(sch_1):page181_i256"
				( attribute "CDS_LIB" "mstr_discrete"
					( Origin gPackager )
				)
				( attribute "CDS_LOCATION" "R9R10"
					( Origin gPackager )
				)
				( attribute "CDS_SEC" "1"
					( Origin gPackager )
				)
				( attribute "LOCATION" "R9R10"
					( Origin gFrontEnd )
				)
				( attribute "MATERIAL" "CHIP"
					( Origin gFrontEnd )
				)
				( attribute "PACK_TYPE" "0402"
					( Origin gFrontEnd )
				)
				( attribute "PART_NUMBER" "G21497-005"
					( Origin gFrontEnd )
				)
				( attribute "PHYS_PAGE" "181"
					( Origin gFrontEnd )
				)
				( attribute "ROT" "0"
					( Origin gFrontEnd )
				)
				( attribute "SEC" "1"
					( Origin gFrontEnd )
				)
				( attribute "SEC_TYPE" "0402"
					( Origin gFrontEnd )
				)
				( attribute "TOLERANCE" "5%"
					( Origin gFrontEnd )
				)
				( attribute "VALUE" "0.0"
					( Origin gFrontEnd )
				)
				( attribute "VER" "1"
					( Origin gFrontEnd )
				)
				( attribute "WATTAGE" "1/16W"
					( Origin gFrontEnd )
				)
				( attribute "XY" "(-2125,3100)"
					( Origin gFrontEnd )
				)
				( attribute "CHIPS_PART_NAME" "RES"
					( Origin gPackager )
				)
				( attribute "CDS_PART_NAME" "RES_0402-0.0,5%,1/16W,CHIP,G21A"
					( Origin gPackager )
				)
				( objectStatus "R9R10" )
				( pin "a"
					( attribute "PN" "1"
						( Origin gPackager )
					)
					( objectStatus "R9R10.1" )
				)
				( pin "b"
					( attribute "PN" "2"
						( Origin gPackager )
					)
					( objectStatus "R9R10.2" )
				)
			)
			( gate "@baseboard_fab2_lib.baseboard_fab2(sch_1):page181_i261"
				( attribute "CDS_LIB" "mstr_discrete"
					( Origin gPackager )
				)
				( attribute "CDS_LOCATION" "R9T1"
					( Origin gPackager )
				)
				( attribute "CDS_SEC" "1"
					( Origin gPackager )
				)
				( attribute "LOCATION" "R9T1"
					( Origin gFrontEnd )
				)
				( attribute "MATERIAL" "CHIP"
					( Origin gFrontEnd )
				)
				( attribute "PACK_TYPE" "0402"
					( Origin gFrontEnd )
				)
				( attribute "PART_NUMBER" "G21497-005"
					( Origin gFrontEnd )
				)
				( attribute "PHYS_PAGE" "181"
					( Origin gFrontEnd )
				)
				( attribute "ROT" "0"
					( Origin gFrontEnd )
				)
				( attribute "SEC" "1"
					( Origin gFrontEnd )
				)
				( attribute "SEC_TYPE" "0402"
					( Origin gFrontEnd )
				)
				( attribute "TOLERANCE" "5%"
					( Origin gFrontEnd )
				)
				( attribute "VALUE" "0.0"
					( Origin gFrontEnd )
				)
				( attribute "VER" "1"
					( Origin gFrontEnd )
				)
				( attribute "WATTAGE" "1/16W"
					( Origin gFrontEnd )
				)
				( attribute "XY" "(-2100,2950)"
					( Origin gFrontEnd )
				)
				( attribute "CHIPS_PART_NAME" "RES"
					( Origin gPackager )
				)
				( attribute "CDS_PART_NAME" "RES_0402-0.0,5%,1/16W,CHIP,G21A"
					( Origin gPackager )
				)
				( objectStatus "R9T1" )
				( pin "a"
					( attribute "PN" "1"
						( Origin gPackager )
					)
					( objectStatus "R9T1.1" )
				)
				( pin "b"
					( attribute "PN" "2"
						( Origin gPackager )
					)
					( objectStatus "R9T1.2" )
				)
			)
			( gate "@baseboard_fab2_lib.baseboard_fab2(sch_1):page181_i268"
				( attribute "CDS_LIB" "mstr_discrete"
					( Origin gPackager )
				)
				( attribute "CDS_LOCATION" "R1F8"
					( Origin gPackager )
				)
				( attribute "CDS_SEC" "1"
					( Origin gPackager )
				)
				( attribute "LOCATION" "R1F8"
					( Origin gFrontEnd )
				)
				( attribute "MATERIAL" "CHIP"
					( Origin gFrontEnd )
				)
				( attribute "PACK_TYPE" "0402"
					( Origin gFrontEnd )
				)
				( attribute "PART_NUMBER" "G21497-005"
					( Origin gFrontEnd )
				)
				( attribute "PHYS_PAGE" "181"
					( Origin gFrontEnd )
				)
				( attribute "ROT" "0"
					( Origin gFrontEnd )
				)
				( attribute "SEC" "1"
					( Origin gFrontEnd )
				)
				( attribute "SEC_TYPE" "0402"
					( Origin gFrontEnd )
				)
				( attribute "TOLERANCE" "5%"
					( Origin gFrontEnd )
				)
				( attribute "VALUE" "0.0"
					( Origin gFrontEnd )
				)
				( attribute "VER" "1"
					( Origin gFrontEnd )
				)
				( attribute "WATTAGE" "1/16W"
					( Origin gFrontEnd )
				)
				( attribute "XY" "(-2825,3050)"
					( Origin gFrontEnd )
				)
				( attribute "CHIPS_PART_NAME" "RES"
					( Origin gPackager )
				)
				( attribute "CDS_PART_NAME" "RES_0402-0.0,5%,1/16W,CHIP,G21A"
					( Origin gPackager )
				)
				( objectStatus "R1F8" )
				( pin "a"
					( attribute "PN" "1"
						( Origin gPackager )
					)
					( objectStatus "R1F8.1" )
				)
				( pin "b"
					( attribute "PN" "2"
						( Origin gPackager )
					)
					( objectStatus "R1F8.2" )
				)
			)
			( gate "@baseboard_fab2_lib.baseboard_fab2(sch_1):page158_i150"
				( attribute "BOM_COST" "DEBUG"
					( Origin gFrontEnd )
				)
				( attribute "CDS_LIB" "mstr_discrete"
					( Origin gPackager )
				)
				( attribute "CDS_LOCATION" "R9F69"
					( Origin gPackager )
				)
				( attribute "CDS_SEC" "1"
					( Origin gPackager )
				)
				( attribute "LOCATION" "R9F69"
					( Origin gFrontEnd )
				)
				( attribute "MATERIAL" "CHIP"
					( Origin gFrontEnd )
				)
				( attribute "PACK_TYPE" "0402"
					( Origin gFrontEnd )
				)
				( attribute "PART_NUMBER" "G21497-005"
					( Origin gFrontEnd )
				)
				( attribute "PHYS_PAGE" "158"
					( Origin gFrontEnd )
				)
				( attribute "ROOM" "UART_MUX"
					( Origin gFrontEnd )
				)
				( attribute "ROT" "0"
					( Origin gFrontEnd )
				)
				( attribute "SEC" "1"
					( Origin gFrontEnd )
				)
				( attribute "SEC_TYPE" "0402"
					( Origin gFrontEnd )
				)
				( attribute "TOLERANCE" "5%"
					( Origin gFrontEnd )
				)
				( attribute "VALUE" "0.0"
					( Origin gFrontEnd )
				)
				( attribute "VER" "1"
					( Origin gFrontEnd )
				)
				( attribute "WATTAGE" "1/16W"
					( Origin gFrontEnd )
				)
				( attribute "XY" "(-1250,1775)"
					( Origin gFrontEnd )
				)
				( attribute "CHIPS_PART_NAME" "RES"
					( Origin gPackager )
				)
				( attribute "CDS_PART_NAME" "RES_0402-0.0,5%,1/16W,CHIP,G21A"
					( Origin gPackager )
				)
				( objectStatus "R9F69" )
				( pin "a"
					( attribute "PN" "1"
						( Origin gPackager )
					)
					( objectStatus "R9F69.1" )
				)
				( pin "b"
					( attribute "PN" "2"
						( Origin gPackager )
					)
					( objectStatus "R9F69.2" )
				)
			)
			( gate "@baseboard_fab2_lib.baseboard_fab2(sch_1):page158_i149"
				( attribute "BOM_COST" "DEBUG"
					( Origin gFrontEnd )
				)
				( attribute "CDS_LIB" "mstr_discrete"
					( Origin gPackager )
				)
				( attribute "CDS_LOCATION" "R9F68"
					( Origin gPackager )
				)
				( attribute "CDS_SEC" "1"
					( Origin gPackager )
				)
				( attribute "LOCATION" "R9F68"
					( Origin gFrontEnd )
				)
				( attribute "MATERIAL" "EMPTY"
					( Origin gFrontEnd )
				)
				( attribute "PACK_TYPE" "0402"
					( Origin gFrontEnd )
				)
				( attribute "PART_NUMBER" "G21497-005"
					( Origin gFrontEnd )
				)
				( attribute "PHYS_PAGE" "158"
					( Origin gFrontEnd )
				)
				( attribute "ROOM" "UART_MUX"
					( Origin gFrontEnd )
				)
				( attribute "ROT" "0"
					( Origin gFrontEnd )
				)
				( attribute "SEC" "1"
					( Origin gPackager )
				)
				( attribute "TOLERANCE" "5%"
					( Origin gFrontEnd )
				)
				( attribute "VALUE" "0.0"
					( Origin gFrontEnd )
				)
				( attribute "VER" "1"
					( Origin gFrontEnd )
				)
				( attribute "WATTAGE" "1/16W"
					( Origin gFrontEnd )
				)
				( attribute "XY" "(-1400,850)"
					( Origin gFrontEnd )
				)
				( attribute "CHIPS_PART_NAME" "RES"
					( Origin gPackager )
				)
				( attribute "CDS_PART_NAME" "RES_0402-0.0,5%,1/16W,EMPTY,G2A"
					( Origin gPackager )
				)
				( objectStatus "R9F68" )
				( pin "a"
					( attribute "PN" "1"
						( Origin gPackager )
					)
					( objectStatus "R9F68.1" )
				)
				( pin "b"
					( attribute "PN" "2"
						( Origin gPackager )
					)
					( objectStatus "R9F68.2" )
				)
			)
			( gate "@baseboard_fab2_lib.baseboard_fab2(sch_1):page182_i9"
				( attribute "BOM_COST" "IO_SLOT"
					( Origin gFrontEnd )
				)
				( attribute "CDS_LIB" "mstr_discrete"
					( Origin gPackager )
				)
				( attribute "CDS_LOCATION" "C9N18"
					( Origin gPackager )
				)
				( attribute "CDS_SEC" "1"
					( Origin gPackager )
				)
				( attribute "LOCATION" "C9N18"
					( Origin gFrontEnd )
				)
				( attribute "MATERIAL" "X7R"
					( Origin gFrontEnd )
				)
				( attribute "PACK_TYPE" "0402"
					( Origin gFrontEnd )
				)
				( attribute "PART_NUMBER" "A36096-155"
					( Origin gFrontEnd )
				)
				( attribute "PHYS_PAGE" "182"
					( Origin gFrontEnd )
				)
				( attribute "ROOM" "IO_SLOT"
					( Origin gFrontEnd )
				)
				( attribute "ROT" "0"
					( Origin gFrontEnd )
				)
				( attribute "SEC" "1"
					( Origin gFrontEnd )
				)
				( attribute "SEC_TYPE" "0402"
					( Origin gFrontEnd )
				)
				( attribute "TOLERANCE" "10%"
					( Origin gFrontEnd )
				)
				( attribute "VALUE" "0.22UF"
					( Origin gFrontEnd )
				)
				( attribute "VER" "2"
					( Origin gFrontEnd )
				)
				( attribute "VOLTAGE" "16V"
					( Units "uVoltage" "V" 1.000000)
					( Origin gFrontEnd )
				)
				( attribute "XY" "(-2475,2000)"
					( Origin gFrontEnd )
				)
				( attribute "CHIPS_PART_NAME" "CAP"
					( Origin gPackager )
				)
				( attribute "CDS_PART_NAME" "CAP_0402-0.22UF,16V,10%,X7R,A3A"
					( Origin gPackager )
				)
				( objectStatus "C9N18" )
				( pin "a"
					( attribute "PN" "1"
						( Origin gPackager )
					)
					( objectStatus "C9N18.1" )
				)
				( pin "b"
					( attribute "PN" "2"
						( Origin gPackager )
					)
					( objectStatus "C9N18.2" )
				)
			)
			( gate "@baseboard_fab2_lib.baseboard_fab2(sch_1):page182_i12"
				( attribute "BOM_COST" "IO_SLOT"
					( Origin gFrontEnd )
				)
				( attribute "CDS_LIB" "mstr_discrete"
					( Origin gPackager )
				)
				( attribute "CDS_LOCATION" "C9N17"
					( Origin gPackager )
				)
				( attribute "CDS_SEC" "1"
					( Origin gPackager )
				)
				( attribute "LOCATION" "C9N17"
					( Origin gFrontEnd )
				)
				( attribute "MATERIAL" "X7R"
					( Origin gFrontEnd )
				)
				( attribute "PACK_TYPE" "0402"
					( Origin gFrontEnd )
				)
				( attribute "PART_NUMBER" "A36096-155"
					( Origin gFrontEnd )
				)
				( attribute "PHYS_PAGE" "182"
					( Origin gFrontEnd )
				)
				( attribute "ROOM" "IO_SLOT"
					( Origin gFrontEnd )
				)
				( attribute "ROT" "0"
					( Origin gFrontEnd )
				)
				( attribute "SEC" "1"
					( Origin gFrontEnd )
				)
				( attribute "SEC_TYPE" "0402"
					( Origin gFrontEnd )
				)
				( attribute "TOLERANCE" "10%"
					( Origin gFrontEnd )
				)
				( attribute "VALUE" "0.22UF"
					( Origin gFrontEnd )
				)
				( attribute "VER" "2"
					( Origin gFrontEnd )
				)
				( attribute "VOLTAGE" "16V"
					( Units "uVoltage" "V" 1.000000)
					( Origin gFrontEnd )
				)
				( attribute "XY" "(-2950,1950)"
					( Origin gFrontEnd )
				)
				( attribute "CHIPS_PART_NAME" "CAP"
					( Origin gPackager )
				)
				( attribute "CDS_PART_NAME" "CAP_0402-0.22UF,16V,10%,X7R,A3A"
					( Origin gPackager )
				)
				( objectStatus "C9N17" )
				( pin "a"
					( attribute "PN" "1"
						( Origin gPackager )
					)
					( objectStatus "C9N17.1" )
				)
				( pin "b"
					( attribute "PN" "2"
						( Origin gPackager )
					)
					( objectStatus "C9N17.2" )
				)
			)
			( gate "@baseboard_fab2_lib.baseboard_fab2(sch_1):page182_i13"
				( attribute "BOM_COST" "IO_SLOT"
					( Origin gFrontEnd )
				)
				( attribute "CDS_LIB" "mstr_discrete"
					( Origin gPackager )
				)
				( attribute "CDS_LOCATION" "C9N15"
					( Origin gPackager )
				)
				( attribute "CDS_SEC" "1"
					( Origin gPackager )
				)
				( attribute "LOCATION" "C9N15"
					( Origin gFrontEnd )
				)
				( attribute "MATERIAL" "X7R"
					( Origin gFrontEnd )
				)
				( attribute "PACK_TYPE" "0402"
					( Origin gFrontEnd )
				)
				( attribute "PART_NUMBER" "A36096-155"
					( Origin gFrontEnd )
				)
				( attribute "PHYS_PAGE" "182"
					( Origin gFrontEnd )
				)
				( attribute "ROOM" "IO_SLOT"
					( Origin gFrontEnd )
				)
				( attribute "ROT" "0"
					( Origin gFrontEnd )
				)
				( attribute "SEC" "1"
					( Origin gFrontEnd )
				)
				( attribute "SEC_TYPE" "0402"
					( Origin gFrontEnd )
				)
				( attribute "TOLERANCE" "10%"
					( Origin gFrontEnd )
				)
				( attribute "VALUE" "0.22UF"
					( Origin gFrontEnd )
				)
				( attribute "VER" "2"
					( Origin gFrontEnd )
				)
				( attribute "VOLTAGE" "16V"
					( Units "uVoltage" "V" 1.000000)
					( Origin gFrontEnd )
				)
				( attribute "XY" "(-2475,1850)"
					( Origin gFrontEnd )
				)
				( attribute "CHIPS_PART_NAME" "CAP"
					( Origin gPackager )
				)
				( attribute "CDS_PART_NAME" "CAP_0402-0.22UF,16V,10%,X7R,A3A"
					( Origin gPackager )
				)
				( objectStatus "C9N15" )
				( pin "a"
					( attribute "PN" "1"
						( Origin gPackager )
					)
					( objectStatus "C9N15.1" )
				)
				( pin "b"
					( attribute "PN" "2"
						( Origin gPackager )
					)
					( objectStatus "C9N15.2" )
				)
			)
			( gate "@baseboard_fab2_lib.baseboard_fab2(sch_1):page182_i14"
				( attribute "BOM_COST" "IO_SLOT"
					( Origin gFrontEnd )
				)
				( attribute "CDS_LIB" "mstr_discrete"
					( Origin gPackager )
				)
				( attribute "CDS_LOCATION" "C9N1"
					( Origin gPackager )
				)
				( attribute "CDS_SEC" "1"
					( Origin gPackager )
				)
				( attribute "LOCATION" "C9N1"
					( Origin gFrontEnd )
				)
				( attribute "MATERIAL" "X7R"
					( Origin gFrontEnd )
				)
				( attribute "PACK_TYPE" "0402"
					( Origin gFrontEnd )
				)
				( attribute "PART_NUMBER" "A36096-155"
					( Origin gFrontEnd )
				)
				( attribute "PHYS_PAGE" "182"
					( Origin gFrontEnd )
				)
				( attribute "ROOM" "IO_SLOT"
					( Origin gFrontEnd )
				)
				( attribute "ROT" "0"
					( Origin gFrontEnd )
				)
				( attribute "SEC" "1"
					( Origin gFrontEnd )
				)
				( attribute "SEC_TYPE" "0402"
					( Origin gFrontEnd )
				)
				( attribute "TOLERANCE" "10%"
					( Origin gFrontEnd )
				)
				( attribute "VALUE" "0.22UF"
					( Origin gFrontEnd )
				)
				( attribute "VER" "2"
					( Origin gFrontEnd )
				)
				( attribute "VOLTAGE" "16V"
					( Units "uVoltage" "V" 1.000000)
					( Origin gFrontEnd )
				)
				( attribute "XY" "(-2475,1700)"
					( Origin gFrontEnd )
				)
				( attribute "CHIPS_PART_NAME" "CAP"
					( Origin gPackager )
				)
				( attribute "CDS_PART_NAME" "CAP_0402-0.22UF,16V,10%,X7R,A3A"
					( Origin gPackager )
				)
				( objectStatus "C9N1" )
				( pin "a"
					( attribute "PN" "1"
						( Origin gPackager )
					)
					( objectStatus "C9N1.1" )
				)
				( pin "b"
					( attribute "PN" "2"
						( Origin gPackager )
					)
					( objectStatus "C9N1.2" )
				)
			)
			( gate "@baseboard_fab2_lib.baseboard_fab2(sch_1):page182_i15"
				( attribute "BOM_COST" "IO_SLOT"
					( Origin gFrontEnd )
				)
				( attribute "CDS_LIB" "mstr_discrete"
					( Origin gPackager )
				)
				( attribute "CDS_LOCATION" "C9N2"
					( Origin gPackager )
				)
				( attribute "CDS_SEC" "1"
					( Origin gPackager )
				)
				( attribute "LOCATION" "C9N2"
					( Origin gFrontEnd )
				)
				( attribute "MATERIAL" "X7R"
					( Origin gFrontEnd )
				)
				( attribute "PACK_TYPE" "0402"
					( Origin gFrontEnd )
				)
				( attribute "PART_NUMBER" "A36096-155"
					( Origin gFrontEnd )
				)
				( attribute "PHYS_PAGE" "182"
					( Origin gFrontEnd )
				)
				( attribute "ROOM" "IO_SLOT"
					( Origin gFrontEnd )
				)
				( attribute "ROT" "0"
					( Origin gFrontEnd )
				)
				( attribute "SEC" "1"
					( Origin gFrontEnd )
				)
				( attribute "SEC_TYPE" "0402"
					( Origin gFrontEnd )
				)
				( attribute "TOLERANCE" "10%"
					( Origin gFrontEnd )
				)
				( attribute "VALUE" "0.22UF"
					( Origin gFrontEnd )
				)
				( attribute "VER" "2"
					( Origin gFrontEnd )
				)
				( attribute "VOLTAGE" "16V"
					( Units "uVoltage" "V" 1.000000)
					( Origin gFrontEnd )
				)
				( attribute "XY" "(-2950,1650)"
					( Origin gFrontEnd )
				)
				( attribute "CHIPS_PART_NAME" "CAP"
					( Origin gPackager )
				)
				( attribute "CDS_PART_NAME" "CAP_0402-0.22UF,16V,10%,X7R,A3A"
					( Origin gPackager )
				)
				( objectStatus "C9N2" )
				( pin "a"
					( attribute "PN" "1"
						( Origin gPackager )
					)
					( objectStatus "C9N2.1" )
				)
				( pin "b"
					( attribute "PN" "2"
						( Origin gPackager )
					)
					( objectStatus "C9N2.2" )
				)
			)
			( gate "@baseboard_fab2_lib.baseboard_fab2(sch_1):page182_i16"
				( attribute "BOM_COST" "IO_SLOT"
					( Origin gFrontEnd )
				)
				( attribute "CDS_LIB" "mstr_discrete"
					( Origin gPackager )
				)
				( attribute "CDS_LOCATION" "C9N12"
					( Origin gPackager )
				)
				( attribute "CDS_SEC" "1"
					( Origin gPackager )
				)
				( attribute "LOCATION" "C9N12"
					( Origin gFrontEnd )
				)
				( attribute "MATERIAL" "X7R"
					( Origin gFrontEnd )
				)
				( attribute "PACK_TYPE" "0402"
					( Origin gFrontEnd )
				)
				( attribute "PART_NUMBER" "A36096-155"
					( Origin gFrontEnd )
				)
				( attribute "PHYS_PAGE" "182"
					( Origin gFrontEnd )
				)
				( attribute "ROOM" "IO_SLOT"
					( Origin gFrontEnd )
				)
				( attribute "ROT" "0"
					( Origin gFrontEnd )
				)
				( attribute "SEC" "1"
					( Origin gFrontEnd )
				)
				( attribute "SEC_TYPE" "0402"
					( Origin gFrontEnd )
				)
				( attribute "TOLERANCE" "10%"
					( Origin gFrontEnd )
				)
				( attribute "VALUE" "0.22UF"
					( Origin gFrontEnd )
				)
				( attribute "VER" "2"
					( Origin gFrontEnd )
				)
				( attribute "VOLTAGE" "16V"
					( Units "uVoltage" "V" 1.000000)
					( Origin gFrontEnd )
				)
				( attribute "XY" "(-2950,1800)"
					( Origin gFrontEnd )
				)
				( attribute "CHIPS_PART_NAME" "CAP"
					( Origin gPackager )
				)
				( attribute "CDS_PART_NAME" "CAP_0402-0.22UF,16V,10%,X7R,A3A"
					( Origin gPackager )
				)
				( objectStatus "C9N12" )
				( pin "a"
					( attribute "PN" "1"
						( Origin gPackager )
					)
					( objectStatus "C9N12.1" )
				)
				( pin "b"
					( attribute "PN" "2"
						( Origin gPackager )
					)
					( objectStatus "C9N12.2" )
				)
			)
			( gate "@baseboard_fab2_lib.baseboard_fab2(sch_1):page182_i18"
				( attribute "BOM_COST" "IO_SLOT"
					( Origin gFrontEnd )
				)
				( attribute "CDS_LIB" "mstr_conn"
					( Origin gPackager )
				)
				( attribute "CDS_LOCATION" "J1C1"
					( Origin gPackager )
				)
				( attribute "CDS_SEC" "1"
					( Origin gPackager )
				)
				( attribute "LOCATION" "J1C1"
					( Origin gFrontEnd )
				)
				( attribute "MATERIAL" "CONN"
					( Origin gFrontEnd )
				)
				( attribute "PACK_TYPE" "THMT1"
					( Origin gFrontEnd )
				)
				( attribute "PART_NUMBER" "H22707-001"
					( Origin gFrontEnd )
				)
				( attribute "PHYS_PAGE" "182"
					( Origin gFrontEnd )
				)
				( attribute "ROOM" "IO_SLOT"
					( Origin gFrontEnd )
				)
				( attribute "ROT" "0"
					( Origin gFrontEnd )
				)
				( attribute "SEC" "1"
					( Origin gFrontEnd )
				)
				( attribute "SEC_TYPE" "THMT1"
					( Origin gFrontEnd )
				)
				( attribute "VER" "1"
					( Origin gFrontEnd )
				)
				( attribute "XY" "(-4425,2650)"
					( Origin gFrontEnd )
				)
				( attribute "CHIPS_PART_NAME" "CONN76_H22707001"
					( Origin gPackager )
				)
				( attribute "CDS_PART_NAME" "CONN76_H22707001_THMT1-CONN,H2A"
					( Origin gPackager )
				)
				( objectStatus "J1C1" )
				( pin "gnda2"
					( attribute "PN" "A2"
						( Origin gPackager )
					)
					( objectStatus "J1C1.A2" )
				)
				( pin "gnda4"
					( attribute "PN" "A4"
						( Origin gPackager )
					)
					( objectStatus "J1C1.A4" )
				)
				( pin "gnda6"
					( attribute "PN" "A6"
						( Origin gPackager )
					)
					( objectStatus "J1C1.A6" )
				)
				( pin "gnda8"
					( attribute "PN" "A8"
						( Origin gPackager )
					)
					( objectStatus "J1C1.A8" )
				)
				( pin "gndc1"
					( attribute "PN" "C1"
						( Origin gPackager )
					)
					( objectStatus "J1C1.C1" )
				)
				( pin "gndc3"
					( attribute "PN" "C3"
						( Origin gPackager )
					)
					( objectStatus "J1C1.C3" )
				)
				( pin "gndc5"
					( attribute "PN" "C5"
						( Origin gPackager )
					)
					( objectStatus "J1C1.C5" )
				)
				( pin "gndc7"
					( attribute "PN" "C7"
						( Origin gPackager )
					)
					( objectStatus "J1C1.C7" )
				)
				( pin "gndd2"
					( attribute "PN" "D2"
						( Origin gPackager )
					)
					( objectStatus "J1C1.D2" )
				)
				( pin "gndd4"
					( attribute "PN" "D4"
						( Origin gPackager )
					)
					( objectStatus "J1C1.D4" )
				)
				( pin "gndd6"
					( attribute "PN" "D6"
						( Origin gPackager )
					)
					( objectStatus "J1C1.D6" )
				)
				( pin "gndd8"
					( attribute "PN" "D8"
						( Origin gPackager )
					)
					( objectStatus "J1C1.D8" )
				)
				( pin "gndf1"
					( attribute "PN" "F1"
						( Origin gPackager )
					)
					( objectStatus "J1C1.F1" )
				)
				( pin "gndf3"
					( attribute "PN" "F3"
						( Origin gPackager )
					)
					( objectStatus "J1C1.F3" )
				)
				( pin "gndf5"
					( attribute "PN" "F5"
						( Origin gPackager )
					)
					( objectStatus "J1C1.F5" )
				)
				( pin "gndf7"
					( attribute "PN" "F7"
						( Origin gPackager )
					)
					( objectStatus "J1C1.F7" )
				)
				( pin "gndg2"
					( attribute "PN" "G2"
						( Origin gPackager )
					)
					( objectStatus "J1C1.G2" )
				)
				( pin "gndg4"
					( attribute "PN" "G4"
						( Origin gPackager )
					)
					( objectStatus "J1C1.G4" )
				)
				( pin "gndg6"
					( attribute "PN" "G6"
						( Origin gPackager )
					)
					( objectStatus "J1C1.G6" )
				)
				( pin "gndg8"
					( attribute "PN" "G8"
						( Origin gPackager )
					)
					( objectStatus "J1C1.G8" )
				)
				( pin "gndi1"
					( attribute "PN" "I1"
						( Origin gPackager )
					)
					( objectStatus "J1C1.I1" )
				)
				( pin "gndi3"
					( attribute "PN" "I3"
						( Origin gPackager )
					)
					( objectStatus "J1C1.I3" )
				)
				( pin "gndi5"
					( attribute "PN" "I5"
						( Origin gPackager )
					)
					( objectStatus "J1C1.I5" )
				)
				( pin "gndi7"
					( attribute "PN" "I7"
						( Origin gPackager )
					)
					( objectStatus "J1C1.I7" )
				)
				( pin "gndj2"
					( attribute "PN" "J2"
						( Origin gPackager )
					)
					( objectStatus "J1C1.J2" )
				)
				( pin "gndj4"
					( attribute "PN" "J4"
						( Origin gPackager )
					)
					( objectStatus "J1C1.J4" )
				)
				( pin "gndj6"
					( attribute "PN" "J6"
						( Origin gPackager )
					)
					( objectStatus "J1C1.J6" )
				)
				( pin "gndj8"
					( attribute "PN" "J8"
						( Origin gPackager )
					)
					( objectStatus "J1C1.J8" )
				)
				( pin "ioa1"
					( attribute "PN" "A1"
						( Origin gPackager )
					)
					( objectStatus "J1C1.A1" )
				)
				( pin "ioa3"
					( attribute "PN" "A3"
						( Origin gPackager )
					)
					( objectStatus "J1C1.A3" )
				)
				( pin "ioa5"
					( attribute "PN" "A5"
						( Origin gPackager )
					)
					( objectStatus "J1C1.A5" )
				)
				( pin "ioa7"
					( attribute "PN" "A7"
						( Origin gPackager )
					)
					( objectStatus "J1C1.A7" )
				)
				( pin "iob1"
					( attribute "PN" "B1"
						( Origin gPackager )
					)
					( objectStatus "J1C1.B1" )
				)
				( pin "iob2"
					( attribute "PN" "B2"
						( Origin gPackager )
					)
					( objectStatus "J1C1.B2" )
				)
				( pin "iob3"
					( attribute "PN" "B3"
						( Origin gPackager )
					)
					( objectStatus "J1C1.B3" )
				)
				( pin "iob4"
					( attribute "PN" "B4"
						( Origin gPackager )
					)
					( objectStatus "J1C1.B4" )
				)
				( pin "iob5"
					( attribute "PN" "B5"
						( Origin gPackager )
					)
					( objectStatus "J1C1.B5" )
				)
				( pin "iob6"
					( attribute "PN" "B6"
						( Origin gPackager )
					)
					( objectStatus "J1C1.B6" )
				)
				( pin "iob7"
					( attribute "PN" "B7"
						( Origin gPackager )
					)
					( objectStatus "J1C1.B7" )
				)
				( pin "iob8"
					( attribute "PN" "B8"
						( Origin gPackager )
					)
					( objectStatus "J1C1.B8" )
				)
				( pin "ioc2"
					( attribute "PN" "C2"
						( Origin gPackager )
					)
					( objectStatus "J1C1.C2" )
				)
				( pin "ioc4"
					( attribute "PN" "C4"
						( Origin gPackager )
					)
					( objectStatus "J1C1.C4" )
				)
				( pin "ioc6"
					( attribute "PN" "C6"
						( Origin gPackager )
					)
					( objectStatus "J1C1.C6" )
				)
				( pin "ioc8"
					( attribute "PN" "C8"
						( Origin gPackager )
					)
					( objectStatus "J1C1.C8" )
				)
				( pin "iod1"
					( attribute "PN" "D1"
						( Origin gPackager )
					)
					( objectStatus "J1C1.D1" )
				)
				( pin "iod3"
					( attribute "PN" "D3"
						( Origin gPackager )
					)
					( objectStatus "J1C1.D3" )
				)
				( pin "iod5"
					( attribute "PN" "D5"
						( Origin gPackager )
					)
					( objectStatus "J1C1.D5" )
				)
				( pin "iod7"
					( attribute "PN" "D7"
						( Origin gPackager )
					)
					( objectStatus "J1C1.D7" )
				)
				( pin "ioe1"
					( attribute "PN" "E1"
						( Origin gPackager )
					)
					( objectStatus "J1C1.E1" )
				)
				( pin "ioe2"
					( attribute "PN" "E2"
						( Origin gPackager )
					)
					( objectStatus "J1C1.E2" )
				)
				( pin "ioe3"
					( attribute "PN" "E3"
						( Origin gPackager )
					)
					( objectStatus "J1C1.E3" )
				)
				( pin "ioe4"
					( attribute "PN" "E4"
						( Origin gPackager )
					)
					( objectStatus "J1C1.E4" )
				)
				( pin "ioe5"
					( attribute "PN" "E5"
						( Origin gPackager )
					)
					( objectStatus "J1C1.E5" )
				)
				( pin "ioe6"
					( attribute "PN" "E6"
						( Origin gPackager )
					)
					( objectStatus "J1C1.E6" )
				)
				( pin "ioe7"
					( attribute "PN" "E7"
						( Origin gPackager )
					)
					( objectStatus "J1C1.E7" )
				)
				( pin "ioe8"
					( attribute "PN" "E8"
						( Origin gPackager )
					)
					( objectStatus "J1C1.E8" )
				)
				( pin "iof2"
					( attribute "PN" "F2"
						( Origin gPackager )
					)
					( objectStatus "J1C1.F2" )
				)
				( pin "iof4"
					( attribute "PN" "F4"
						( Origin gPackager )
					)
					( objectStatus "J1C1.F4" )
				)
				( pin "iof6"
					( attribute "PN" "F6"
						( Origin gPackager )
					)
					( objectStatus "J1C1.F6" )
				)
				( pin "iof8"
					( attribute "PN" "F8"
						( Origin gPackager )
					)
					( objectStatus "J1C1.F8" )
				)
				( pin "iog1"
					( attribute "PN" "G1"
						( Origin gPackager )
					)
					( objectStatus "J1C1.G1" )
				)
				( pin "iog3"
					( attribute "PN" "G3"
						( Origin gPackager )
					)
					( objectStatus "J1C1.G3" )
				)
				( pin "iog5"
					( attribute "PN" "G5"
						( Origin gPackager )
					)
					( objectStatus "J1C1.G5" )
				)
				( pin "iog7"
					( attribute "PN" "G7"
						( Origin gPackager )
					)
					( objectStatus "J1C1.G7" )
				)
				( pin "ioh1"
					( attribute "PN" "H1"
						( Origin gPackager )
					)
					( objectStatus "J1C1.H1" )
				)
				( pin "ioh2"
					( attribute "PN" "H2"
						( Origin gPackager )
					)
					( objectStatus "J1C1.H2" )
				)
				( pin "ioh3"
					( attribute "PN" "H3"
						( Origin gPackager )
					)
					( objectStatus "J1C1.H3" )
				)
				( pin "ioh4"
					( attribute "PN" "H4"
						( Origin gPackager )
					)
					( objectStatus "J1C1.H4" )
				)
				( pin "ioh5"
					( attribute "PN" "H5"
						( Origin gPackager )
					)
					( objectStatus "J1C1.H5" )
				)
				( pin "ioh6"
					( attribute "PN" "H6"
						( Origin gPackager )
					)
					( objectStatus "J1C1.H6" )
				)
				( pin "ioh7"
					( attribute "PN" "H7"
						( Origin gPackager )
					)
					( objectStatus "J1C1.H7" )
				)
				( pin "ioh8"
					( attribute "PN" "H8"
						( Origin gPackager )
					)
					( objectStatus "J1C1.H8" )
				)
				( pin "ioi2"
					( attribute "PN" "I2"
						( Origin gPackager )
					)
					( objectStatus "J1C1.I2" )
				)
				( pin "ioi4"
					( attribute "PN" "I4"
						( Origin gPackager )
					)
					( objectStatus "J1C1.I4" )
				)
				( pin "ioi6"
					( attribute "PN" "I6"
						( Origin gPackager )
					)
					( objectStatus "J1C1.I6" )
				)
				( pin "ioi8"
					( attribute "PN" "I8"
						( Origin gPackager )
					)
					( objectStatus "J1C1.I8" )
				)
			)
			( gate "@baseboard_fab2_lib.baseboard_fab2(sch_1):page182_i49"
				( attribute "BOM_COST" "IO_SLOT"
					( Origin gFrontEnd )
				)
				( attribute "CDS_LIB" "mstr_discrete"
					( Origin gPackager )
				)
				( attribute "CDS_LOCATION" "C9N9"
					( Origin gPackager )
				)
				( attribute "CDS_SEC" "1"
					( Origin gPackager )
				)
				( attribute "LOCATION" "C9N9"
					( Origin gFrontEnd )
				)
				( attribute "MATERIAL" "X7R"
					( Origin gFrontEnd )
				)
				( attribute "PACK_TYPE" "0402"
					( Origin gFrontEnd )
				)
				( attribute "PART_NUMBER" "A36096-155"
					( Origin gFrontEnd )
				)
				( attribute "PHYS_PAGE" "182"
					( Origin gFrontEnd )
				)
				( attribute "ROOM" "IO_SLOT"
					( Origin gFrontEnd )
				)
				( attribute "ROT" "0"
					( Origin gFrontEnd )
				)
				( attribute "SEC" "1"
					( Origin gFrontEnd )
				)
				( attribute "SEC_TYPE" "0402"
					( Origin gFrontEnd )
				)
				( attribute "TOLERANCE" "10%"
					( Origin gFrontEnd )
				)
				( attribute "VALUE" "0.22UF"
					( Origin gFrontEnd )
				)
				( attribute "VER" "2"
					( Origin gFrontEnd )
				)
				( attribute "VOLTAGE" "16V"
					( Units "uVoltage" "V" 1.000000)
					( Origin gFrontEnd )
				)
				( attribute "XY" "(-2475,2750)"
					( Origin gFrontEnd )
				)
				( attribute "CHIPS_PART_NAME" "CAP"
					( Origin gPackager )
				)
				( attribute "CDS_PART_NAME" "CAP_0402-0.22UF,16V,10%,X7R,A3A"
					( Origin gPackager )
				)
				( objectStatus "C9N9" )
				( pin "a"
					( attribute "PN" "1"
						( Origin gPackager )
					)
					( objectStatus "C9N9.1" )
				)
				( pin "b"
					( attribute "PN" "2"
						( Origin gPackager )
					)
					( objectStatus "C9N9.2" )
				)
			)
			( gate "@baseboard_fab2_lib.baseboard_fab2(sch_1):page182_i50"
				( attribute "BOM_COST" "IO_SLOT"
					( Origin gFrontEnd )
				)
				( attribute "CDS_LIB" "mstr_discrete"
					( Origin gPackager )
				)
				( attribute "CDS_LOCATION" "C9N8"
					( Origin gPackager )
				)
				( attribute "CDS_SEC" "1"
					( Origin gPackager )
				)
				( attribute "LOCATION" "C9N8"
					( Origin gFrontEnd )
				)
				( attribute "MATERIAL" "X7R"
					( Origin gFrontEnd )
				)
				( attribute "PACK_TYPE" "0402"
					( Origin gFrontEnd )
				)
				( attribute "PART_NUMBER" "A36096-155"
					( Origin gFrontEnd )
				)
				( attribute "PHYS_PAGE" "182"
					( Origin gFrontEnd )
				)
				( attribute "ROOM" "IO_SLOT"
					( Origin gFrontEnd )
				)
				( attribute "ROT" "0"
					( Origin gFrontEnd )
				)
				( attribute "SEC" "1"
					( Origin gFrontEnd )
				)
				( attribute "SEC_TYPE" "0402"
					( Origin gFrontEnd )
				)
				( attribute "TOLERANCE" "10%"
					( Origin gFrontEnd )
				)
				( attribute "VALUE" "0.22UF"
					( Origin gFrontEnd )
				)
				( attribute "VER" "2"
					( Origin gFrontEnd )
				)
				( attribute "VOLTAGE" "16V"
					( Units "uVoltage" "V" 1.000000)
					( Origin gFrontEnd )
				)
				( attribute "XY" "(-2475,2900)"
					( Origin gFrontEnd )
				)
				( attribute "CHIPS_PART_NAME" "CAP"
					( Origin gPackager )
				)
				( attribute "CDS_PART_NAME" "CAP_0402-0.22UF,16V,10%,X7R,A3A"
					( Origin gPackager )
				)
				( objectStatus "C9N8" )
				( pin "a"
					( attribute "PN" "1"
						( Origin gPackager )
					)
					( objectStatus "C9N8.1" )
				)
				( pin "b"
					( attribute "PN" "2"
						( Origin gPackager )
					)
					( objectStatus "C9N8.2" )
				)
			)
			( gate "@baseboard_fab2_lib.baseboard_fab2(sch_1):page182_i51"
				( attribute "BOM_COST" "IO_SLOT"
					( Origin gFrontEnd )
				)
				( attribute "CDS_LIB" "mstr_discrete"
					( Origin gPackager )
				)
				( attribute "CDS_LOCATION" "C9N3"
					( Origin gPackager )
				)
				( attribute "CDS_SEC" "1"
					( Origin gPackager )
				)
				( attribute "LOCATION" "C9N3"
					( Origin gFrontEnd )
				)
				( attribute "MATERIAL" "X7R"
					( Origin gFrontEnd )
				)
				( attribute "PACK_TYPE" "0402"
					( Origin gFrontEnd )
				)
				( attribute "PART_NUMBER" "A36096-155"
					( Origin gFrontEnd )
				)
				( attribute "PHYS_PAGE" "182"
					( Origin gFrontEnd )
				)
				( attribute "ROOM" "IO_SLOT"
					( Origin gFrontEnd )
				)
				( attribute "ROT" "0"
					( Origin gFrontEnd )
				)
				( attribute "SEC" "1"
					( Origin gFrontEnd )
				)
				( attribute "SEC_TYPE" "0402"
					( Origin gFrontEnd )
				)
				( attribute "TOLERANCE" "10%"
					( Origin gFrontEnd )
				)
				( attribute "VALUE" "0.22UF"
					( Origin gFrontEnd )
				)
				( attribute "VER" "2"
					( Origin gFrontEnd )
				)
				( attribute "VOLTAGE" "16V"
					( Units "uVoltage" "V" 1.000000)
					( Origin gFrontEnd )
				)
				( attribute "XY" "(-2475,2550)"
					( Origin gFrontEnd )
				)
				( attribute "CHIPS_PART_NAME" "CAP"
					( Origin gPackager )
				)
				( attribute "CDS_PART_NAME" "CAP_0402-0.22UF,16V,10%,X7R,A3A"
					( Origin gPackager )
				)
				( objectStatus "C9N3" )
				( pin "a"
					( attribute "PN" "1"
						( Origin gPackager )
					)
					( objectStatus "C9N3.1" )
				)
				( pin "b"
					( attribute "PN" "2"
						( Origin gPackager )
					)
					( objectStatus "C9N3.2" )
				)
			)
			( gate "@baseboard_fab2_lib.baseboard_fab2(sch_1):page182_i52"
				( attribute "BOM_COST" "IO_SLOT"
					( Origin gFrontEnd )
				)
				( attribute "CDS_LIB" "mstr_discrete"
					( Origin gPackager )
				)
				( attribute "CDS_LOCATION" "C9N16"
					( Origin gPackager )
				)
				( attribute "CDS_SEC" "1"
					( Origin gPackager )
				)
				( attribute "LOCATION" "C9N16"
					( Origin gFrontEnd )
				)
				( attribute "MATERIAL" "X7R"
					( Origin gFrontEnd )
				)
				( attribute "PACK_TYPE" "0402"
					( Origin gFrontEnd )
				)
				( attribute "PART_NUMBER" "A36096-155"
					( Origin gFrontEnd )
				)
				( attribute "PHYS_PAGE" "182"
					( Origin gFrontEnd )
				)
				( attribute "ROOM" "IO_SLOT"
					( Origin gFrontEnd )
				)
				( attribute "ROT" "0"
					( Origin gFrontEnd )
				)
				( attribute "SEC" "1"
					( Origin gFrontEnd )
				)
				( attribute "SEC_TYPE" "0402"
					( Origin gFrontEnd )
				)
				( attribute "TOLERANCE" "10%"
					( Origin gFrontEnd )
				)
				( attribute "VALUE" "0.22UF"
					( Origin gFrontEnd )
				)
				( attribute "VER" "2"
					( Origin gFrontEnd )
				)
				( attribute "VOLTAGE" "16V"
					( Units "uVoltage" "V" 1.000000)
					( Origin gFrontEnd )
				)
				( attribute "XY" "(-2475,2400)"
					( Origin gFrontEnd )
				)
				( attribute "CHIPS_PART_NAME" "CAP"
					( Origin gPackager )
				)
				( attribute "CDS_PART_NAME" "CAP_0402-0.22UF,16V,10%,X7R,A3A"
					( Origin gPackager )
				)
				( objectStatus "C9N16" )
				( pin "a"
					( attribute "PN" "1"
						( Origin gPackager )
					)
					( objectStatus "C9N16.1" )
				)
				( pin "b"
					( attribute "PN" "2"
						( Origin gPackager )
					)
					( objectStatus "C9N16.2" )
				)
			)
			( gate "@baseboard_fab2_lib.baseboard_fab2(sch_1):page182_i53"
				( attribute "BOM_COST" "IO_SLOT"
					( Origin gFrontEnd )
				)
				( attribute "CDS_LIB" "mstr_discrete"
					( Origin gPackager )
				)
				( attribute "CDS_LOCATION" "C9N10"
					( Origin gPackager )
				)
				( attribute "CDS_SEC" "1"
					( Origin gPackager )
				)
				( attribute "LOCATION" "C9N10"
					( Origin gFrontEnd )
				)
				( attribute "MATERIAL" "X7R"
					( Origin gFrontEnd )
				)
				( attribute "PACK_TYPE" "0402"
					( Origin gFrontEnd )
				)
				( attribute "PART_NUMBER" "A36096-155"
					( Origin gFrontEnd )
				)
				( attribute "PHYS_PAGE" "182"
					( Origin gFrontEnd )
				)
				( attribute "ROOM" "IO_SLOT"
					( Origin gFrontEnd )
				)
				( attribute "ROT" "0"
					( Origin gFrontEnd )
				)
				( attribute "SEC" "1"
					( Origin gFrontEnd )
				)
				( attribute "SEC_TYPE" "0402"
					( Origin gFrontEnd )
				)
				( attribute "TOLERANCE" "10%"
					( Origin gFrontEnd )
				)
				( attribute "VALUE" "0.22UF"
					( Origin gFrontEnd )
				)
				( attribute "VER" "2"
					( Origin gFrontEnd )
				)
				( attribute "VOLTAGE" "16V"
					( Units "uVoltage" "V" 1.000000)
					( Origin gFrontEnd )
				)
				( attribute "XY" "(-2950,2850)"
					( Origin gFrontEnd )
				)
				( attribute "CHIPS_PART_NAME" "CAP"
					( Origin gPackager )
				)
				( attribute "CDS_PART_NAME" "CAP_0402-0.22UF,16V,10%,X7R,A3A"
					( Origin gPackager )
				)
				( objectStatus "C9N10" )
				( pin "a"
					( attribute "PN" "1"
						( Origin gPackager )
					)
					( objectStatus "C9N10.1" )
				)
				( pin "b"
					( attribute "PN" "2"
						( Origin gPackager )
					)
					( objectStatus "C9N10.2" )
				)
			)
			( gate "@baseboard_fab2_lib.baseboard_fab2(sch_1):page182_i54"
				( attribute "BOM_COST" "IO_SLOT"
					( Origin gFrontEnd )
				)
				( attribute "CDS_LIB" "mstr_discrete"
					( Origin gPackager )
				)
				( attribute "CDS_LOCATION" "C9N7"
					( Origin gPackager )
				)
				( attribute "CDS_SEC" "1"
					( Origin gPackager )
				)
				( attribute "LOCATION" "C9N7"
					( Origin gFrontEnd )
				)
				( attribute "MATERIAL" "X7R"
					( Origin gFrontEnd )
				)
				( attribute "PACK_TYPE" "0402"
					( Origin gFrontEnd )
				)
				( attribute "PART_NUMBER" "A36096-155"
					( Origin gFrontEnd )
				)
				( attribute "PHYS_PAGE" "182"
					( Origin gFrontEnd )
				)
				( attribute "ROOM" "IO_SLOT"
					( Origin gFrontEnd )
				)
				( attribute "ROT" "0"
					( Origin gFrontEnd )
				)
				( attribute "SEC" "1"
					( Origin gFrontEnd )
				)
				( attribute "SEC_TYPE" "0402"
					( Origin gFrontEnd )
				)
				( attribute "TOLERANCE" "10%"
					( Origin gFrontEnd )
				)
				( attribute "VALUE" "0.22UF"
					( Origin gFrontEnd )
				)
				( attribute "VER" "2"
					( Origin gFrontEnd )
				)
				( attribute "VOLTAGE" "16V"
					( Units "uVoltage" "V" 1.000000)
					( Origin gFrontEnd )
				)
				( attribute "XY" "(-2950,2700)"
					( Origin gFrontEnd )
				)
				( attribute "CHIPS_PART_NAME" "CAP"
					( Origin gPackager )
				)
				( attribute "CDS_PART_NAME" "CAP_0402-0.22UF,16V,10%,X7R,A3A"
					( Origin gPackager )
				)
				( objectStatus "C9N7" )
				( pin "a"
					( attribute "PN" "1"
						( Origin gPackager )
					)
					( objectStatus "C9N7.1" )
				)
				( pin "b"
					( attribute "PN" "2"
						( Origin gPackager )
					)
					( objectStatus "C9N7.2" )
				)
			)
			( gate "@baseboard_fab2_lib.baseboard_fab2(sch_1):page182_i55"
				( attribute "BOM_COST" "IO_SLOT"
					( Origin gFrontEnd )
				)
				( attribute "CDS_LIB" "mstr_discrete"
					( Origin gPackager )
				)
				( attribute "CDS_LOCATION" "C9N4"
					( Origin gPackager )
				)
				( attribute "CDS_SEC" "1"
					( Origin gPackager )
				)
				( attribute "LOCATION" "C9N4"
					( Origin gFrontEnd )
				)
				( attribute "MATERIAL" "X7R"
					( Origin gFrontEnd )
				)
				( attribute "PACK_TYPE" "0402"
					( Origin gFrontEnd )
				)
				( attribute "PART_NUMBER" "A36096-155"
					( Origin gFrontEnd )
				)
				( attribute "PHYS_PAGE" "182"
					( Origin gFrontEnd )
				)
				( attribute "ROOM" "IO_SLOT"
					( Origin gFrontEnd )
				)
				( attribute "ROT" "0"
					( Origin gFrontEnd )
				)
				( attribute "SEC" "1"
					( Origin gFrontEnd )
				)
				( attribute "SEC_TYPE" "0402"
					( Origin gFrontEnd )
				)
				( attribute "TOLERANCE" "10%"
					( Origin gFrontEnd )
				)
				( attribute "VALUE" "0.22UF"
					( Origin gFrontEnd )
				)
				( attribute "VER" "2"
					( Origin gFrontEnd )
				)
				( attribute "VOLTAGE" "16V"
					( Units "uVoltage" "V" 1.000000)
					( Origin gFrontEnd )
				)
				( attribute "XY" "(-2950,2500)"
					( Origin gFrontEnd )
				)
				( attribute "CHIPS_PART_NAME" "CAP"
					( Origin gPackager )
				)
				( attribute "CDS_PART_NAME" "CAP_0402-0.22UF,16V,10%,X7R,A3A"
					( Origin gPackager )
				)
				( objectStatus "C9N4" )
				( pin "a"
					( attribute "PN" "1"
						( Origin gPackager )
					)
					( objectStatus "C9N4.1" )
				)
				( pin "b"
					( attribute "PN" "2"
						( Origin gPackager )
					)
					( objectStatus "C9N4.2" )
				)
			)
			( gate "@baseboard_fab2_lib.baseboard_fab2(sch_1):page182_i56"
				( attribute "BOM_COST" "IO_SLOT"
					( Origin gFrontEnd )
				)
				( attribute "CDS_LIB" "mstr_discrete"
					( Origin gPackager )
				)
				( attribute "CDS_LOCATION" "C9N14"
					( Origin gPackager )
				)
				( attribute "CDS_SEC" "1"
					( Origin gPackager )
				)
				( attribute "LOCATION" "C9N14"
					( Origin gFrontEnd )
				)
				( attribute "MATERIAL" "X7R"
					( Origin gFrontEnd )
				)
				( attribute "PACK_TYPE" "0402"
					( Origin gFrontEnd )
				)
				( attribute "PART_NUMBER" "A36096-155"
					( Origin gFrontEnd )
				)
				( attribute "PHYS_PAGE" "182"
					( Origin gFrontEnd )
				)
				( attribute "ROOM" "IO_SLOT"
					( Origin gFrontEnd )
				)
				( attribute "ROT" "0"
					( Origin gFrontEnd )
				)
				( attribute "SEC" "1"
					( Origin gFrontEnd )
				)
				( attribute "SEC_TYPE" "0402"
					( Origin gFrontEnd )
				)
				( attribute "TOLERANCE" "10%"
					( Origin gFrontEnd )
				)
				( attribute "VALUE" "0.22UF"
					( Origin gFrontEnd )
				)
				( attribute "VER" "2"
					( Origin gFrontEnd )
				)
				( attribute "VOLTAGE" "16V"
					( Units "uVoltage" "V" 1.000000)
					( Origin gFrontEnd )
				)
				( attribute "XY" "(-2950,2350)"
					( Origin gFrontEnd )
				)
				( attribute "CHIPS_PART_NAME" "CAP"
					( Origin gPackager )
				)
				( attribute "CDS_PART_NAME" "CAP_0402-0.22UF,16V,10%,X7R,A3A"
					( Origin gPackager )
				)
				( objectStatus "C9N14" )
				( pin "a"
					( attribute "PN" "1"
						( Origin gPackager )
					)
					( objectStatus "C9N14.1" )
				)
				( pin "b"
					( attribute "PN" "2"
						( Origin gPackager )
					)
					( objectStatus "C9N14.2" )
				)
			)
			( gate "@baseboard_fab2_lib.baseboard_fab2(sch_1):page182_i81"
				( attribute "BOM_COST" "IO_SLOT"
					( Origin gFrontEnd )
				)
				( attribute "CDS_LIB" "mstr_discrete"
					( Origin gPackager )
				)
				( attribute "CDS_LOCATION" "C9N6"
					( Origin gPackager )
				)
				( attribute "CDS_SEC" "1"
					( Origin gPackager )
				)
				( attribute "LOCATION" "C9N6"
					( Origin gFrontEnd )
				)
				( attribute "MATERIAL" "X7R"
					( Origin gFrontEnd )
				)
				( attribute "PACK_TYPE" "0402"
					( Origin gFrontEnd )
				)
				( attribute "PART_NUMBER" "A36096-155"
					( Origin gFrontEnd )
				)
				( attribute "PHYS_PAGE" "182"
					( Origin gFrontEnd )
				)
				( attribute "ROOM" "IO_SLOT"
					( Origin gFrontEnd )
				)
				( attribute "ROT" "0"
					( Origin gFrontEnd )
				)
				( attribute "SEC" "1"
					( Origin gFrontEnd )
				)
				( attribute "SEC_TYPE" "0402"
					( Origin gFrontEnd )
				)
				( attribute "TOLERANCE" "10%"
					( Origin gFrontEnd )
				)
				( attribute "VALUE" "0.22UF"
					( Origin gFrontEnd )
				)
				( attribute "VER" "2"
					( Origin gFrontEnd )
				)
				( attribute "VOLTAGE" "16V"
					( Units "uVoltage" "V" 1.000000)
					( Origin gFrontEnd )
				)
				( attribute "XY" "(-2950,2250)"
					( Origin gFrontEnd )
				)
				( attribute "CHIPS_PART_NAME" "CAP"
					( Origin gPackager )
				)
				( attribute "CDS_PART_NAME" "CAP_0402-0.22UF,16V,10%,X7R,A3A"
					( Origin gPackager )
				)
				( objectStatus "C9N6" )
				( pin "a"
					( attribute "PN" "1"
						( Origin gPackager )
					)
					( objectStatus "C9N6.1" )
				)
				( pin "b"
					( attribute "PN" "2"
						( Origin gPackager )
					)
					( objectStatus "C9N6.2" )
				)
			)
			( gate "@baseboard_fab2_lib.baseboard_fab2(sch_1):page182_i83"
				( attribute "BOM_COST" "IO_SLOT"
					( Origin gFrontEnd )
				)
				( attribute "CDS_LIB" "mstr_discrete"
					( Origin gPackager )
				)
				( attribute "CDS_LOCATION" "C9N5"
					( Origin gPackager )
				)
				( attribute "CDS_SEC" "1"
					( Origin gPackager )
				)
				( attribute "LOCATION" "C9N5"
					( Origin gFrontEnd )
				)
				( attribute "MATERIAL" "X7R"
					( Origin gFrontEnd )
				)
				( attribute "PACK_TYPE" "0402"
					( Origin gFrontEnd )
				)
				( attribute "PART_NUMBER" "A36096-155"
					( Origin gFrontEnd )
				)
				( attribute "PHYS_PAGE" "182"
					( Origin gFrontEnd )
				)
				( attribute "ROOM" "IO_SLOT"
					( Origin gFrontEnd )
				)
				( attribute "ROT" "0"
					( Origin gFrontEnd )
				)
				( attribute "SEC" "1"
					( Origin gFrontEnd )
				)
				( attribute "SEC_TYPE" "0402"
					( Origin gFrontEnd )
				)
				( attribute "TOLERANCE" "10%"
					( Origin gFrontEnd )
				)
				( attribute "VALUE" "0.22UF"
					( Origin gFrontEnd )
				)
				( attribute "VER" "2"
					( Origin gFrontEnd )
				)
				( attribute "VOLTAGE" "16V"
					( Units "uVoltage" "V" 1.000000)
					( Origin gFrontEnd )
				)
				( attribute "XY" "(-2475,2200)"
					( Origin gFrontEnd )
				)
				( attribute "CHIPS_PART_NAME" "CAP"
					( Origin gPackager )
				)
				( attribute "CDS_PART_NAME" "CAP_0402-0.22UF,16V,10%,X7R,A3A"
					( Origin gPackager )
				)
				( objectStatus "C9N5" )
				( pin "a"
					( attribute "PN" "1"
						( Origin gPackager )
					)
					( objectStatus "C9N5.1" )
				)
				( pin "b"
					( attribute "PN" "2"
						( Origin gPackager )
					)
					( objectStatus "C9N5.2" )
				)
			)
			( gate "@baseboard_fab2_lib.baseboard_fab2(sch_1):page182_i97"
				( attribute "CDS_LIB" "mstr_discrete"
					( Origin gPackager )
				)
				( attribute "CDS_LOCATION" "R1C11"
					( Origin gPackager )
				)
				( attribute "CDS_SEC" "1"
					( Origin gPackager )
				)
				( attribute "LOCATION" "R1C11"
					( Origin gFrontEnd )
				)
				( attribute "MATERIAL" "EMPTY"
					( Origin gFrontEnd )
				)
				( attribute "NO_XNET_CONNECTION" "1"
					( Origin gFrontEnd )
				)
				( attribute "PACK_TYPE" "0402"
					( Origin gFrontEnd )
				)
				( attribute "PART_NUMBER" "G21497-005"
					( Origin gFrontEnd )
				)
				( attribute "PHYS_PAGE" "182"
					( Origin gFrontEnd )
				)
				( attribute "ROOM" "IO_SLOT"
					( Origin gFrontEnd )
				)
				( attribute "ROT" "0"
					( Origin gFrontEnd )
				)
				( attribute "SEC" "1"
					( Origin gFrontEnd )
				)
				( attribute "SEC_TYPE" "0402"
					( Origin gFrontEnd )
				)
				( attribute "TOLERANCE" "5%"
					( Origin gFrontEnd )
				)
				( attribute "VALUE" "0.0"
					( Origin gFrontEnd )
				)
				( attribute "VER" "1"
					( Origin gFrontEnd )
				)
				( attribute "WATTAGE" "1/16W"
					( Origin gFrontEnd )
				)
				( attribute "XY" "(-6550,875)"
					( Origin gFrontEnd )
				)
				( attribute "CHIPS_PART_NAME" "RES"
					( Origin gPackager )
				)
				( attribute "CDS_PART_NAME" "RES_0402-0.0,5%,1/16W,EMPTY,G2A"
					( Origin gPackager )
				)
				( objectStatus "R1C11" )
				( pin "a"
					( attribute "PN" "1"
						( Origin gPackager )
					)
					( objectStatus "R1C11.1" )
				)
				( pin "b"
					( attribute "PN" "2"
						( Origin gPackager )
					)
					( objectStatus "R1C11.2" )
				)
			)
			( gate "@baseboard_fab2_lib.baseboard_fab2(sch_1):page182_i101"
				( attribute "CDS_LIB" "mstr_discrete"
					( Origin gPackager )
				)
				( attribute "CDS_LOCATION" "R1C10"
					( Origin gPackager )
				)
				( attribute "CDS_SEC" "1"
					( Origin gPackager )
				)
				( attribute "LOCATION" "R1C10"
					( Origin gFrontEnd )
				)
				( attribute "MATERIAL" "EMPTY"
					( Origin gFrontEnd )
				)
				( attribute "NO_XNET_CONNECTION" "1"
					( Origin gFrontEnd )
				)
				( attribute "PACK_TYPE" "0402"
					( Origin gFrontEnd )
				)
				( attribute "PART_NUMBER" "G21497-005"
					( Origin gFrontEnd )
				)
				( attribute "PHYS_PAGE" "182"
					( Origin gFrontEnd )
				)
				( attribute "ROOM" "IO_SLOT"
					( Origin gFrontEnd )
				)
				( attribute "ROT" "0"
					( Origin gFrontEnd )
				)
				( attribute "SEC" "1"
					( Origin gFrontEnd )
				)
				( attribute "SEC_TYPE" "0402"
					( Origin gFrontEnd )
				)
				( attribute "TOLERANCE" "5%"
					( Origin gFrontEnd )
				)
				( attribute "VALUE" "0.0"
					( Origin gFrontEnd )
				)
				( attribute "VER" "1"
					( Origin gFrontEnd )
				)
				( attribute "WATTAGE" "1/16W"
					( Origin gFrontEnd )
				)
				( attribute "XY" "(-6550,750)"
					( Origin gFrontEnd )
				)
				( attribute "CHIPS_PART_NAME" "RES"
					( Origin gPackager )
				)
				( attribute "CDS_PART_NAME" "RES_0402-0.0,5%,1/16W,EMPTY,G2A"
					( Origin gPackager )
				)
				( objectStatus "R1C10" )
				( pin "a"
					( attribute "PN" "1"
						( Origin gPackager )
					)
					( objectStatus "R1C10.1" )
				)
				( pin "b"
					( attribute "PN" "2"
						( Origin gPackager )
					)
					( objectStatus "R1C10.2" )
				)
			)
			( gate "@baseboard_fab2_lib.baseboard_fab2(sch_1):page182_i104"
				( attribute "CDS_LIB" "mstr_discrete"
					( Origin gPackager )
				)
				( attribute "CDS_LOCATION" "R1C9"
					( Origin gPackager )
				)
				( attribute "CDS_SEC" "1"
					( Origin gPackager )
				)
				( attribute "LOCATION" "R1C9"
					( Origin gFrontEnd )
				)
				( attribute "MATERIAL" "EMPTY"
					( Origin gFrontEnd )
				)
				( attribute "NO_XNET_CONNECTION" "1"
					( Origin gFrontEnd )
				)
				( attribute "PACK_TYPE" "0402"
					( Origin gFrontEnd )
				)
				( attribute "PART_NUMBER" "G21497-005"
					( Origin gFrontEnd )
				)
				( attribute "PHYS_PAGE" "182"
					( Origin gFrontEnd )
				)
				( attribute "ROOM" "IO_SLOT"
					( Origin gFrontEnd )
				)
				( attribute "ROT" "0"
					( Origin gFrontEnd )
				)
				( attribute "SEC" "1"
					( Origin gFrontEnd )
				)
				( attribute "SEC_TYPE" "0402"
					( Origin gFrontEnd )
				)
				( attribute "TOLERANCE" "5%"
					( Origin gFrontEnd )
				)
				( attribute "VALUE" "0.0"
					( Origin gFrontEnd )
				)
				( attribute "VER" "1"
					( Origin gFrontEnd )
				)
				( attribute "WATTAGE" "1/16W"
					( Origin gFrontEnd )
				)
				( attribute "XY" "(-6550,625)"
					( Origin gFrontEnd )
				)
				( attribute "CHIPS_PART_NAME" "RES"
					( Origin gPackager )
				)
				( attribute "CDS_PART_NAME" "RES_0402-0.0,5%,1/16W,EMPTY,G2A"
					( Origin gPackager )
				)
				( objectStatus "R1C9" )
				( pin "a"
					( attribute "PN" "1"
						( Origin gPackager )
					)
					( objectStatus "R1C9.1" )
				)
				( pin "b"
					( attribute "PN" "2"
						( Origin gPackager )
					)
					( objectStatus "R1C9.2" )
				)
			)
			( gate "@baseboard_fab2_lib.baseboard_fab2(sch_1):page182_i107"
				( attribute "CDS_LIB" "mstr_discrete"
					( Origin gPackager )
				)
				( attribute "CDS_LOCATION" "R1F9"
					( Origin gPackager )
				)
				( attribute "CDS_SEC" "1"
					( Origin gPackager )
				)
				( attribute "LOCATION" "R1F9"
					( Origin gFrontEnd )
				)
				( attribute "MATERIAL" "EMPTY"
					( Origin gFrontEnd )
				)
				( attribute "NO_XNET_CONNECTION" "1"
					( Origin gFrontEnd )
				)
				( attribute "PACK_TYPE" "0402"
					( Origin gFrontEnd )
				)
				( attribute "PART_NUMBER" "G21497-005"
					( Origin gFrontEnd )
				)
				( attribute "PHYS_PAGE" "182"
					( Origin gFrontEnd )
				)
				( attribute "ROOM" "IO_SLOT"
					( Origin gFrontEnd )
				)
				( attribute "ROT" "0"
					( Origin gFrontEnd )
				)
				( attribute "SEC" "1"
					( Origin gFrontEnd )
				)
				( attribute "SEC_TYPE" "0402"
					( Origin gFrontEnd )
				)
				( attribute "TOLERANCE" "5%"
					( Origin gFrontEnd )
				)
				( attribute "VALUE" "0.0"
					( Origin gFrontEnd )
				)
				( attribute "VER" "1"
					( Origin gFrontEnd )
				)
				( attribute "WATTAGE" "1/16W"
					( Origin gFrontEnd )
				)
				( attribute "XY" "(-6550,500)"
					( Origin gFrontEnd )
				)
				( attribute "CHIPS_PART_NAME" "RES"
					( Origin gPackager )
				)
				( attribute "CDS_PART_NAME" "RES_0402-0.0,5%,1/16W,EMPTY,G2A"
					( Origin gPackager )
				)
				( objectStatus "R1F9" )
				( pin "a"
					( attribute "PN" "1"
						( Origin gPackager )
					)
					( objectStatus "R1F9.1" )
				)
				( pin "b"
					( attribute "PN" "2"
						( Origin gPackager )
					)
					( objectStatus "R1F9.2" )
				)
			)
			( gate "@baseboard_fab2_lib.baseboard_fab2(sch_1):page182_i110"
				( attribute "CDS_LIB" "mstr_discrete"
					( Origin gPackager )
				)
				( attribute "CDS_LOCATION" "R1C31"
					( Origin gPackager )
				)
				( attribute "CDS_SEC" "1"
					( Origin gPackager )
				)
				( attribute "LOCATION" "R1C31"
					( Origin gFrontEnd )
				)
				( attribute "MATERIAL" "EMPTY"
					( Origin gFrontEnd )
				)
				( attribute "NO_XNET_CONNECTION" "1"
					( Origin gFrontEnd )
				)
				( attribute "PACK_TYPE" "0402"
					( Origin gFrontEnd )
				)
				( attribute "PART_NUMBER" "G21497-005"
					( Origin gFrontEnd )
				)
				( attribute "PHYS_PAGE" "182"
					( Origin gFrontEnd )
				)
				( attribute "ROOM" "IO_SLOT"
					( Origin gFrontEnd )
				)
				( attribute "ROT" "0"
					( Origin gFrontEnd )
				)
				( attribute "SEC" "1"
					( Origin gFrontEnd )
				)
				( attribute "SEC_TYPE" "0402"
					( Origin gFrontEnd )
				)
				( attribute "TOLERANCE" "5%"
					( Origin gFrontEnd )
				)
				( attribute "VALUE" "0.0"
					( Origin gFrontEnd )
				)
				( attribute "VER" "1"
					( Origin gFrontEnd )
				)
				( attribute "WATTAGE" "1/16W"
					( Origin gFrontEnd )
				)
				( attribute "XY" "(-6550,350)"
					( Origin gFrontEnd )
				)
				( attribute "CHIPS_PART_NAME" "RES"
					( Origin gPackager )
				)
				( attribute "CDS_PART_NAME" "RES_0402-0.0,5%,1/16W,EMPTY,G2A"
					( Origin gPackager )
				)
				( objectStatus "R1C31" )
				( pin "a"
					( attribute "PN" "1"
						( Origin gPackager )
					)
					( objectStatus "R1C31.1" )
				)
				( pin "b"
					( attribute "PN" "2"
						( Origin gPackager )
					)
					( objectStatus "R1C31.2" )
				)
			)
			( gate "@baseboard_fab2_lib.baseboard_fab2(sch_1):page183_i1"
				( attribute "BOM_COST" "LBG_UART"
					( Origin gFrontEnd )
				)
				( attribute "CDS_LIB" "mstr_controller"
					( Origin gPackager )
				)
				( attribute "CDS_LOCATION" "EU9F3"
					( Origin gPackager )
				)
				( attribute "CDS_SEC" "1"
					( Origin gPackager )
				)
				( attribute "LOCATION" "EU9F3"
					( Origin gFrontEnd )
				)
				( attribute "MATERIAL" "IC"
					( Origin gFrontEnd )
				)
				( attribute "PACK_TYPE" "QFN"
					( Origin gFrontEnd )
				)
				( attribute "PART_NUMBER" "H66899-001"
					( Origin gFrontEnd )
				)
				( attribute "PHYS_PAGE" "183"
					( Origin gFrontEnd )
				)
				( attribute "ROOM" "LBG"
					( Origin gFrontEnd )
				)
				( attribute "ROT" "0"
					( Origin gFrontEnd )
				)
				( attribute "SEC" "1"
					( Origin gPackager )
				)
				( attribute "VER" "1"
					( Origin gFrontEnd )
				)
				( attribute "XY" "(1475,1025)"
					( Origin gFrontEnd )
				)
				( attribute "CHIPS_PART_NAME" "PI7C9X1172"
					( Origin gPackager )
				)
				( attribute "CDS_PART_NAME" "PI7C9X1172_QFN-IC,H66899-001"
					( Origin gPackager )
				)
				( objectStatus "EU9F3" )
				( pin "a0_cs_n"
					( attribute "PN" "30"
						( Origin gPackager )
					)
					( objectStatus "EU9F3.30" )
				)
				( pin "a1_s1"
					( attribute "PN" "31"
						( Origin gPackager )
					)
					( objectStatus "EU9F3.31" )
				)
				( pin "ctsa_n"
					( attribute "PN" "25"
						( Origin gPackager )
					)
					( objectStatus "EU9F3.25" )
				)
				( pin "ctsb_n"
					( attribute "PN" "16"
						( Origin gPackager )
					)
					( objectStatus "EU9F3.16" )
				)
				( pin "en485_n"
					( attribute "PN" "19"
						( Origin gPackager )
					)
					( objectStatus "EU9F3.19" )
				)
				( pin "enir_n"
					( attribute "PN" "18"
						( Origin gPackager )
					)
					( objectStatus "EU9F3.18" )
				)
				( pin "gnd"
					( attribute "PN" "12"
						( Origin gPackager )
					)
					( objectStatus "EU9F3.12" )
				)
				( pin "gpio0_dsrb_n"
					( attribute "PN" "13"
						( Origin gPackager )
					)
					( objectStatus "EU9F3.13" )
				)
				( pin "gpio1_dtrb_n"
					( attribute "PN" "23"
						( Origin gPackager )
					)
					( objectStatus "EU9F3.23" )
				)
				( pin "gpio2_cdb_n"
					( attribute "PN" "11"
						( Origin gPackager )
					)
					( objectStatus "EU9F3.11" )
				)
				( pin "gpio3_rib_n"
					( attribute "PN" "14"
						( Origin gPackager )
					)
					( objectStatus "EU9F3.14" )
				)
				( pin "gpio4_dsra_n"
					( attribute "PN" "26"
						( Origin gPackager )
					)
					( objectStatus "EU9F3.26" )
				)
				( pin "gpio5_dtra_n"
					( attribute "PN" "22"
						( Origin gPackager )
					)
					( objectStatus "EU9F3.22" )
				)
				( pin "gpio6_cda_n"
					( attribute "PN" "27"
						( Origin gPackager )
					)
					( objectStatus "EU9F3.27" )
				)
				( pin "gpio7_ria_n"
					( attribute "PN" "28"
						( Origin gPackager )
					)
					( objectStatus "EU9F3.28" )
				)
				( pin "i2c_spi_n"
					( attribute "PN" "32"
						( Origin gPackager )
					)
					( objectStatus "EU9F3.32" )
				)
				( pin "irq_n"
					( attribute "PN" "20"
						( Origin gPackager )
					)
					( objectStatus "EU9F3.20" )
				)
				( pin "nc(0)"
					( attribute "PN" "1"
						( Origin gPackager )
					)
					( objectStatus "EU9F3.1" )
				)
				( pin "nc(1)"
					( attribute "PN" "8"
						( Origin gPackager )
					)
					( objectStatus "EU9F3.8" )
				)
				( pin "reset_n"
					( attribute "PN" "24"
						( Origin gPackager )
					)
					( objectStatus "EU9F3.24" )
				)
				( pin "rtsa_n"
					( attribute "PN" "21"
						( Origin gPackager )
					)
					( objectStatus "EU9F3.21" )
				)
				( pin "rtsb_n"
					( attribute "PN" "15"
						( Origin gPackager )
					)
					( objectStatus "EU9F3.15" )
				)
				( pin "rxa"
					( attribute "PN" "5"
						( Origin gPackager )
					)
					( objectStatus "EU9F3.5" )
				)
				( pin "rxb"
					( attribute "PN" "4"
						( Origin gPackager )
					)
					( objectStatus "EU9F3.4" )
				)
				( pin "scl"
					( attribute "PN" "17"
						( Origin gPackager )
					)
					( objectStatus "EU9F3.17" )
				)
				( pin "sda"
					( attribute "PN" "3"
						( Origin gPackager )
					)
					( objectStatus "EU9F3.3" )
				)
				( pin "so"
					( attribute "PN" "2"
						( Origin gPackager )
					)
					( objectStatus "EU9F3.2" )
				)
				( pin "thpad"
					( attribute "PN" "33"
						( Origin gPackager )
					)
					( objectStatus "EU9F3.33" )
				)
				( pin "txa"
					( attribute "PN" "6"
						( Origin gPackager )
					)
					( objectStatus "EU9F3.6" )
				)
				( pin "txb"
					( attribute "PN" "7"
						( Origin gPackager )
					)
					( objectStatus "EU9F3.7" )
				)
				( pin "vdd"
					( attribute "PN" "29"
						( Origin gPackager )
					)
					( objectStatus "EU9F3.29" )
				)
				( pin "xtal1"
					( attribute "PN" "9"
						( Origin gPackager )
					)
					( objectStatus "EU9F3.9" )
				)
				( pin "xtal2"
					( attribute "PN" "10"
						( Origin gPackager )
					)
					( objectStatus "EU9F3.10" )
				)
			)
			( gate "@baseboard_fab2_lib.baseboard_fab2(sch_1):page183_i4"
				( attribute "BOM_COST" "LBG_UART"
					( Origin gFrontEnd )
				)
				( attribute "CDS_LIB" "mstr_discrete"
					( Origin gPackager )
				)
				( attribute "CDS_LOCATION" "R9F47"
					( Origin gPackager )
				)
				( attribute "CDS_SEC" "1"
					( Origin gPackager )
				)
				( attribute "LOCATION" "R9F47"
					( Origin gFrontEnd )
				)
				( attribute "MATERIAL" "CHIP"
					( Origin gFrontEnd )
				)
				( attribute "PACK_TYPE" "0402"
					( Origin gFrontEnd )
				)
				( attribute "PART_NUMBER" "G21796-072"
					( Origin gFrontEnd )
				)
				( attribute "PHYS_PAGE" "183"
					( Origin gFrontEnd )
				)
				( attribute "ROOM" "LBG"
					( Origin gFrontEnd )
				)
				( attribute "ROT" "0"
					( Origin gFrontEnd )
				)
				( attribute "SEC" "1"
					( Origin gFrontEnd )
				)
				( attribute "SEC_TYPE" "0402"
					( Origin gFrontEnd )
				)
				( attribute "TOLERANCE" "1%"
					( Origin gFrontEnd )
				)
				( attribute "VALUE" "4.75K"
					( Origin gFrontEnd )
				)
				( attribute "VER" "1"
					( Origin gFrontEnd )
				)
				( attribute "WATTAGE" "1/16W"
					( Origin gFrontEnd )
				)
				( attribute "XY" "(-150,1025)"
					( Origin gFrontEnd )
				)
				( attribute "CHIPS_PART_NAME" "RES"
					( Origin gPackager )
				)
				( attribute "CDS_PART_NAME" "RES_0402-4.75K,1%,1/16W,CHIP,GA"
					( Origin gPackager )
				)
				( objectStatus "R9F47" )
				( pin "a"
					( attribute "PN" "1"
						( Origin gPackager )
					)
					( objectStatus "R9F47.1" )
				)
				( pin "b"
					( attribute "PN" "2"
						( Origin gPackager )
					)
					( objectStatus "R9F47.2" )
				)
			)
			( gate "@baseboard_fab2_lib.baseboard_fab2(sch_1):page183_i7"
				( attribute "BOM_COST" "LBG_UART"
					( Origin gFrontEnd )
				)
				( attribute "CDS_LIB" "dev_discrete"
					( Origin gPackager )
				)
				( attribute "CDS_LOCATION" "C9F19"
					( Origin gPackager )
				)
				( attribute "CDS_SEC" "1"
					( Origin gPackager )
				)
				( attribute "LOCATION" "C9F19"
					( Origin gFrontEnd )
				)
				( attribute "MATERIAL" "X7R"
					( Origin gFrontEnd )
				)
				( attribute "PACK_TYPE" "0402V"
					( Origin gFrontEnd )
				)
				( attribute "PART_NUMBER" "A36096-030"
					( Origin gFrontEnd )
				)
				( attribute "PHYS_PAGE" "183"
					( Origin gFrontEnd )
				)
				( attribute "ROOM" "LBG"
					( Origin gFrontEnd )
				)
				( attribute "ROT" "0"
					( Origin gFrontEnd )
				)
				( attribute "SEC" "1"
					( Origin gFrontEnd )
				)
				( attribute "SEC_TYPE" "0402V"
					( Origin gFrontEnd )
				)
				( attribute "TOLERANCE" "10%"
					( Origin gFrontEnd )
				)
				( attribute "VALUE" "0.1UF"
					( Origin gFrontEnd )
				)
				( attribute "VER" "1"
					( Origin gFrontEnd )
				)
				( attribute "VOLTAGE" "16V"
					( Units "uVoltage" "V" 1.000000)
					( Origin gFrontEnd )
				)
				( attribute "XY" "(325,1775)"
					( Origin gFrontEnd )
				)
				( attribute "CHIPS_PART_NAME" "CAP_A"
					( Origin gPackager )
				)
				( attribute "CDS_PART_NAME" "CAP_A_0402V-0.1UF,16V,10%,X7R,A"
					( Origin gPackager )
				)
				( objectStatus "C9F19" )
				( pin "a"
					( attribute "PN" "1"
						( Origin gPackager )
					)
					( objectStatus "C9F19.1" )
				)
				( pin "b"
					( attribute "PN" "2"
						( Origin gPackager )
					)
					( objectStatus "C9F19.2" )
				)
			)
			( gate "@baseboard_fab2_lib.baseboard_fab2(sch_1):page183_i11"
				( attribute "BOM_COST" "LBG_UART"
					( Origin gFrontEnd )
				)
				( attribute "CDS_LIB" "mstr_discrete"
					( Origin gPackager )
				)
				( attribute "CDS_LOCATION" "R9F50"
					( Origin gPackager )
				)
				( attribute "CDS_SEC" "1"
					( Origin gPackager )
				)
				( attribute "LOCATION" "R9F50"
					( Origin gFrontEnd )
				)
				( attribute "MATERIAL" "CHIP"
					( Origin gFrontEnd )
				)
				( attribute "PACK_TYPE" "0402"
					( Origin gFrontEnd )
				)
				( attribute "PART_NUMBER" "G21796-026"
					( Origin gFrontEnd )
				)
				( attribute "PHYS_PAGE" "183"
					( Origin gFrontEnd )
				)
				( attribute "ROOM" "LBG"
					( Origin gFrontEnd )
				)
				( attribute "ROT" "0"
					( Origin gFrontEnd )
				)
				( attribute "SEC" "1"
					( Origin gPackager )
				)
				( attribute "TOLERANCE" "1%"
					( Origin gFrontEnd )
				)
				( attribute "VALUE" "1.00K"
					( Origin gFrontEnd )
				)
				( attribute "VER" "2"
					( Origin gFrontEnd )
				)
				( attribute "WATTAGE" "1/16W"
					( Origin gFrontEnd )
				)
				( attribute "XY" "(-1150,600)"
					( Origin gFrontEnd )
				)
				( attribute "CHIPS_PART_NAME" "RES"
					( Origin gPackager )
				)
				( attribute "CDS_PART_NAME" "RES_0402-1.00K,1%,1/16W,CHIP,GA"
					( Origin gPackager )
				)
				( objectStatus "R9F50" )
				( pin "a"
					( attribute "PN" "1"
						( Origin gPackager )
					)
					( objectStatus "R9F50.1" )
				)
				( pin "b"
					( attribute "PN" "2"
						( Origin gPackager )
					)
					( objectStatus "R9F50.2" )
				)
			)
			( gate "@baseboard_fab2_lib.baseboard_fab2(sch_1):page183_i12"
				( attribute "BOM_COST" "LBG_UART"
					( Origin gFrontEnd )
				)
				( attribute "CDS_LIB" "mstr_discrete"
					( Origin gPackager )
				)
				( attribute "CDS_LOCATION" "R9F51"
					( Origin gPackager )
				)
				( attribute "CDS_SEC" "1"
					( Origin gPackager )
				)
				( attribute "LOCATION" "R9F51"
					( Origin gFrontEnd )
				)
				( attribute "MATERIAL" "CHIP"
					( Origin gFrontEnd )
				)
				( attribute "PACK_TYPE" "0402"
					( Origin gFrontEnd )
				)
				( attribute "PART_NUMBER" "G21796-026"
					( Origin gFrontEnd )
				)
				( attribute "PHYS_PAGE" "183"
					( Origin gFrontEnd )
				)
				( attribute "ROOM" "LBG"
					( Origin gFrontEnd )
				)
				( attribute "ROT" "0"
					( Origin gFrontEnd )
				)
				( attribute "SEC" "1"
					( Origin gPackager )
				)
				( attribute "TOLERANCE" "1%"
					( Origin gFrontEnd )
				)
				( attribute "VALUE" "1.00K"
					( Origin gFrontEnd )
				)
				( attribute "VER" "2"
					( Origin gFrontEnd )
				)
				( attribute "WATTAGE" "1/16W"
					( Origin gFrontEnd )
				)
				( attribute "XY" "(-1500,600)"
					( Origin gFrontEnd )
				)
				( attribute "CHIPS_PART_NAME" "RES"
					( Origin gPackager )
				)
				( attribute "CDS_PART_NAME" "RES_0402-1.00K,1%,1/16W,CHIP,GA"
					( Origin gPackager )
				)
				( objectStatus "R9F51" )
				( pin "a"
					( attribute "PN" "1"
						( Origin gPackager )
					)
					( objectStatus "R9F51.1" )
				)
				( pin "b"
					( attribute "PN" "2"
						( Origin gPackager )
					)
					( objectStatus "R9F51.2" )
				)
			)
			( gate "@baseboard_fab2_lib.baseboard_fab2(sch_1):page183_i13"
				( attribute "BOM_COST" "LBG_UART"
					( Origin gFrontEnd )
				)
				( attribute "CDS_LIB" "mstr_discrete"
					( Origin gPackager )
				)
				( attribute "CDS_LOCATION" "R9F48"
					( Origin gPackager )
				)
				( attribute "CDS_SEC" "1"
					( Origin gPackager )
				)
				( attribute "LOCATION" "R9F48"
					( Origin gFrontEnd )
				)
				( attribute "MATERIAL" "EMPTY"
					( Origin gFrontEnd )
				)
				( attribute "PACK_TYPE" "0402"
					( Origin gFrontEnd )
				)
				( attribute "PART_NUMBER" "G21796-072"
					( Origin gFrontEnd )
				)
				( attribute "PHYS_PAGE" "183"
					( Origin gFrontEnd )
				)
				( attribute "ROOM" "LBG"
					( Origin gFrontEnd )
				)
				( attribute "ROT" "0"
					( Origin gFrontEnd )
				)
				( attribute "SEC" "1"
					( Origin gFrontEnd )
				)
				( attribute "SEC_TYPE" "0402"
					( Origin gFrontEnd )
				)
				( attribute "TOLERANCE" "1%"
					( Origin gFrontEnd )
				)
				( attribute "VALUE" "4.75K"
					( Origin gFrontEnd )
				)
				( attribute "VER" "2"
					( Origin gFrontEnd )
				)
				( attribute "WATTAGE" "1/16W"
					( Origin gFrontEnd )
				)
				( attribute "XY" "(-1150,1050)"
					( Origin gFrontEnd )
				)
				( attribute "CHIPS_PART_NAME" "RES"
					( Origin gPackager )
				)
				( attribute "CDS_PART_NAME" "RES_0402-4.75K,1%,1/16W,EMPTY,A"
					( Origin gPackager )
				)
				( objectStatus "R9F48" )
				( pin "a"
					( attribute "PN" "1"
						( Origin gPackager )
					)
					( objectStatus "R9F48.1" )
				)
				( pin "b"
					( attribute "PN" "2"
						( Origin gPackager )
					)
					( objectStatus "R9F48.2" )
				)
			)
			( gate "@baseboard_fab2_lib.baseboard_fab2(sch_1):page183_i14"
				( attribute "BOM_COST" "LBG_UART"
					( Origin gFrontEnd )
				)
				( attribute "CDS_LIB" "mstr_discrete"
					( Origin gPackager )
				)
				( attribute "CDS_LOCATION" "R9F49"
					( Origin gPackager )
				)
				( attribute "CDS_SEC" "1"
					( Origin gPackager )
				)
				( attribute "LOCATION" "R9F49"
					( Origin gFrontEnd )
				)
				( attribute "MATERIAL" "EMPTY"
					( Origin gFrontEnd )
				)
				( attribute "PACK_TYPE" "0402"
					( Origin gFrontEnd )
				)
				( attribute "PART_NUMBER" "G21796-072"
					( Origin gFrontEnd )
				)
				( attribute "PHYS_PAGE" "183"
					( Origin gFrontEnd )
				)
				( attribute "ROOM" "LBG"
					( Origin gFrontEnd )
				)
				( attribute "ROT" "0"
					( Origin gFrontEnd )
				)
				( attribute "SEC" "1"
					( Origin gFrontEnd )
				)
				( attribute "SEC_TYPE" "0402"
					( Origin gFrontEnd )
				)
				( attribute "TOLERANCE" "1%"
					( Origin gFrontEnd )
				)
				( attribute "VALUE" "4.75K"
					( Origin gFrontEnd )
				)
				( attribute "VER" "2"
					( Origin gFrontEnd )
				)
				( attribute "WATTAGE" "1/16W"
					( Origin gFrontEnd )
				)
				( attribute "XY" "(-1500,1050)"
					( Origin gFrontEnd )
				)
				( attribute "CHIPS_PART_NAME" "RES"
					( Origin gPackager )
				)
				( attribute "CDS_PART_NAME" "RES_0402-4.75K,1%,1/16W,EMPTY,A"
					( Origin gPackager )
				)
				( objectStatus "R9F49" )
				( pin "a"
					( attribute "PN" "1"
						( Origin gPackager )
					)
					( objectStatus "R9F49.1" )
				)
				( pin "b"
					( attribute "PN" "2"
						( Origin gPackager )
					)
					( objectStatus "R9F49.2" )
				)
			)
			( gate "@baseboard_fab2_lib.baseboard_fab2(sch_1):page183_i19"
				( attribute "BOM_COST" "LBG_UART"
					( Origin gFrontEnd )
				)
				( attribute "CDS_LIB" "mstr_discrete"
					( Origin gPackager )
				)
				( attribute "CDS_LOCATION" "Y9F1"
					( Origin gPackager )
				)
				( attribute "CDS_SEC" "1"
					( Origin gPackager )
				)
				( attribute "LOCATION" "Y9F1"
					( Origin gFrontEnd )
				)
				( attribute "MATERIAL" "IC"
					( Origin gFrontEnd )
				)
				( attribute "PACK_TYPE" "SM"
					( Origin gFrontEnd )
				)
				( attribute "PART_NUMBER" "D95126-001"
					( Origin gFrontEnd )
				)
				( attribute "PHYS_PAGE" "183"
					( Origin gFrontEnd )
				)
				( attribute "ROOM" "LBG"
					( Origin gFrontEnd )
				)
				( attribute "ROT" "0"
					( Origin gFrontEnd )
				)
				( attribute "SEC" "1"
					( Origin gFrontEnd )
				)
				( attribute "SEC_TYPE" "SM"
					( Origin gFrontEnd )
				)
				( attribute "VALUE" "24.000MHZ"
					( Origin gFrontEnd )
				)
				( attribute "VER" "1"
					( Origin gFrontEnd )
				)
				( attribute "XY" "(-225,50)"
					( Origin gFrontEnd )
				)
				( attribute "CHIPS_PART_NAME" "CRYSTAL"
					( Origin gPackager )
				)
				( attribute "CDS_PART_NAME" "CRYSTAL_SM-24.000MHZ,IC,D95126A"
					( Origin gPackager )
				)
				( objectStatus "Y9F1" )
				( pin "a"
					( attribute "PN" "1"
						( Origin gPackager )
					)
					( objectStatus "Y9F1.1" )
				)
				( pin "b"
					( attribute "PN" "2"
						( Origin gPackager )
					)
					( objectStatus "Y9F1.2" )
				)
			)
			( gate "@baseboard_fab2_lib.baseboard_fab2(sch_1):page183_i20"
				( attribute "BOM_COST" "LBG_UART"
					( Origin gFrontEnd )
				)
				( attribute "CDS_LIB" "mstr_discrete"
					( Origin gPackager )
				)
				( attribute "CDS_LOCATION" "C9F20"
					( Origin gPackager )
				)
				( attribute "CDS_SEC" "1"
					( Origin gPackager )
				)
				( attribute "LOCATION" "C9F20"
					( Origin gFrontEnd )
				)
				( attribute "MATERIAL" "COG"
					( Origin gFrontEnd )
				)
				( attribute "PACK_TYPE" "0402LF"
					( Origin gFrontEnd )
				)
				( attribute "PART_NUMBER" "A36095-043"
					( Origin gFrontEnd )
				)
				( attribute "PHYS_PAGE" "183"
					( Origin gFrontEnd )
				)
				( attribute "ROOM" "LBG"
					( Origin gFrontEnd )
				)
				( attribute "ROT" "0"
					( Origin gFrontEnd )
				)
				( attribute "SEC" "1"
					( Origin gPackager )
				)
				( attribute "TOLERANCE" "5%"
					( Origin gFrontEnd )
				)
				( attribute "VALUE" "12.0PF"
					( Origin gFrontEnd )
				)
				( attribute "VER" "1"
					( Origin gFrontEnd )
				)
				( attribute "VOLTAGE" "50V"
					( Units "uVoltage" "V" 1.000000)
					( Origin gFrontEnd )
				)
				( attribute "XY" "(-475,-200)"
					( Origin gFrontEnd )
				)
				( attribute "CHIPS_PART_NAME" "CAP"
					( Origin gPackager )
				)
				( attribute "CDS_PART_NAME" "CAP_0402LF-12.0PF,50V,5%,COG,AA"
					( Origin gPackager )
				)
				( objectStatus "C9F20" )
				( pin "a"
					( attribute "PN" "1"
						( Origin gPackager )
					)
					( objectStatus "C9F20.1" )
				)
				( pin "b"
					( attribute "PN" "2"
						( Origin gPackager )
					)
					( objectStatus "C9F20.2" )
				)
			)
			( gate "@baseboard_fab2_lib.baseboard_fab2(sch_1):page183_i21"
				( attribute "BOM_COST" "LBG_UART"
					( Origin gFrontEnd )
				)
				( attribute "CDS_LIB" "mstr_discrete"
					( Origin gPackager )
				)
				( attribute "CDS_LOCATION" "C9F21"
					( Origin gPackager )
				)
				( attribute "CDS_SEC" "1"
					( Origin gPackager )
				)
				( attribute "LOCATION" "C9F21"
					( Origin gFrontEnd )
				)
				( attribute "MATERIAL" "COG"
					( Origin gFrontEnd )
				)
				( attribute "PACK_TYPE" "0402LF"
					( Origin gFrontEnd )
				)
				( attribute "PART_NUMBER" "A36095-043"
					( Origin gFrontEnd )
				)
				( attribute "PHYS_PAGE" "183"
					( Origin gFrontEnd )
				)
				( attribute "ROOM" "LBG"
					( Origin gFrontEnd )
				)
				( attribute "ROT" "0"
					( Origin gFrontEnd )
				)
				( attribute "SEC" "1"
					( Origin gPackager )
				)
				( attribute "TOLERANCE" "5%"
					( Origin gFrontEnd )
				)
				( attribute "VALUE" "12.0PF"
					( Origin gFrontEnd )
				)
				( attribute "VER" "1"
					( Origin gFrontEnd )
				)
				( attribute "VOLTAGE" "50V"
					( Units "uVoltage" "V" 1.000000)
					( Origin gFrontEnd )
				)
				( attribute "XY" "(25,-200)"
					( Origin gFrontEnd )
				)
				( attribute "CHIPS_PART_NAME" "CAP"
					( Origin gPackager )
				)
				( attribute "CDS_PART_NAME" "CAP_0402LF-12.0PF,50V,5%,COG,AA"
					( Origin gPackager )
				)
				( objectStatus "C9F21" )
				( pin "a"
					( attribute "PN" "1"
						( Origin gPackager )
					)
					( objectStatus "C9F21.1" )
				)
				( pin "b"
					( attribute "PN" "2"
						( Origin gPackager )
					)
					( objectStatus "C9F21.2" )
				)
			)
			( gate "@baseboard_fab2_lib.baseboard_fab2(sch_1):page183_i24"
				( attribute "BOM_COST" "LBG_UART"
					( Origin gFrontEnd )
				)
				( attribute "CDS_LIB" "mstr_discrete"
					( Origin gPackager )
				)
				( attribute "CDS_LOCATION" "R9F58"
					( Origin gPackager )
				)
				( attribute "CDS_SEC" "1"
					( Origin gPackager )
				)
				( attribute "LOCATION" "R9F58"
					( Origin gFrontEnd )
				)
				( attribute "MATERIAL" "CHIP"
					( Origin gFrontEnd )
				)
				( attribute "PACK_TYPE" "0402"
					( Origin gFrontEnd )
				)
				( attribute "PART_NUMBER" "G21497-005"
					( Origin gFrontEnd )
				)
				( attribute "PHYS_PAGE" "183"
					( Origin gFrontEnd )
				)
				( attribute "ROOM" "LBG"
					( Origin gFrontEnd )
				)
				( attribute "ROT" "0"
					( Origin gFrontEnd )
				)
				( attribute "SEC" "1"
					( Origin gFrontEnd )
				)
				( attribute "SEC_TYPE" "0402"
					( Origin gFrontEnd )
				)
				( attribute "TOLERANCE" "5%"
					( Origin gFrontEnd )
				)
				( attribute "VALUE" "0.0"
					( Origin gFrontEnd )
				)
				( attribute "VER" "1"
					( Origin gFrontEnd )
				)
				( attribute "WATTAGE" "1/16W"
					( Origin gFrontEnd )
				)
				( attribute "XY" "(125,575)"
					( Origin gFrontEnd )
				)
				( attribute "CHIPS_PART_NAME" "RES"
					( Origin gPackager )
				)
				( attribute "CDS_PART_NAME" "RES_0402-0.0,5%,1/16W,CHIP,G21A"
					( Origin gPackager )
				)
				( objectStatus "R9F58" )
				( pin "a"
					( attribute "PN" "1"
						( Origin gPackager )
					)
					( objectStatus "R9F58.1" )
				)
				( pin "b"
					( attribute "PN" "2"
						( Origin gPackager )
					)
					( objectStatus "R9F58.2" )
				)
			)
			( gate "@baseboard_fab2_lib.baseboard_fab2(sch_1):page183_i25"
				( attribute "BOM_COST" "LBG_UART"
					( Origin gFrontEnd )
				)
				( attribute "CDS_LIB" "mstr_discrete"
					( Origin gPackager )
				)
				( attribute "CDS_LOCATION" "R9F59"
					( Origin gPackager )
				)
				( attribute "CDS_SEC" "1"
					( Origin gPackager )
				)
				( attribute "LOCATION" "R9F59"
					( Origin gFrontEnd )
				)
				( attribute "MATERIAL" "CHIP"
					( Origin gFrontEnd )
				)
				( attribute "PACK_TYPE" "0402"
					( Origin gFrontEnd )
				)
				( attribute "PART_NUMBER" "G21497-005"
					( Origin gFrontEnd )
				)
				( attribute "PHYS_PAGE" "183"
					( Origin gFrontEnd )
				)
				( attribute "ROOM" "LBG"
					( Origin gFrontEnd )
				)
				( attribute "ROT" "0"
					( Origin gFrontEnd )
				)
				( attribute "SEC" "1"
					( Origin gFrontEnd )
				)
				( attribute "SEC_TYPE" "0402"
					( Origin gFrontEnd )
				)
				( attribute "TOLERANCE" "5%"
					( Origin gFrontEnd )
				)
				( attribute "VALUE" "0.0"
					( Origin gFrontEnd )
				)
				( attribute "VER" "1"
					( Origin gFrontEnd )
				)
				( attribute "WATTAGE" "1/16W"
					( Origin gFrontEnd )
				)
				( attribute "XY" "(275,325)"
					( Origin gFrontEnd )
				)
				( attribute "CHIPS_PART_NAME" "RES"
					( Origin gPackager )
				)
				( attribute "CDS_PART_NAME" "RES_0402-0.0,5%,1/16W,CHIP,G21A"
					( Origin gPackager )
				)
				( objectStatus "R9F59" )
				( pin "a"
					( attribute "PN" "1"
						( Origin gPackager )
					)
					( objectStatus "R9F59.1" )
				)
				( pin "b"
					( attribute "PN" "2"
						( Origin gPackager )
					)
					( objectStatus "R9F59.2" )
				)
			)
			( gate "@baseboard_fab2_lib.baseboard_fab2(sch_1):page183_i30"
				( attribute "BOM_COST" "LBG_UART"
					( Origin gFrontEnd )
				)
				( attribute "CDS_LIB" "mstr_discrete"
					( Origin gPackager )
				)
				( attribute "CDS_LOCATION" "R9F55"
					( Origin gPackager )
				)
				( attribute "CDS_SEC" "1"
					( Origin gPackager )
				)
				( attribute "LOCATION" "R9F55"
					( Origin gFrontEnd )
				)
				( attribute "MATERIAL" "CHIP"
					( Origin gFrontEnd )
				)
				( attribute "PACK_TYPE" "0402"
					( Origin gFrontEnd )
				)
				( attribute "PART_NUMBER" "G21796-072"
					( Origin gFrontEnd )
				)
				( attribute "PHYS_PAGE" "183"
					( Origin gFrontEnd )
				)
				( attribute "ROOM" "LBG"
					( Origin gFrontEnd )
				)
				( attribute "ROT" "0"
					( Origin gFrontEnd )
				)
				( attribute "SEC" "1"
					( Origin gFrontEnd )
				)
				( attribute "SEC_TYPE" "0402"
					( Origin gFrontEnd )
				)
				( attribute "TOLERANCE" "1%"
					( Origin gFrontEnd )
				)
				( attribute "VALUE" "4.75K"
					( Origin gFrontEnd )
				)
				( attribute "VER" "2"
					( Origin gFrontEnd )
				)
				( attribute "WATTAGE" "1/16W"
					( Origin gFrontEnd )
				)
				( attribute "XY" "(3700,700)"
					( Origin gFrontEnd )
				)
				( attribute "CHIPS_PART_NAME" "RES"
					( Origin gPackager )
				)
				( attribute "CDS_PART_NAME" "RES_0402-4.75K,1%,1/16W,CHIP,GA"
					( Origin gPackager )
				)
				( objectStatus "R9F55" )
				( pin "a"
					( attribute "PN" "1"
						( Origin gPackager )
					)
					( objectStatus "R9F55.1" )
				)
				( pin "b"
					( attribute "PN" "2"
						( Origin gPackager )
					)
					( objectStatus "R9F55.2" )
				)
			)
			( gate "@baseboard_fab2_lib.baseboard_fab2(sch_1):page183_i48"
				( attribute "BOM_COST" "LBG_UART"
					( Origin gFrontEnd )
				)
				( attribute "CDS_LIB" "mstr_discrete"
					( Origin gPackager )
				)
				( attribute "CDS_LOCATION" "R9F57"
					( Origin gPackager )
				)
				( attribute "CDS_SEC" "1"
					( Origin gPackager )
				)
				( attribute "LOCATION" "R9F57"
					( Origin gFrontEnd )
				)
				( attribute "MATERIAL" "CHIP"
					( Origin gFrontEnd )
				)
				( attribute "PACK_TYPE" "0402"
					( Origin gFrontEnd )
				)
				( attribute "PART_NUMBER" "G21497-005"
					( Origin gFrontEnd )
				)
				( attribute "PHYS_PAGE" "183"
					( Origin gFrontEnd )
				)
				( attribute "ROOM" "LBG"
					( Origin gFrontEnd )
				)
				( attribute "ROT" "0"
					( Origin gFrontEnd )
				)
				( attribute "SEC" "1"
					( Origin gFrontEnd )
				)
				( attribute "SEC_TYPE" "0402"
					( Origin gFrontEnd )
				)
				( attribute "TOLERANCE" "5%"
					( Origin gFrontEnd )
				)
				( attribute "VALUE" "0.0"
					( Origin gFrontEnd )
				)
				( attribute "VER" "1"
					( Origin gFrontEnd )
				)
				( attribute "WATTAGE" "1/16W"
					( Origin gFrontEnd )
				)
				( attribute "XY" "(3950,1225)"
					( Origin gFrontEnd )
				)
				( attribute "CHIPS_PART_NAME" "RES"
					( Origin gPackager )
				)
				( attribute "CDS_PART_NAME" "RES_0402-0.0,5%,1/16W,CHIP,G21A"
					( Origin gPackager )
				)
				( objectStatus "R9F57" )
				( pin "a"
					( attribute "PN" "1"
						( Origin gPackager )
					)
					( objectStatus "R9F57.1" )
				)
				( pin "b"
					( attribute "PN" "2"
						( Origin gPackager )
					)
					( objectStatus "R9F57.2" )
				)
			)
			( gate "@baseboard_fab2_lib.baseboard_fab2(sch_1):page183_i49"
				( attribute "BOM_COST" "LBG_UART"
					( Origin gFrontEnd )
				)
				( attribute "CDS_LIB" "mstr_discrete"
					( Origin gPackager )
				)
				( attribute "CDS_LOCATION" "R9F56"
					( Origin gPackager )
				)
				( attribute "CDS_SEC" "1"
					( Origin gPackager )
				)
				( attribute "LOCATION" "R9F56"
					( Origin gFrontEnd )
				)
				( attribute "MATERIAL" "CHIP"
					( Origin gFrontEnd )
				)
				( attribute "PACK_TYPE" "0402"
					( Origin gFrontEnd )
				)
				( attribute "PART_NUMBER" "G21497-005"
					( Origin gFrontEnd )
				)
				( attribute "PHYS_PAGE" "183"
					( Origin gFrontEnd )
				)
				( attribute "ROOM" "LBG"
					( Origin gFrontEnd )
				)
				( attribute "ROT" "0"
					( Origin gFrontEnd )
				)
				( attribute "SEC" "1"
					( Origin gFrontEnd )
				)
				( attribute "SEC_TYPE" "0402"
					( Origin gFrontEnd )
				)
				( attribute "TOLERANCE" "5%"
					( Origin gFrontEnd )
				)
				( attribute "VALUE" "0.0"
					( Origin gFrontEnd )
				)
				( attribute "VER" "1"
					( Origin gFrontEnd )
				)
				( attribute "WATTAGE" "1/16W"
					( Origin gFrontEnd )
				)
				( attribute "XY" "(3475,1275)"
					( Origin gFrontEnd )
				)
				( attribute "CHIPS_PART_NAME" "RES"
					( Origin gPackager )
				)
				( attribute "CDS_PART_NAME" "RES_0402-0.0,5%,1/16W,CHIP,G21A"
					( Origin gPackager )
				)
				( objectStatus "R9F56" )
				( pin "a"
					( attribute "PN" "1"
						( Origin gPackager )
					)
					( objectStatus "R9F56.1" )
				)
				( pin "b"
					( attribute "PN" "2"
						( Origin gPackager )
					)
					( objectStatus "R9F56.2" )
				)
			)
			( gate "@baseboard_fab2_lib.baseboard_fab2(sch_1):page183_i52"
				( attribute "BOM_COST" "LBG_UART"
					( Origin gFrontEnd )
				)
				( attribute "CDS_LIB" "mstr_discrete"
					( Origin gPackager )
				)
				( attribute "CDS_LOCATION" "R9F54"
					( Origin gPackager )
				)
				( attribute "CDS_SEC" "1"
					( Origin gPackager )
				)
				( attribute "LOCATION" "R9F54"
					( Origin gFrontEnd )
				)
				( attribute "MATERIAL" "CHIP"
					( Origin gFrontEnd )
				)
				( attribute "PACK_TYPE" "0402"
					( Origin gFrontEnd )
				)
				( attribute "PART_NUMBER" "G21497-005"
					( Origin gFrontEnd )
				)
				( attribute "PHYS_PAGE" "183"
					( Origin gFrontEnd )
				)
				( attribute "ROOM" "LBG"
					( Origin gFrontEnd )
				)
				( attribute "ROT" "0"
					( Origin gFrontEnd )
				)
				( attribute "SEC" "1"
					( Origin gFrontEnd )
				)
				( attribute "SEC_TYPE" "0402"
					( Origin gFrontEnd )
				)
				( attribute "TOLERANCE" "5%"
					( Origin gFrontEnd )
				)
				( attribute "VALUE" "0.0"
					( Origin gFrontEnd )
				)
				( attribute "VER" "1"
					( Origin gFrontEnd )
				)
				( attribute "WATTAGE" "1/16W"
					( Origin gFrontEnd )
				)
				( attribute "XY" "(-750,1500)"
					( Origin gFrontEnd )
				)
				( attribute "CHIPS_PART_NAME" "RES"
					( Origin gPackager )
				)
				( attribute "CDS_PART_NAME" "RES_0402-0.0,5%,1/16W,CHIP,G21A"
					( Origin gPackager )
				)
				( objectStatus "R9F54" )
				( pin "a"
					( attribute "PN" "1"
						( Origin gPackager )
					)
					( objectStatus "R9F54.1" )
				)
				( pin "b"
					( attribute "PN" "2"
						( Origin gPackager )
					)
					( objectStatus "R9F54.2" )
				)
			)
			( gate "@baseboard_fab2_lib.baseboard_fab2(sch_1):page183_i53"
				( attribute "BOM_COST" "LBG_UART"
					( Origin gFrontEnd )
				)
				( attribute "CDS_LIB" "mstr_discrete"
					( Origin gPackager )
				)
				( attribute "CDS_LOCATION" "R9F53"
					( Origin gPackager )
				)
				( attribute "CDS_SEC" "1"
					( Origin gPackager )
				)
				( attribute "LOCATION" "R9F53"
					( Origin gFrontEnd )
				)
				( attribute "MATERIAL" "CHIP"
					( Origin gFrontEnd )
				)
				( attribute "PACK_TYPE" "0402"
					( Origin gFrontEnd )
				)
				( attribute "PART_NUMBER" "G21497-005"
					( Origin gFrontEnd )
				)
				( attribute "PHYS_PAGE" "183"
					( Origin gFrontEnd )
				)
				( attribute "ROOM" "LBG"
					( Origin gFrontEnd )
				)
				( attribute "ROT" "0"
					( Origin gFrontEnd )
				)
				( attribute "SEC" "1"
					( Origin gFrontEnd )
				)
				( attribute "SEC_TYPE" "0402"
					( Origin gFrontEnd )
				)
				( attribute "TOLERANCE" "5%"
					( Origin gFrontEnd )
				)
				( attribute "VALUE" "0.0"
					( Origin gFrontEnd )
				)
				( attribute "VER" "1"
					( Origin gFrontEnd )
				)
				( attribute "WATTAGE" "1/16W"
					( Origin gFrontEnd )
				)
				( attribute "XY" "(-275,1450)"
					( Origin gFrontEnd )
				)
				( attribute "CHIPS_PART_NAME" "RES"
					( Origin gPackager )
				)
				( attribute "CDS_PART_NAME" "RES_0402-0.0,5%,1/16W,CHIP,G21A"
					( Origin gPackager )
				)
				( objectStatus "R9F53" )
				( pin "a"
					( attribute "PN" "1"
						( Origin gPackager )
					)
					( objectStatus "R9F53.1" )
				)
				( pin "b"
					( attribute "PN" "2"
						( Origin gPackager )
					)
					( objectStatus "R9F53.2" )
				)
			)
			( gate "@baseboard_fab2_lib.baseboard_fab2(sch_1):page184_i87"
				( attribute "BOM_COST" "MIO_SECURITY"
					( Origin gFrontEnd )
				)
				( attribute "CDS_LIB" "mstr_sconn"
					( Origin gPackager )
				)
				( attribute "CDS_LMAN_SYM_OUTLINE" "-300,450,300,-450"
					( Origin gPackager )
				)
				( attribute "CDS_LOCATION" "J8E1"
					( Origin gPackager )
				)
				( attribute "CDS_SEC" "1"
					( Origin gPackager )
				)
				( attribute "LOCATION" "J8E1"
					( Origin gFrontEnd )
				)
				( attribute "MATERIAL" "CONN"
					( Origin gFrontEnd )
				)
				( attribute "PACK_TYPE" "SM"
					( Origin gFrontEnd )
				)
				( attribute "PART_NUMBER" "H67026-001"
					( Origin gFrontEnd )
				)
				( attribute "PHYS_PAGE" "184"
					( Origin gFrontEnd )
				)
				( attribute "ROOM" "TPM"
					( Origin gFrontEnd )
				)
				( attribute "ROT" "0"
					( Origin gFrontEnd )
				)
				( attribute "SEC" "1"
					( Origin gFrontEnd )
				)
				( attribute "SEC_TYPE" "SM"
					( Origin gFrontEnd )
				)
				( attribute "VER" "1"
					( Origin gFrontEnd )
				)
				( attribute "XY" "(-3700,-3375)"
					( Origin gFrontEnd )
				)
				( attribute "CHIPS_PART_NAME" "SCONN11_H67026001"
					( Origin gPackager )
				)
				( attribute "CDS_PART_NAME" "SCONN11_H67026001_SM-CONN,H670A"
					( Origin gPackager )
				)
				( objectStatus "J8E1" )
				( pin "io1"
					( attribute "PN" "1"
						( Origin gPackager )
					)
					( objectStatus "J8E1.1" )
				)
				( pin "io2"
					( attribute "PN" "2"
						( Origin gPackager )
					)
					( objectStatus "J8E1.2" )
				)
				( pin "io3"
					( attribute "PN" "3"
						( Origin gPackager )
					)
					( objectStatus "J8E1.3" )
				)
				( pin "io4"
					( attribute "PN" "4"
						( Origin gPackager )
					)
					( objectStatus "J8E1.4" )
				)
				( pin "io5"
					( attribute "PN" "5"
						( Origin gPackager )
					)
					( objectStatus "J8E1.5" )
				)
				( pin "io6"
					( attribute "PN" "6"
						( Origin gPackager )
					)
					( objectStatus "J8E1.6" )
				)
				( pin "io7"
					( attribute "PN" "7"
						( Origin gPackager )
					)
					( objectStatus "J8E1.7" )
				)
				( pin "io8"
					( attribute "PN" "8"
						( Origin gPackager )
					)
					( objectStatus "J8E1.8" )
				)
				( pin "io9"
					( attribute "PN" "9"
						( Origin gPackager )
					)
					( objectStatus "J8E1.9" )
				)
				( pin "io10"
					( attribute "PN" "10"
						( Origin gPackager )
					)
					( objectStatus "J8E1.10" )
				)
				( pin "io11"
					( attribute "PN" "11"
						( Origin gPackager )
					)
					( objectStatus "J8E1.11" )
				)
				( pin "mp1"
					( attribute "PN" "MP1"
						( Origin gPackager )
					)
					( objectStatus "J8E1.MP1" )
				)
				( pin "mp2"
					( attribute "PN" "MP2"
						( Origin gPackager )
					)
					( objectStatus "J8E1.MP2" )
				)
			)
			( gate "@baseboard_fab2_lib.baseboard_fab2(sch_1):page184_i88"
				( attribute "BOM_COST" "MIO_SECURITY"
					( Origin gFrontEnd )
				)
				( attribute "CDS_LIB" "mstr_discrete"
					( Origin gPackager )
				)
				( attribute "CDS_LOCATION" "R8E9"
					( Origin gPackager )
				)
				( attribute "CDS_SEC" "1"
					( Origin gPackager )
				)
				( attribute "LOCATION" "R8E9"
					( Origin gFrontEnd )
				)
				( attribute "MATERIAL" "CHIP"
					( Origin gFrontEnd )
				)
				( attribute "PACK_TYPE" "0402"
					( Origin gFrontEnd )
				)
				( attribute "PART_NUMBER" "G21796-074"
					( Origin gFrontEnd )
				)
				( attribute "PHYS_PAGE" "184"
					( Origin gFrontEnd )
				)
				( attribute "ROOM" "TPM"
					( Origin gFrontEnd )
				)
				( attribute "ROT" "0"
					( Origin gFrontEnd )
				)
				( attribute "SEC" "1"
					( Origin gFrontEnd )
				)
				( attribute "SEC_TYPE" "0402"
					( Origin gFrontEnd )
				)
				( attribute "TOLERANCE" "1%"
					( Origin gFrontEnd )
				)
				( attribute "VALUE" "33.2"
					( Origin gFrontEnd )
				)
				( attribute "VER" "1"
					( Origin gFrontEnd )
				)
				( attribute "WATTAGE" "1/16W"
					( Origin gFrontEnd )
				)
				( attribute "XY" "(-4750,-3175)"
					( Origin gFrontEnd )
				)
				( attribute "CHIPS_PART_NAME" "RES"
					( Origin gPackager )
				)
				( attribute "CDS_PART_NAME" "RES_0402-33.2,1%,1/16W,CHIP,G2A"
					( Origin gPackager )
				)
				( objectStatus "R8E9" )
				( pin "a"
					( attribute "PN" "1"
						( Origin gPackager )
					)
					( objectStatus "R8E9.1" )
				)
				( pin "b"
					( attribute "PN" "2"
						( Origin gPackager )
					)
					( objectStatus "R8E9.2" )
				)
			)
			( gate "@baseboard_fab2_lib.baseboard_fab2(sch_1):page184_i92"
				( attribute "BOM_COST" "MIO_SECURITY"
					( Origin gFrontEnd )
				)
				( attribute "CDS_LIB" "mstr_discrete"
					( Origin gPackager )
				)
				( attribute "CDS_LOCATION" "R8D35"
					( Origin gPackager )
				)
				( attribute "CDS_SEC" "1"
					( Origin gPackager )
				)
				( attribute "LOCATION" "R8D35"
					( Origin gFrontEnd )
				)
				( attribute "MATERIAL" "CHIP"
					( Origin gFrontEnd )
				)
				( attribute "PACK_TYPE" "0402"
					( Origin gFrontEnd )
				)
				( attribute "PART_NUMBER" "G21497-005"
					( Origin gFrontEnd )
				)
				( attribute "PHYS_PAGE" "184"
					( Origin gFrontEnd )
				)
				( attribute "ROOM" "TPM"
					( Origin gFrontEnd )
				)
				( attribute "ROT" "0"
					( Origin gFrontEnd )
				)
				( attribute "SEC" "1"
					( Origin gFrontEnd )
				)
				( attribute "SEC_TYPE" "0402"
					( Origin gFrontEnd )
				)
				( attribute "TOLERANCE" "5%"
					( Origin gFrontEnd )
				)
				( attribute "VALUE" "0.0"
					( Origin gFrontEnd )
				)
				( attribute "VER" "1"
					( Origin gFrontEnd )
				)
				( attribute "WATTAGE" "1/16W"
					( Origin gFrontEnd )
				)
				( attribute "XY" "(-4750,-3575)"
					( Origin gFrontEnd )
				)
				( attribute "CHIPS_PART_NAME" "RES"
					( Origin gPackager )
				)
				( attribute "CDS_PART_NAME" "RES_0402-0.0,5%,1/16W,CHIP,G21A"
					( Origin gPackager )
				)
				( objectStatus "R8D35" )
				( pin "a"
					( attribute "PN" "1"
						( Origin gPackager )
					)
					( objectStatus "R8D35.1" )
				)
				( pin "b"
					( attribute "PN" "2"
						( Origin gPackager )
					)
					( objectStatus "R8D35.2" )
				)
			)
			( gate "@baseboard_fab2_lib.baseboard_fab2(sch_1):page184_i93"
				( attribute "BOM_COST" "MIO_SECURITY"
					( Origin gFrontEnd )
				)
				( attribute "CDS_LIB" "mstr_discrete"
					( Origin gPackager )
				)
				( attribute "CDS_LOCATION" "R8E13"
					( Origin gPackager )
				)
				( attribute "CDS_SEC" "1"
					( Origin gPackager )
				)
				( attribute "LOCATION" "R8E13"
					( Origin gFrontEnd )
				)
				( attribute "MATERIAL" "CHIP"
					( Origin gFrontEnd )
				)
				( attribute "PACK_TYPE" "0402"
					( Origin gFrontEnd )
				)
				( attribute "PART_NUMBER" "G21796-074"
					( Origin gFrontEnd )
				)
				( attribute "PHYS_PAGE" "184"
					( Origin gFrontEnd )
				)
				( attribute "ROOM" "TPM"
					( Origin gFrontEnd )
				)
				( attribute "ROT" "0"
					( Origin gFrontEnd )
				)
				( attribute "SEC" "1"
					( Origin gFrontEnd )
				)
				( attribute "SEC_TYPE" "0402"
					( Origin gFrontEnd )
				)
				( attribute "TOLERANCE" "1%"
					( Origin gFrontEnd )
				)
				( attribute "VALUE" "33.2"
					( Origin gFrontEnd )
				)
				( attribute "VER" "1"
					( Origin gFrontEnd )
				)
				( attribute "WATTAGE" "1/16W"
					( Origin gFrontEnd )
				)
				( attribute "XY" "(-4725,-3475)"
					( Origin gFrontEnd )
				)
				( attribute "CHIPS_PART_NAME" "RES"
					( Origin gPackager )
				)
				( attribute "CDS_PART_NAME" "RES_0402-33.2,1%,1/16W,CHIP,G2A"
					( Origin gPackager )
				)
				( objectStatus "R8E13" )
				( pin "a"
					( attribute "PN" "1"
						( Origin gPackager )
					)
					( objectStatus "R8E13.1" )
				)
				( pin "b"
					( attribute "PN" "2"
						( Origin gPackager )
					)
					( objectStatus "R8E13.2" )
				)
			)
			( gate "@baseboard_fab2_lib.baseboard_fab2(sch_1):page184_i95"
				( attribute "BOM_COST" "MIO_SECURITY"
					( Origin gFrontEnd )
				)
				( attribute "CDS_LIB" "mstr_discrete"
					( Origin gPackager )
				)
				( attribute "CDS_LOCATION" "R8E10"
					( Origin gPackager )
				)
				( attribute "CDS_SEC" "1"
					( Origin gPackager )
				)
				( attribute "LOCATION" "R8E10"
					( Origin gFrontEnd )
				)
				( attribute "MATERIAL" "CHIP"
					( Origin gFrontEnd )
				)
				( attribute "PACK_TYPE" "0402"
					( Origin gFrontEnd )
				)
				( attribute "PART_NUMBER" "G21796-074"
					( Origin gFrontEnd )
				)
				( attribute "PHYS_PAGE" "184"
					( Origin gFrontEnd )
				)
				( attribute "ROOM" "TPM"
					( Origin gFrontEnd )
				)
				( attribute "ROT" "0"
					( Origin gFrontEnd )
				)
				( attribute "SEC" "1"
					( Origin gFrontEnd )
				)
				( attribute "SEC_TYPE" "0402"
					( Origin gFrontEnd )
				)
				( attribute "TOLERANCE" "1%"
					( Origin gFrontEnd )
				)
				( attribute "VALUE" "33.2"
					( Origin gFrontEnd )
				)
				( attribute "VER" "1"
					( Origin gFrontEnd )
				)
				( attribute "WATTAGE" "1/16W"
					( Origin gFrontEnd )
				)
				( attribute "XY" "(-4725,-3375)"
					( Origin gFrontEnd )
				)
				( attribute "CHIPS_PART_NAME" "RES"
					( Origin gPackager )
				)
				( attribute "CDS_PART_NAME" "RES_0402-33.2,1%,1/16W,CHIP,G2A"
					( Origin gPackager )
				)
				( objectStatus "R8E10" )
				( pin "a"
					( attribute "PN" "1"
						( Origin gPackager )
					)
					( objectStatus "R8E10.1" )
				)
				( pin "b"
					( attribute "PN" "2"
						( Origin gPackager )
					)
					( objectStatus "R8E10.2" )
				)
			)
			( gate "@baseboard_fab2_lib.baseboard_fab2(sch_1):page184_i99"
				( attribute "BOM_COST" "MIO_SECURITY"
					( Origin gFrontEnd )
				)
				( attribute "CDS_LIB" "mstr_discrete"
					( Origin gPackager )
				)
				( attribute "CDS_LOCATION" "R8E1"
					( Origin gPackager )
				)
				( attribute "CDS_SEC" "1"
					( Origin gPackager )
				)
				( attribute "LOCATION" "R8E1"
					( Origin gFrontEnd )
				)
				( attribute "MATERIAL" "CHIP"
					( Origin gFrontEnd )
				)
				( attribute "PACK_TYPE" "0402"
					( Origin gFrontEnd )
				)
				( attribute "PART_NUMBER" "G21497-005"
					( Origin gFrontEnd )
				)
				( attribute "PHYS_PAGE" "184"
					( Origin gFrontEnd )
				)
				( attribute "ROOM" "TPM"
					( Origin gFrontEnd )
				)
				( attribute "ROT" "0"
					( Origin gFrontEnd )
				)
				( attribute "SEC" "1"
					( Origin gPackager )
				)
				( attribute "TOLERANCE" "5%"
					( Origin gFrontEnd )
				)
				( attribute "VALUE" "0.0"
					( Origin gFrontEnd )
				)
				( attribute "VER" "1"
					( Origin gFrontEnd )
				)
				( attribute "WATTAGE" "1/16W"
					( Origin gFrontEnd )
				)
				( attribute "XY" "(-2575,-3425)"
					( Origin gFrontEnd )
				)
				( attribute "CHIPS_PART_NAME" "RES"
					( Origin gPackager )
				)
				( attribute "CDS_PART_NAME" "RES_0402-0.0,5%,1/16W,CHIP,G21A"
					( Origin gPackager )
				)
				( objectStatus "R8E1" )
				( pin "a"
					( attribute "PN" "1"
						( Origin gPackager )
					)
					( objectStatus "R8E1.1" )
				)
				( pin "b"
					( attribute "PN" "2"
						( Origin gPackager )
					)
					( objectStatus "R8E1.2" )
				)
			)
			( gate "@baseboard_fab2_lib.baseboard_fab2(sch_1):page184_i104"
				( attribute "CDS_LIB" "mstr_misc"
					( Origin gPackager )
				)
				( attribute "CDS_LOCATION" "RM8D1"
					( Origin gPackager )
				)
				( attribute "CDS_SEC" "1"
					( Origin gPackager )
				)
				( attribute "LOCATION" "RM8D1"
					( Origin gFrontEnd )
				)
				( attribute "MATERIAL" "SO"
					( Origin gFrontEnd )
				)
				( attribute "PACK_TYPE" "TH1"
					( Origin gFrontEnd )
				)
				( attribute "PART_NUMBER" "H72821-001"
					( Origin gFrontEnd )
				)
				( attribute "PHYS_PAGE" "184"
					( Origin gFrontEnd )
				)
				( attribute "ROT" "0"
					( Origin gFrontEnd )
				)
				( attribute "SEC" "1"
					( Origin gFrontEnd )
				)
				( attribute "SEC_TYPE" "TH1"
					( Origin gFrontEnd )
				)
				( attribute "VER" "2"
					( Origin gFrontEnd )
				)
				( attribute "XY" "(-5125,-1900)"
					( Origin gFrontEnd )
				)
				( attribute "CHIPS_PART_NAME" "STANDOFF"
					( Origin gPackager )
				)
				( attribute "CDS_PART_NAME" "STANDOFF_TH1-SO,H72821-001"
					( Origin gPackager )
				)
				( objectStatus "RM8D1" )
				( pin "io1"
					( attribute "PN" "1"
						( Origin gPackager )
					)
					( objectStatus "RM8D1.1" )
				)
			)
			( gate "@baseboard_fab2_lib.baseboard_fab2(sch_1):page185_i53"
				( attribute "BOM_COST" "ST_FLASH"
					( Origin gFrontEnd )
				)
				( attribute "CDS_LIB" "mstr_sconn"
					( Origin gPackager )
				)
				( attribute "CDS_LMAN_SYM_OUTLINE" "-700,1250,700,-1250"
					( Origin gPackager )
				)
				( attribute "CDS_LOCATION" "J8F1"
					( Origin gPackager )
				)
				( attribute "CDS_SEC" "1"
					( Origin gPackager )
				)
				( attribute "LOCATION" "J8F1"
					( Origin gFrontEnd )
				)
				( attribute "MATERIAL" "SCONN"
					( Origin gFrontEnd )
				)
				( attribute "PACK_TYPE" "SMT1"
					( Origin gFrontEnd )
				)
				( attribute "PART_NUMBER" "H17033-002"
					( Origin gFrontEnd )
				)
				( attribute "PHYS_PAGE" "185"
					( Origin gFrontEnd )
				)
				( attribute "ROOM" "M_2"
					( Origin gFrontEnd )
				)
				( attribute "ROT" "0"
					( Origin gFrontEnd )
				)
				( attribute "SEC" "1"
					( Origin gFrontEnd )
				)
				( attribute "SEC_TYPE" "SMT1"
					( Origin gFrontEnd )
				)
				( attribute "VER" "2"
					( Origin gFrontEnd )
				)
				( attribute "XY" "(-5850,3275)"
					( Origin gFrontEnd )
				)
				( attribute "CHIPS_PART_NAME" "SCONN75K_H17033002"
					( Origin gPackager )
				)
				( attribute "CDS_PART_NAME" "SCONN75K_H17033002_SMT1-SCONN,A"
					( Origin gPackager )
				)
				( objectStatus "J8F1" )
				( pin "\3_3v\(0)"
					( attribute "PN" "2"
						( Origin gPackager )
					)
					( objectStatus "J8F1.2" )
				)
				( pin "\3_3v\(1)"
					( attribute "PN" "4"
						( Origin gPackager )
					)
					( objectStatus "J8F1.4" )
				)
				( pin "\3_3v\(2)"
					( attribute "PN" "12"
						( Origin gPackager )
					)
					( objectStatus "J8F1.12" )
				)
				( pin "\3_3v\(3)"
					( attribute "PN" "14"
						( Origin gPackager )
					)
					( objectStatus "J8F1.14" )
				)
				( pin "\3_3v\(4)"
					( attribute "PN" "16"
						( Origin gPackager )
					)
					( objectStatus "J8F1.16" )
				)
				( pin "\3_3v\(5)"
					( attribute "PN" "18"
						( Origin gPackager )
					)
					( objectStatus "J8F1.18" )
				)
				( pin "\3_3v\(6)"
					( attribute "PN" "70"
						( Origin gPackager )
					)
					( objectStatus "J8F1.70" )
				)
				( pin "\3_3v\(7)"
					( attribute "PN" "72"
						( Origin gPackager )
					)
					( objectStatus "J8F1.72" )
				)
				( pin "\3_3v\(8)"
					( attribute "PN" "74"
						( Origin gPackager )
					)
					( objectStatus "J8F1.74" )
				)
				( pin "clkreq_n_nc"
					( attribute "PN" "52"
						( Origin gPackager )
					)
					( objectStatus "J8F1.52" )
				)
				( pin "das_dss_n"
					( attribute "PN" "10"
						( Origin gPackager )
					)
					( objectStatus "J8F1.10" )
				)
				( pin "devslp"
					( attribute "PN" "38"
						( Origin gPackager )
					)
					( objectStatus "J8F1.38" )
				)
				( pin "gnd(0)"
					( attribute "PN" "1"
						( Origin gPackager )
					)
					( objectStatus "J8F1.1" )
				)
				( pin "gnd(1)"
					( attribute "PN" "3"
						( Origin gPackager )
					)
					( objectStatus "J8F1.3" )
				)
				( pin "gnd(2)"
					( attribute "PN" "9"
						( Origin gPackager )
					)
					( objectStatus "J8F1.9" )
				)
				( pin "gnd(3)"
					( attribute "PN" "15"
						( Origin gPackager )
					)
					( objectStatus "J8F1.15" )
				)
				( pin "gnd(4)"
					( attribute "PN" "21"
						( Origin gPackager )
					)
					( objectStatus "J8F1.21" )
				)
				( pin "gnd(5)"
					( attribute "PN" "27"
						( Origin gPackager )
					)
					( objectStatus "J8F1.27" )
				)
				( pin "gnd(6)"
					( attribute "PN" "33"
						( Origin gPackager )
					)
					( objectStatus "J8F1.33" )
				)
				( pin "gnd(7)"
					( attribute "PN" "39"
						( Origin gPackager )
					)
					( objectStatus "J8F1.39" )
				)
				( pin "gnd(8)"
					( attribute "PN" "45"
						( Origin gPackager )
					)
					( objectStatus "J8F1.45" )
				)
				( pin "gnd(9)"
					( attribute "PN" "51"
						( Origin gPackager )
					)
					( objectStatus "J8F1.51" )
				)
				( pin "gnd(10)"
					( attribute "PN" "57"
						( Origin gPackager )
					)
					( objectStatus "J8F1.57" )
				)
				( pin "gnd(11)"
					( attribute "PN" "71"
						( Origin gPackager )
					)
					( objectStatus "J8F1.71" )
				)
				( pin "gnd(12)"
					( attribute "PN" "73"
						( Origin gPackager )
					)
					( objectStatus "J8F1.73" )
				)
				( pin "gnd(13)"
					( attribute "PN" "75"
						( Origin gPackager )
					)
					( objectStatus "J8F1.75" )
				)
				( pin "mp1"
					( attribute "PN" "MP1"
						( Origin gPackager )
					)
					( objectStatus "J8F1.MP1" )
				)
				( pin "mp2"
					( attribute "PN" "MP2"
						( Origin gPackager )
					)
					( objectStatus "J8F1.MP2" )
				)
				( pin "nc(0)"
					( attribute "PN" "6"
						( Origin gPackager )
					)
					( objectStatus "J8F1.6" )
				)
				( pin "nc(1)"
					( attribute "PN" "8"
						( Origin gPackager )
					)
					( objectStatus "J8F1.8" )
				)
				( pin "nc(2)"
					( attribute "PN" "20"
						( Origin gPackager )
					)
					( objectStatus "J8F1.20" )
				)
				( pin "nc(3)"
					( attribute "PN" "22"
						( Origin gPackager )
					)
					( objectStatus "J8F1.22" )
				)
				( pin "nc(4)"
					( attribute "PN" "24"
						( Origin gPackager )
					)
					( objectStatus "J8F1.24" )
				)
				( pin "nc(5)"
					( attribute "PN" "26"
						( Origin gPackager )
					)
					( objectStatus "J8F1.26" )
				)
				( pin "nc(6)"
					( attribute "PN" "28"
						( Origin gPackager )
					)
					( objectStatus "J8F1.28" )
				)
				( pin "nc(7)"
					( attribute "PN" "30"
						( Origin gPackager )
					)
					( objectStatus "J8F1.30" )
				)
				( pin "nc(8)"
					( attribute "PN" "32"
						( Origin gPackager )
					)
					( objectStatus "J8F1.32" )
				)
				( pin "nc(9)"
					( attribute "PN" "34"
						( Origin gPackager )
					)
					( objectStatus "J8F1.34" )
				)
				( pin "nc(10)"
					( attribute "PN" "36"
						( Origin gPackager )
					)
					( objectStatus "J8F1.36" )
				)
				( pin "nc(11)"
					( attribute "PN" "40"
						( Origin gPackager )
					)
					( objectStatus "J8F1.40" )
				)
				( pin "nc(12)"
					( attribute "PN" "42"
						( Origin gPackager )
					)
					( objectStatus "J8F1.42" )
				)
				( pin "nc(13)"
					( attribute "PN" "44"
						( Origin gPackager )
					)
					( objectStatus "J8F1.44" )
				)
				( pin "nc(14)"
					( attribute "PN" "46"
						( Origin gPackager )
					)
					( objectStatus "J8F1.46" )
				)
				( pin "nc(15)"
					( attribute "PN" "48"
						( Origin gPackager )
					)
					( objectStatus "J8F1.48" )
				)
				( pin "nc(16)"
					( attribute "PN" "56"
						( Origin gPackager )
					)
					( objectStatus "J8F1.56" )
				)
				( pin "nc(17)"
					( attribute "PN" "58"
						( Origin gPackager )
					)
					( objectStatus "J8F1.58" )
				)
				( pin "nc(18)"
					( attribute "PN" "67"
						( Origin gPackager )
					)
					( objectStatus "J8F1.67" )
				)
				( pin "pedet"
					( attribute "PN" "69"
						( Origin gPackager )
					)
					( objectStatus "J8F1.69" )
				)
				( pin "pern0_sata_bp"
					( attribute "PN" "41"
						( Origin gPackager )
					)
					( objectStatus "J8F1.41" )
				)
				( pin "pern1"
					( attribute "PN" "29"
						( Origin gPackager )
					)
					( objectStatus "J8F1.29" )
				)
				( pin "pern2"
					( attribute "PN" "17"
						( Origin gPackager )
					)
					( objectStatus "J8F1.17" )
				)
				( pin "pern3"
					( attribute "PN" "5"
						( Origin gPackager )
					)
					( objectStatus "J8F1.5" )
				)
				( pin "perp0_sata_bn"
					( attribute "PN" "43"
						( Origin gPackager )
					)
					( objectStatus "J8F1.43" )
				)
				( pin "perp1"
					( attribute "PN" "31"
						( Origin gPackager )
					)
					( objectStatus "J8F1.31" )
				)
				( pin "perp2"
					( attribute "PN" "19"
						( Origin gPackager )
					)
					( objectStatus "J8F1.19" )
				)
				( pin "perp3"
					( attribute "PN" "7"
						( Origin gPackager )
					)
					( objectStatus "J8F1.7" )
				)
				( pin "perst_n_nc"
					( attribute "PN" "50"
						( Origin gPackager )
					)
					( objectStatus "J8F1.50" )
				)
				( pin "petn0_sata_an"
					( attribute "PN" "47"
						( Origin gPackager )
					)
					( objectStatus "J8F1.47" )
				)
				( pin "petn1"
					( attribute "PN" "35"
						( Origin gPackager )
					)
					( objectStatus "J8F1.35" )
				)
				( pin "petn2"
					( attribute "PN" "23"
						( Origin gPackager )
					)
					( objectStatus "J8F1.23" )
				)
				( pin "petn3"
					( attribute "PN" "11"
						( Origin gPackager )
					)
					( objectStatus "J8F1.11" )
				)
				( pin "petp0_sata_ap"
					( attribute "PN" "49"
						( Origin gPackager )
					)
					( objectStatus "J8F1.49" )
				)
				( pin "petp1"
					( attribute "PN" "37"
						( Origin gPackager )
					)
					( objectStatus "J8F1.37" )
				)
				( pin "petp2"
					( attribute "PN" "25"
						( Origin gPackager )
					)
					( objectStatus "J8F1.25" )
				)
				( pin "petp3"
					( attribute "PN" "13"
						( Origin gPackager )
					)
					( objectStatus "J8F1.13" )
				)
				( pin "pewake_n_nc"
					( attribute "PN" "54"
						( Origin gPackager )
					)
					( objectStatus "J8F1.54" )
				)
				( pin "refclkn"
					( attribute "PN" "53"
						( Origin gPackager )
					)
					( objectStatus "J8F1.53" )
				)
				( pin "refclkp"
					( attribute "PN" "55"
						( Origin gPackager )
					)
					( objectStatus "J8F1.55" )
				)
				( pin "susclk"
					( attribute "PN" "68"
						( Origin gPackager )
					)
					( objectStatus "J8F1.68" )
				)
			)
			( gate "@baseboard_fab2_lib.baseboard_fab2(sch_1):page185_i62"
				( attribute "BOM_COST" "ST_FLASH"
					( Origin gFrontEnd )
				)
				( attribute "CDS_LIB" "mstr_discrete"
					( Origin gPackager )
				)
				( attribute "CDS_LOCATION" "C2T11"
					( Origin gPackager )
				)
				( attribute "CDS_SEC" "1"
					( Origin gPackager )
				)
				( attribute "LOCATION" "C2T11"
					( Origin gFrontEnd )
				)
				( attribute "MATERIAL" "X7R"
					( Origin gFrontEnd )
				)
				( attribute "PACK_TYPE" "0402"
					( Origin gFrontEnd )
				)
				( attribute "PART_NUMBER" "A36096-155"
					( Origin gFrontEnd )
				)
				( attribute "PHYS_PAGE" "185"
					( Origin gFrontEnd )
				)
				( attribute "ROOM" "M_2"
					( Origin gFrontEnd )
				)
				( attribute "ROT" "0"
					( Origin gFrontEnd )
				)
				( attribute "SEC" "1"
					( Origin gFrontEnd )
				)
				( attribute "SEC_TYPE" "0402"
					( Origin gFrontEnd )
				)
				( attribute "TOLERANCE" "10%"
					( Origin gFrontEnd )
				)
				( attribute "VALUE" "0.22UF"
					( Origin gFrontEnd )
				)
				( attribute "VER" "2"
					( Origin gFrontEnd )
				)
				( attribute "VOLTAGE" "16V"
					( Units "uVoltage" "V" 1.000000)
					( Origin gFrontEnd )
				)
				( attribute "XY" "(-3950,3625)"
					( Origin gFrontEnd )
				)
				( attribute "CHIPS_PART_NAME" "CAP"
					( Origin gPackager )
				)
				( attribute "CDS_PART_NAME" "CAP_0402-0.22UF,16V,10%,X7R,A3A"
					( Origin gPackager )
				)
				( objectStatus "C2T11" )
				( pin "a"
					( attribute "PN" "1"
						( Origin gPackager )
					)
					( objectStatus "C2T11.1" )
				)
				( pin "b"
					( attribute "PN" "2"
						( Origin gPackager )
					)
					( objectStatus "C2T11.2" )
				)
			)
			( gate "@baseboard_fab2_lib.baseboard_fab2(sch_1):page185_i63"
				( attribute "BOM_COST" "ST_FLASH"
					( Origin gFrontEnd )
				)
				( attribute "CDS_LIB" "mstr_discrete"
					( Origin gPackager )
				)
				( attribute "CDS_LOCATION" "C2T10"
					( Origin gPackager )
				)
				( attribute "CDS_SEC" "1"
					( Origin gPackager )
				)
				( attribute "LOCATION" "C2T10"
					( Origin gFrontEnd )
				)
				( attribute "MATERIAL" "X7R"
					( Origin gFrontEnd )
				)
				( attribute "PACK_TYPE" "0402"
					( Origin gFrontEnd )
				)
				( attribute "PART_NUMBER" "A36096-155"
					( Origin gFrontEnd )
				)
				( attribute "PHYS_PAGE" "185"
					( Origin gFrontEnd )
				)
				( attribute "ROOM" "M_2"
					( Origin gFrontEnd )
				)
				( attribute "ROT" "0"
					( Origin gFrontEnd )
				)
				( attribute "SEC" "1"
					( Origin gFrontEnd )
				)
				( attribute "SEC_TYPE" "0402"
					( Origin gFrontEnd )
				)
				( attribute "TOLERANCE" "10%"
					( Origin gFrontEnd )
				)
				( attribute "VALUE" "0.22UF"
					( Origin gFrontEnd )
				)
				( attribute "VER" "2"
					( Origin gFrontEnd )
				)
				( attribute "VOLTAGE" "16V"
					( Units "uVoltage" "V" 1.000000)
					( Origin gFrontEnd )
				)
				( attribute "XY" "(-3950,3675)"
					( Origin gFrontEnd )
				)
				( attribute "CHIPS_PART_NAME" "CAP"
					( Origin gPackager )
				)
				( attribute "CDS_PART_NAME" "CAP_0402-0.22UF,16V,10%,X7R,A3A"
					( Origin gPackager )
				)
				( objectStatus "C2T10" )
				( pin "a"
					( attribute "PN" "1"
						( Origin gPackager )
					)
					( objectStatus "C2T10.1" )
				)
				( pin "b"
					( attribute "PN" "2"
						( Origin gPackager )
					)
					( objectStatus "C2T10.2" )
				)
			)
			( gate "@baseboard_fab2_lib.baseboard_fab2(sch_1):page185_i64"
				( attribute "BOM_COST" "ST_FLASH"
					( Origin gFrontEnd )
				)
				( attribute "CDS_LIB" "mstr_discrete"
					( Origin gPackager )
				)
				( attribute "CDS_LOCATION" "C2T13"
					( Origin gPackager )
				)
				( attribute "CDS_SEC" "1"
					( Origin gPackager )
				)
				( attribute "LOCATION" "C2T13"
					( Origin gFrontEnd )
				)
				( attribute "MATERIAL" "X7R"
					( Origin gFrontEnd )
				)
				( attribute "PACK_TYPE" "0402"
					( Origin gFrontEnd )
				)
				( attribute "PART_NUMBER" "A36096-155"
					( Origin gFrontEnd )
				)
				( attribute "PHYS_PAGE" "185"
					( Origin gFrontEnd )
				)
				( attribute "ROOM" "M_2"
					( Origin gFrontEnd )
				)
				( attribute "ROT" "0"
					( Origin gFrontEnd )
				)
				( attribute "SEC" "1"
					( Origin gFrontEnd )
				)
				( attribute "SEC_TYPE" "0402"
					( Origin gFrontEnd )
				)
				( attribute "TOLERANCE" "10%"
					( Origin gFrontEnd )
				)
				( attribute "VALUE" "0.22UF"
					( Origin gFrontEnd )
				)
				( attribute "VER" "2"
					( Origin gFrontEnd )
				)
				( attribute "VOLTAGE" "16V"
					( Units "uVoltage" "V" 1.000000)
					( Origin gFrontEnd )
				)
				( attribute "XY" "(-3950,3925)"
					( Origin gFrontEnd )
				)
				( attribute "CHIPS_PART_NAME" "CAP"
					( Origin gPackager )
				)
				( attribute "CDS_PART_NAME" "CAP_0402-0.22UF,16V,10%,X7R,A3A"
					( Origin gPackager )
				)
				( objectStatus "C2T13" )
				( pin "a"
					( attribute "PN" "1"
						( Origin gPackager )
					)
					( objectStatus "C2T13.1" )
				)
				( pin "b"
					( attribute "PN" "2"
						( Origin gPackager )
					)
					( objectStatus "C2T13.2" )
				)
			)
			( gate "@baseboard_fab2_lib.baseboard_fab2(sch_1):page185_i65"
				( attribute "BOM_COST" "ST_FLASH"
					( Origin gFrontEnd )
				)
				( attribute "CDS_LIB" "mstr_discrete"
					( Origin gPackager )
				)
				( attribute "CDS_LOCATION" "C2T14"
					( Origin gPackager )
				)
				( attribute "CDS_SEC" "1"
					( Origin gPackager )
				)
				( attribute "LOCATION" "C2T14"
					( Origin gFrontEnd )
				)
				( attribute "MATERIAL" "X7R"
					( Origin gFrontEnd )
				)
				( attribute "PACK_TYPE" "0402"
					( Origin gFrontEnd )
				)
				( attribute "PART_NUMBER" "A36096-155"
					( Origin gFrontEnd )
				)
				( attribute "PHYS_PAGE" "185"
					( Origin gFrontEnd )
				)
				( attribute "ROOM" "M_2"
					( Origin gFrontEnd )
				)
				( attribute "ROT" "0"
					( Origin gFrontEnd )
				)
				( attribute "SEC" "1"
					( Origin gFrontEnd )
				)
				( attribute "SEC_TYPE" "0402"
					( Origin gFrontEnd )
				)
				( attribute "TOLERANCE" "10%"
					( Origin gFrontEnd )
				)
				( attribute "VALUE" "0.22UF"
					( Origin gFrontEnd )
				)
				( attribute "VER" "2"
					( Origin gFrontEnd )
				)
				( attribute "VOLTAGE" "16V"
					( Units "uVoltage" "V" 1.000000)
					( Origin gFrontEnd )
				)
				( attribute "XY" "(-3950,3875)"
					( Origin gFrontEnd )
				)
				( attribute "CHIPS_PART_NAME" "CAP"
					( Origin gPackager )
				)
				( attribute "CDS_PART_NAME" "CAP_0402-0.22UF,16V,10%,X7R,A3A"
					( Origin gPackager )
				)
				( objectStatus "C2T14" )
				( pin "a"
					( attribute "PN" "1"
						( Origin gPackager )
					)
					( objectStatus "C2T14.1" )
				)
				( pin "b"
					( attribute "PN" "2"
						( Origin gPackager )
					)
					( objectStatus "C2T14.2" )
				)
			)
			( gate "@baseboard_fab2_lib.baseboard_fab2(sch_1):page185_i66"
				( attribute "BOM_COST" "ST_FLASH"
					( Origin gFrontEnd )
				)
				( attribute "CDS_LIB" "mstr_discrete"
					( Origin gPackager )
				)
				( attribute "CDS_LOCATION" "C2T20"
					( Origin gPackager )
				)
				( attribute "CDS_SEC" "1"
					( Origin gPackager )
				)
				( attribute "LOCATION" "C2T20"
					( Origin gFrontEnd )
				)
				( attribute "MATERIAL" "X7R"
					( Origin gFrontEnd )
				)
				( attribute "PACK_TYPE" "0402"
					( Origin gFrontEnd )
				)
				( attribute "PART_NUMBER" "A36096-155"
					( Origin gFrontEnd )
				)
				( attribute "PHYS_PAGE" "185"
					( Origin gFrontEnd )
				)
				( attribute "ROOM" "M_2"
					( Origin gFrontEnd )
				)
				( attribute "ROT" "0"
					( Origin gFrontEnd )
				)
				( attribute "SEC" "1"
					( Origin gFrontEnd )
				)
				( attribute "SEC_TYPE" "0402"
					( Origin gFrontEnd )
				)
				( attribute "TOLERANCE" "10%"
					( Origin gFrontEnd )
				)
				( attribute "VALUE" "0.22UF"
					( Origin gFrontEnd )
				)
				( attribute "VER" "2"
					( Origin gFrontEnd )
				)
				( attribute "VOLTAGE" "16V"
					( Units "uVoltage" "V" 1.000000)
					( Origin gFrontEnd )
				)
				( attribute "XY" "(-3950,4175)"
					( Origin gFrontEnd )
				)
				( attribute "CHIPS_PART_NAME" "CAP"
					( Origin gPackager )
				)
				( attribute "CDS_PART_NAME" "CAP_0402-0.22UF,16V,10%,X7R,A3A"
					( Origin gPackager )
				)
				( objectStatus "C2T20" )
				( pin "a"
					( attribute "PN" "1"
						( Origin gPackager )
					)
					( objectStatus "C2T20.1" )
				)
				( pin "b"
					( attribute "PN" "2"
						( Origin gPackager )
					)
					( objectStatus "C2T20.2" )
				)
			)
			( gate "@baseboard_fab2_lib.baseboard_fab2(sch_1):page185_i67"
				( attribute "BOM_COST" "ST_FLASH"
					( Origin gFrontEnd )
				)
				( attribute "CDS_LIB" "mstr_discrete"
					( Origin gPackager )
				)
				( attribute "CDS_LOCATION" "C2T23"
					( Origin gPackager )
				)
				( attribute "CDS_SEC" "1"
					( Origin gPackager )
				)
				( attribute "LOCATION" "C2T23"
					( Origin gFrontEnd )
				)
				( attribute "MATERIAL" "X7R"
					( Origin gFrontEnd )
				)
				( attribute "PACK_TYPE" "0402"
					( Origin gFrontEnd )
				)
				( attribute "PART_NUMBER" "A36096-155"
					( Origin gFrontEnd )
				)
				( attribute "PHYS_PAGE" "185"
					( Origin gFrontEnd )
				)
				( attribute "ROOM" "M_2"
					( Origin gFrontEnd )
				)
				( attribute "ROT" "0"
					( Origin gFrontEnd )
				)
				( attribute "SEC" "1"
					( Origin gFrontEnd )
				)
				( attribute "SEC_TYPE" "0402"
					( Origin gFrontEnd )
				)
				( attribute "TOLERANCE" "10%"
					( Origin gFrontEnd )
				)
				( attribute "VALUE" "0.22UF"
					( Origin gFrontEnd )
				)
				( attribute "VER" "2"
					( Origin gFrontEnd )
				)
				( attribute "VOLTAGE" "16V"
					( Units "uVoltage" "V" 1.000000)
					( Origin gFrontEnd )
				)
				( attribute "XY" "(-3950,4125)"
					( Origin gFrontEnd )
				)
				( attribute "CHIPS_PART_NAME" "CAP"
					( Origin gPackager )
				)
				( attribute "CDS_PART_NAME" "CAP_0402-0.22UF,16V,10%,X7R,A3A"
					( Origin gPackager )
				)
				( objectStatus "C2T23" )
				( pin "a"
					( attribute "PN" "1"
						( Origin gPackager )
					)
					( objectStatus "C2T23.1" )
				)
				( pin "b"
					( attribute "PN" "2"
						( Origin gPackager )
					)
					( objectStatus "C2T23.2" )
				)
			)
			( gate "@baseboard_fab2_lib.baseboard_fab2(sch_1):page185_i90"
				( attribute "BOM_COST" "ST_FLASH"
					( Origin gFrontEnd )
				)
				( attribute "CDS_LIB" "dev_discrete"
					( Origin gPackager )
				)
				( attribute "CDS_LOCATION" "C8F15"
					( Origin gPackager )
				)
				( attribute "CDS_SEC" "1"
					( Origin gPackager )
				)
				( attribute "LOCATION" "C8F15"
					( Origin gFrontEnd )
				)
				( attribute "MATERIAL" "EMPTY"
					( Origin gFrontEnd )
				)
				( attribute "NO_XNET_CONNECTION" "1"
					( Origin gFrontEnd )
				)
				( attribute "PACK_TYPE" "0402V"
					( Origin gFrontEnd )
				)
				( attribute "PART_NUMBER" "A36096-045"
					( Origin gFrontEnd )
				)
				( attribute "PHYS_PAGE" "185"
					( Origin gFrontEnd )
				)
				( attribute "ROOM" "M_2"
					( Origin gFrontEnd )
				)
				( attribute "ROT" "0"
					( Origin gFrontEnd )
				)
				( attribute "SEC" "1"
					( Origin gPackager )
				)
				( attribute "TOLERANCE" "10%"
					( Origin gFrontEnd )
				)
				( attribute "VALUE" "0.01UF"
					( Origin gFrontEnd )
				)
				( attribute "VER" "2"
					( Origin gFrontEnd )
				)
				( attribute "VOLTAGE" "25V"
					( Units "uVoltage" "V" 1.000000)
					( Origin gFrontEnd )
				)
				( attribute "XY" "(-2875,850)"
					( Origin gFrontEnd )
				)
				( attribute "CHIPS_PART_NAME" "CAP_A"
					( Origin gPackager )
				)
				( attribute "CDS_PART_NAME" "CAP_A_0402V-0.01UF,25V,10%,EMPA"
					( Origin gPackager )
				)
				( objectStatus "C8F15" )
				( pin "a"
					( attribute "PN" "1"
						( Origin gPackager )
					)
					( objectStatus "C8F15.1" )
				)
				( pin "b"
					( attribute "PN" "2"
						( Origin gPackager )
					)
					( objectStatus "C8F15.2" )
				)
			)
			( gate "@baseboard_fab2_lib.baseboard_fab2(sch_1):page185_i95"
				( attribute "BOM_COST" "ST_FLASH"
					( Origin gFrontEnd )
				)
				( attribute "CDS_LIB" "dev_discrete"
					( Origin gPackager )
				)
				( attribute "CDS_LOCATION" "C8F6"
					( Origin gPackager )
				)
				( attribute "CDS_SEC" "1"
					( Origin gPackager )
				)
				( attribute "LOCATION" "C8F6"
					( Origin gFrontEnd )
				)
				( attribute "MATERIAL" "EMPTY"
					( Origin gFrontEnd )
				)
				( attribute "NO_XNET_CONNECTION" "1"
					( Origin gFrontEnd )
				)
				( attribute "PACK_TYPE" "0402V"
					( Origin gFrontEnd )
				)
				( attribute "PART_NUMBER" "A36096-045"
					( Origin gFrontEnd )
				)
				( attribute "PHYS_PAGE" "185"
					( Origin gFrontEnd )
				)
				( attribute "ROOM" "M_2"
					( Origin gFrontEnd )
				)
				( attribute "ROT" "0"
					( Origin gFrontEnd )
				)
				( attribute "SEC" "1"
					( Origin gPackager )
				)
				( attribute "TOLERANCE" "10%"
					( Origin gFrontEnd )
				)
				( attribute "VALUE" "0.01UF"
					( Origin gFrontEnd )
				)
				( attribute "VER" "2"
					( Origin gFrontEnd )
				)
				( attribute "VOLTAGE" "25V"
					( Units "uVoltage" "V" 1.000000)
					( Origin gFrontEnd )
				)
				( attribute "XY" "(-2900,2200)"
					( Origin gFrontEnd )
				)
				( attribute "CHIPS_PART_NAME" "CAP_A"
					( Origin gPackager )
				)
				( attribute "CDS_PART_NAME" "CAP_A_0402V-0.01UF,25V,10%,EMPA"
					( Origin gPackager )
				)
				( objectStatus "C8F6" )
				( pin "a"
					( attribute "PN" "1"
						( Origin gPackager )
					)
					( objectStatus "C8F6.1" )
				)
				( pin "b"
					( attribute "PN" "2"
						( Origin gPackager )
					)
					( objectStatus "C8F6.2" )
				)
			)
			( gate "@baseboard_fab2_lib.baseboard_fab2(sch_1):page185_i96"
				( attribute "BOM_COST" "ST_FLASH"
					( Origin gFrontEnd )
				)
				( attribute "CDS_LIB" "mstr_discrete"
					( Origin gPackager )
				)
				( attribute "CDS_LOCATION" "C8F7"
					( Origin gPackager )
				)
				( attribute "CDS_SEC" "1"
					( Origin gPackager )
				)
				( attribute "LOCATION" "C8F7"
					( Origin gFrontEnd )
				)
				( attribute "MATERIAL" "X7R"
					( Origin gFrontEnd )
				)
				( attribute "PACK_TYPE" "0402"
					( Origin gFrontEnd )
				)
				( attribute "PART_NUMBER" "A36096-155"
					( Origin gFrontEnd )
				)
				( attribute "PHYS_PAGE" "185"
					( Origin gFrontEnd )
				)
				( attribute "ROOM" "M_2"
					( Origin gFrontEnd )
				)
				( attribute "ROT" "0"
					( Origin gFrontEnd )
				)
				( attribute "SEC" "1"
					( Origin gFrontEnd )
				)
				( attribute "SEC_TYPE" "0402"
					( Origin gFrontEnd )
				)
				( attribute "TOLERANCE" "10%"
					( Origin gFrontEnd )
				)
				( attribute "VALUE" "0.22UF"
					( Origin gFrontEnd )
				)
				( attribute "VER" "2"
					( Origin gFrontEnd )
				)
				( attribute "VOLTAGE" "16V"
					( Units "uVoltage" "V" 1.000000)
					( Origin gFrontEnd )
				)
				( attribute "XY" "(-2900,1925)"
					( Origin gFrontEnd )
				)
				( attribute "CHIPS_PART_NAME" "CAP"
					( Origin gPackager )
				)
				( attribute "CDS_PART_NAME" "CAP_0402-0.22UF,16V,10%,X7R,A3A"
					( Origin gPackager )
				)
				( objectStatus "C8F7" )
				( pin "a"
					( attribute "PN" "1"
						( Origin gPackager )
					)
					( objectStatus "C8F7.1" )
				)
				( pin "b"
					( attribute "PN" "2"
						( Origin gPackager )
					)
					( objectStatus "C8F7.2" )
				)
			)
			( gate "@baseboard_fab2_lib.baseboard_fab2(sch_1):page185_i97"
				( attribute "BOM_COST" "ST_FLASH"
					( Origin gFrontEnd )
				)
				( attribute "CDS_LIB" "dev_discrete"
					( Origin gPackager )
				)
				( attribute "CDS_LOCATION" "C8F11"
					( Origin gPackager )
				)
				( attribute "CDS_SEC" "1"
					( Origin gPackager )
				)
				( attribute "LOCATION" "C8F11"
					( Origin gFrontEnd )
				)
				( attribute "MATERIAL" "EMPTY"
					( Origin gFrontEnd )
				)
				( attribute "NO_XNET_CONNECTION" "1"
					( Origin gFrontEnd )
				)
				( attribute "PACK_TYPE" "0402V"
					( Origin gFrontEnd )
				)
				( attribute "PART_NUMBER" "A36096-045"
					( Origin gFrontEnd )
				)
				( attribute "PHYS_PAGE" "185"
					( Origin gFrontEnd )
				)
				( attribute "ROOM" "M_2"
					( Origin gFrontEnd )
				)
				( attribute "ROT" "0"
					( Origin gFrontEnd )
				)
				( attribute "SEC" "1"
					( Origin gPackager )
				)
				( attribute "TOLERANCE" "10%"
					( Origin gFrontEnd )
				)
				( attribute "VALUE" "0.01UF"
					( Origin gFrontEnd )
				)
				( attribute "VER" "2"
					( Origin gFrontEnd )
				)
				( attribute "VOLTAGE" "25V"
					( Units "uVoltage" "V" 1.000000)
					( Origin gFrontEnd )
				)
				( attribute "XY" "(-2900,1700)"
					( Origin gFrontEnd )
				)
				( attribute "CHIPS_PART_NAME" "CAP_A"
					( Origin gPackager )
				)
				( attribute "CDS_PART_NAME" "CAP_A_0402V-0.01UF,25V,10%,EMPA"
					( Origin gPackager )
				)
				( objectStatus "C8F11" )
				( pin "a"
					( attribute "PN" "1"
						( Origin gPackager )
					)
					( objectStatus "C8F11.1" )
				)
				( pin "b"
					( attribute "PN" "2"
						( Origin gPackager )
					)
					( objectStatus "C8F11.2" )
				)
			)
			( gate "@baseboard_fab2_lib.baseboard_fab2(sch_1):page185_i98"
				( attribute "BOM_COST" "ST_FLASH"
					( Origin gFrontEnd )
				)
				( attribute "CDS_LIB" "mstr_discrete"
					( Origin gPackager )
				)
				( attribute "CDS_LOCATION" "C8F12"
					( Origin gPackager )
				)
				( attribute "CDS_SEC" "1"
					( Origin gPackager )
				)
				( attribute "LOCATION" "C8F12"
					( Origin gFrontEnd )
				)
				( attribute "MATERIAL" "X7R"
					( Origin gFrontEnd )
				)
				( attribute "PACK_TYPE" "0402"
					( Origin gFrontEnd )
				)
				( attribute "PART_NUMBER" "A36096-155"
					( Origin gFrontEnd )
				)
				( attribute "PHYS_PAGE" "185"
					( Origin gFrontEnd )
				)
				( attribute "ROOM" "M_2"
					( Origin gFrontEnd )
				)
				( attribute "ROT" "0"
					( Origin gFrontEnd )
				)
				( attribute "SEC" "1"
					( Origin gFrontEnd )
				)
				( attribute "SEC_TYPE" "0402"
					( Origin gFrontEnd )
				)
				( attribute "TOLERANCE" "10%"
					( Origin gFrontEnd )
				)
				( attribute "VALUE" "0.22UF"
					( Origin gFrontEnd )
				)
				( attribute "VER" "2"
					( Origin gFrontEnd )
				)
				( attribute "VOLTAGE" "16V"
					( Units "uVoltage" "V" 1.000000)
					( Origin gFrontEnd )
				)
				( attribute "XY" "(-2900,1475)"
					( Origin gFrontEnd )
				)
				( attribute "CHIPS_PART_NAME" "CAP"
					( Origin gPackager )
				)
				( attribute "CDS_PART_NAME" "CAP_0402-0.22UF,16V,10%,X7R,A3A"
					( Origin gPackager )
				)
				( objectStatus "C8F12" )
				( pin "a"
					( attribute "PN" "1"
						( Origin gPackager )
					)
					( objectStatus "C8F12.1" )
				)
				( pin "b"
					( attribute "PN" "2"
						( Origin gPackager )
					)
					( objectStatus "C8F12.2" )
				)
			)
			( gate "@baseboard_fab2_lib.baseboard_fab2(sch_1):page185_i99"
				( attribute "BOM_COST" "ST_FLASH"
					( Origin gFrontEnd )
				)
				( attribute "CDS_LIB" "dev_discrete"
					( Origin gPackager )
				)
				( attribute "CDS_LOCATION" "C8F13"
					( Origin gPackager )
				)
				( attribute "CDS_SEC" "1"
					( Origin gPackager )
				)
				( attribute "LOCATION" "C8F13"
					( Origin gFrontEnd )
				)
				( attribute "MATERIAL" "EMPTY"
					( Origin gFrontEnd )
				)
				( attribute "NO_XNET_CONNECTION" "1"
					( Origin gFrontEnd )
				)
				( attribute "PACK_TYPE" "0402V"
					( Origin gFrontEnd )
				)
				( attribute "PART_NUMBER" "A36096-045"
					( Origin gFrontEnd )
				)
				( attribute "PHYS_PAGE" "185"
					( Origin gFrontEnd )
				)
				( attribute "ROOM" "M_2"
					( Origin gFrontEnd )
				)
				( attribute "ROT" "0"
					( Origin gFrontEnd )
				)
				( attribute "SEC" "1"
					( Origin gPackager )
				)
				( attribute "TOLERANCE" "10%"
					( Origin gFrontEnd )
				)
				( attribute "VALUE" "0.01UF"
					( Origin gFrontEnd )
				)
				( attribute "VER" "2"
					( Origin gFrontEnd )
				)
				( attribute "VOLTAGE" "25V"
					( Units "uVoltage" "V" 1.000000)
					( Origin gFrontEnd )
				)
				( attribute "XY" "(-2900,1275)"
					( Origin gFrontEnd )
				)
				( attribute "CHIPS_PART_NAME" "CAP_A"
					( Origin gPackager )
				)
				( attribute "CDS_PART_NAME" "CAP_A_0402V-0.01UF,25V,10%,EMPA"
					( Origin gPackager )
				)
				( objectStatus "C8F13" )
				( pin "a"
					( attribute "PN" "1"
						( Origin gPackager )
					)
					( objectStatus "C8F13.1" )
				)
				( pin "b"
					( attribute "PN" "2"
						( Origin gPackager )
					)
					( objectStatus "C8F13.2" )
				)
			)
			( gate "@baseboard_fab2_lib.baseboard_fab2(sch_1):page185_i105"
				( attribute "BOM_COST" "ST_FLASH"
					( Origin gFrontEnd )
				)
				( attribute "CDS_LIB" "mstr_discrete"
					( Origin gPackager )
				)
				( attribute "CDS_LOCATION" "R8F18"
					( Origin gPackager )
				)
				( attribute "CDS_SEC" "1"
					( Origin gPackager )
				)
				( attribute "LOCATION" "R8F18"
					( Origin gFrontEnd )
				)
				( attribute "MATERIAL" "CHIP"
					( Origin gFrontEnd )
				)
				( attribute "PACK_TYPE" "0402"
					( Origin gFrontEnd )
				)
				( attribute "PART_NUMBER" "G21497-005"
					( Origin gFrontEnd )
				)
				( attribute "PHYS_PAGE" "185"
					( Origin gFrontEnd )
				)
				( attribute "ROOM" "M_2"
					( Origin gFrontEnd )
				)
				( attribute "ROT" "0"
					( Origin gFrontEnd )
				)
				( attribute "SEC" "1"
					( Origin gFrontEnd )
				)
				( attribute "SEC_TYPE" "0402"
					( Origin gFrontEnd )
				)
				( attribute "TOLERANCE" "5%"
					( Origin gFrontEnd )
				)
				( attribute "VALUE" "0.0"
					( Origin gFrontEnd )
				)
				( attribute "VER" "1"
					( Origin gFrontEnd )
				)
				( attribute "WATTAGE" "1/16W"
					( Origin gFrontEnd )
				)
				( attribute "XY" "(-2900,1050)"
					( Origin gFrontEnd )
				)
				( attribute "CHIPS_PART_NAME" "RES"
					( Origin gPackager )
				)
				( attribute "CDS_PART_NAME" "RES_0402-0.0,5%,1/16W,CHIP,G21A"
					( Origin gPackager )
				)
				( objectStatus "R8F18" )
				( pin "a"
					( attribute "PN" "1"
						( Origin gPackager )
					)
					( objectStatus "R8F18.1" )
				)
				( pin "b"
					( attribute "PN" "2"
						( Origin gPackager )
					)
					( objectStatus "R8F18.2" )
				)
			)
			( gate "@baseboard_fab2_lib.baseboard_fab2(sch_1):page185_i106"
				( attribute "BOM_COST" "ST_FLASH"
					( Origin gFrontEnd )
				)
				( attribute "CDS_LIB" "mstr_discrete"
					( Origin gPackager )
				)
				( attribute "CDS_LOCATION" "R8F21"
					( Origin gPackager )
				)
				( attribute "CDS_SEC" "1"
					( Origin gPackager )
				)
				( attribute "LOCATION" "R8F21"
					( Origin gFrontEnd )
				)
				( attribute "MATERIAL" "CHIP"
					( Origin gFrontEnd )
				)
				( attribute "PACK_TYPE" "0402"
					( Origin gFrontEnd )
				)
				( attribute "PART_NUMBER" "G21497-005"
					( Origin gFrontEnd )
				)
				( attribute "PHYS_PAGE" "185"
					( Origin gFrontEnd )
				)
				( attribute "ROOM" "M_2"
					( Origin gFrontEnd )
				)
				( attribute "ROT" "0"
					( Origin gFrontEnd )
				)
				( attribute "SEC" "1"
					( Origin gFrontEnd )
				)
				( attribute "SEC_TYPE" "0402"
					( Origin gFrontEnd )
				)
				( attribute "TOLERANCE" "5%"
					( Origin gFrontEnd )
				)
				( attribute "VALUE" "0.0"
					( Origin gFrontEnd )
				)
				( attribute "VER" "1"
					( Origin gFrontEnd )
				)
				( attribute "WATTAGE" "1/16W"
					( Origin gFrontEnd )
				)
				( attribute "XY" "(-2875,600)"
					( Origin gFrontEnd )
				)
				( attribute "CHIPS_PART_NAME" "RES"
					( Origin gPackager )
				)
				( attribute "CDS_PART_NAME" "RES_0402-0.0,5%,1/16W,CHIP,G21A"
					( Origin gPackager )
				)
				( objectStatus "R8F21" )
				( pin "a"
					( attribute "PN" "1"
						( Origin gPackager )
					)
					( objectStatus "R8F21.1" )
				)
				( pin "b"
					( attribute "PN" "2"
						( Origin gPackager )
					)
					( objectStatus "R8F21.2" )
				)
			)
			( gate "@baseboard_fab2_lib.baseboard_fab2(sch_1):page185_i110"
				( attribute "BOM_COST" "ST_FLASH"
					( Origin gFrontEnd )
				)
				( attribute "CDS_LIB" "mstr_ttl"
					( Origin gPackager )
				)
				( attribute "CDS_LOCATION" "U2P1"
					( Origin gPackager )
				)
				( attribute "CDS_SEC" "1"
					( Origin gPackager )
				)
				( attribute "LOCATION" "U2P1"
					( Origin gFrontEnd )
				)
				( attribute "MATERIAL" "IC"
					( Origin gFrontEnd )
				)
				( attribute "PACK_TYPE" "SOP"
					( Origin gFrontEnd )
				)
				( attribute "PART_NUMBER" "C88419-001"
					( Origin gFrontEnd )
				)
				( attribute "PHYS_PAGE" "185"
					( Origin gFrontEnd )
				)
				( attribute "ROOM" "M_2"
					( Origin gFrontEnd )
				)
				( attribute "ROT" "0"
					( Origin gFrontEnd )
				)
				( attribute "SEC" "1"
					( Origin gFrontEnd )
				)
				( attribute "SEC_TYPE" "SOP"
					( Origin gFrontEnd )
				)
				( attribute "VALUE" "74LVC1G07"
					( Origin gFrontEnd )
				)
				( attribute "VER" "1"
					( Origin gFrontEnd )
				)
				( attribute "XY" "(-6375,1250)"
					( Origin gFrontEnd )
				)
				( attribute "CHIPS_PART_NAME" "TTL1G07_A"
					( Origin gPackager )
				)
				( attribute "CDS_PART_NAME" "TTL1G07_A_SOP-74LVC1G07,IC,C88B"
					( Origin gPackager )
				)
				( objectStatus "U2P1" )
				( pin "a"
					( attribute "PN" "2"
						( Origin gPackager )
					)
					( objectStatus "U2P1.2" )
				)
				( pin "y"
					( attribute "PN" "4"
						( Origin gPackager )
					)
					( objectStatus "U2P1.4" )
				)
			)
			( gate "@baseboard_fab2_lib.baseboard_fab2(sch_1):page185_i111"
				( attribute "BOM_COST" "ST_FLASH"
					( Origin gFrontEnd )
				)
				( attribute "CDS_LIB" "mstr_discrete"
					( Origin gPackager )
				)
				( attribute "CDS_LOCATION" "R2P15"
					( Origin gPackager )
				)
				( attribute "CDS_SEC" "1"
					( Origin gPackager )
				)
				( attribute "LOCATION" "R2P15"
					( Origin gFrontEnd )
				)
				( attribute "MATERIAL" "CHIP"
					( Origin gFrontEnd )
				)
				( attribute "PACK_TYPE" "0402"
					( Origin gFrontEnd )
				)
				( attribute "PART_NUMBER" "G21796-016"
					( Origin gFrontEnd )
				)
				( attribute "PHYS_PAGE" "185"
					( Origin gFrontEnd )
				)
				( attribute "ROOM" "M_2"
					( Origin gFrontEnd )
				)
				( attribute "ROT" "0"
					( Origin gFrontEnd )
				)
				( attribute "SEC" "1"
					( Origin gFrontEnd )
				)
				( attribute "SEC_TYPE" "0402"
					( Origin gFrontEnd )
				)
				( attribute "TOLERANCE" "1%"
					( Origin gFrontEnd )
				)
				( attribute "VALUE" "10.0K"
					( Origin gFrontEnd )
				)
				( attribute "VER" "2"
					( Origin gFrontEnd )
				)
				( attribute "WATTAGE" "1/16W"
					( Origin gFrontEnd )
				)
				( attribute "XY" "(-6725,1525)"
					( Origin gFrontEnd )
				)
				( attribute "CHIPS_PART_NAME" "RES"
					( Origin gPackager )
				)
				( attribute "CDS_PART_NAME" "RES_0402-10.0K,1%,1/16W,CHIP,GA"
					( Origin gPackager )
				)
				( objectStatus "R2P15" )
				( pin "a"
					( attribute "PN" "1"
						( Origin gPackager )
					)
					( objectStatus "R2P15.1" )
				)
				( pin "b"
					( attribute "PN" "2"
						( Origin gPackager )
					)
					( objectStatus "R2P15.2" )
				)
			)
			( gate "@baseboard_fab2_lib.baseboard_fab2(sch_1):page185_i113"
				( attribute "BOM_COST" "ST_FLASH"
					( Origin gFrontEnd )
				)
				( attribute "CDS_LIB" "mstr_discrete"
					( Origin gPackager )
				)
				( attribute "CDS_LOCATION" "R2P16"
					( Origin gPackager )
				)
				( attribute "CDS_SEC" "1"
					( Origin gPackager )
				)
				( attribute "LOCATION" "R2P16"
					( Origin gFrontEnd )
				)
				( attribute "MATERIAL" "CHIP"
					( Origin gFrontEnd )
				)
				( attribute "PACK_TYPE" "0402"
					( Origin gFrontEnd )
				)
				( attribute "PART_NUMBER" "G21796-016"
					( Origin gFrontEnd )
				)
				( attribute "PHYS_PAGE" "185"
					( Origin gFrontEnd )
				)
				( attribute "ROOM" "M_2"
					( Origin gFrontEnd )
				)
				( attribute "ROT" "0"
					( Origin gFrontEnd )
				)
				( attribute "SEC" "1"
					( Origin gFrontEnd )
				)
				( attribute "SEC_TYPE" "0402"
					( Origin gFrontEnd )
				)
				( attribute "TOLERANCE" "1%"
					( Origin gFrontEnd )
				)
				( attribute "VALUE" "10.0K"
					( Origin gFrontEnd )
				)
				( attribute "VER" "2"
					( Origin gFrontEnd )
				)
				( attribute "WATTAGE" "1/16W"
					( Origin gFrontEnd )
				)
				( attribute "XY" "(-6025,1525)"
					( Origin gFrontEnd )
				)
				( attribute "CHIPS_PART_NAME" "RES"
					( Origin gPackager )
				)
				( attribute "CDS_PART_NAME" "RES_0402-10.0K,1%,1/16W,CHIP,GA"
					( Origin gPackager )
				)
				( objectStatus "R2P16" )
				( pin "a"
					( attribute "PN" "1"
						( Origin gPackager )
					)
					( objectStatus "R2P16.1" )
				)
				( pin "b"
					( attribute "PN" "2"
						( Origin gPackager )
					)
					( objectStatus "R2P16.2" )
				)
			)
			( gate "@baseboard_fab2_lib.baseboard_fab2(sch_1):page185_i115"
				( attribute "BOM_COST" "ST_FLASH"
					( Origin gFrontEnd )
				)
				( attribute "CDS_LIB" "mstr_discrete"
					( Origin gPackager )
				)
				( attribute "CDS_LOCATION" "R2P14"
					( Origin gPackager )
				)
				( attribute "CDS_SEC" "1"
					( Origin gPackager )
				)
				( attribute "LOCATION" "R2P14"
					( Origin gFrontEnd )
				)
				( attribute "MATERIAL" "CHIP"
					( Origin gFrontEnd )
				)
				( attribute "PACK_TYPE" "0402"
					( Origin gFrontEnd )
				)
				( attribute "PART_NUMBER" "G21497-005"
					( Origin gFrontEnd )
				)
				( attribute "PHYS_PAGE" "185"
					( Origin gFrontEnd )
				)
				( attribute "ROOM" "M_2"
					( Origin gFrontEnd )
				)
				( attribute "ROT" "0"
					( Origin gFrontEnd )
				)
				( attribute "SEC" "1"
					( Origin gFrontEnd )
				)
				( attribute "SEC_TYPE" "0402"
					( Origin gFrontEnd )
				)
				( attribute "TOLERANCE" "5%"
					( Origin gFrontEnd )
				)
				( attribute "VALUE" "0.0"
					( Origin gFrontEnd )
				)
				( attribute "VER" "1"
					( Origin gFrontEnd )
				)
				( attribute "WATTAGE" "1/16W"
					( Origin gFrontEnd )
				)
				( attribute "XY" "(-5650,1250)"
					( Origin gFrontEnd )
				)
				( attribute "CHIPS_PART_NAME" "RES"
					( Origin gPackager )
				)
				( attribute "CDS_PART_NAME" "RES_0402-0.0,5%,1/16W,CHIP,G21A"
					( Origin gPackager )
				)
				( objectStatus "R2P14" )
				( pin "a"
					( attribute "PN" "1"
						( Origin gPackager )
					)
					( objectStatus "R2P14.1" )
				)
				( pin "b"
					( attribute "PN" "2"
						( Origin gPackager )
					)
					( objectStatus "R2P14.2" )
				)
			)
			( gate "@baseboard_fab2_lib.baseboard_fab2(sch_1):page185_i117"
				( attribute "BOM_COST" "SD_FLASH"
					( Origin gFrontEnd )
				)
				( attribute "CDS_LIB" "dev_discrete"
					( Origin gPackager )
				)
				( attribute "CDS_LOCATION" "C2P9"
					( Origin gPackager )
				)
				( attribute "CDS_SEC" "1"
					( Origin gPackager )
				)
				( attribute "LOCATION" "C2P9"
					( Origin gFrontEnd )
				)
				( attribute "MATERIAL" "X7R"
					( Origin gFrontEnd )
				)
				( attribute "PACK_TYPE" "0402V"
					( Origin gFrontEnd )
				)
				( attribute "PART_NUMBER" "A36096-030"
					( Origin gFrontEnd )
				)
				( attribute "PHYS_PAGE" "185"
					( Origin gFrontEnd )
				)
				( attribute "ROOM" "M_2"
					( Origin gFrontEnd )
				)
				( attribute "ROT" "0"
					( Origin gFrontEnd )
				)
				( attribute "SEC" "1"
					( Origin gFrontEnd )
				)
				( attribute "SEC_TYPE" "0402V"
					( Origin gFrontEnd )
				)
				( attribute "TOLERANCE" "10%"
					( Origin gFrontEnd )
				)
				( attribute "VALUE" "0.1UF"
					( Origin gFrontEnd )
				)
				( attribute "VER" "1"
					( Origin gFrontEnd )
				)
				( attribute "VOLTAGE" "16V"
					( Units "uVoltage" "V" 1.000000)
					( Origin gFrontEnd )
				)
				( attribute "XY" "(-6425,700)"
					( Origin gFrontEnd )
				)
				( attribute "CHIPS_PART_NAME" "CAP_A"
					( Origin gPackager )
				)
				( attribute "CDS_PART_NAME" "CAP_A_0402V-0.1UF,16V,10%,X7R,A"
					( Origin gPackager )
				)
				( objectStatus "C2P9" )
				( pin "a"
					( attribute "PN" "1"
						( Origin gPackager )
					)
					( objectStatus "C2P9.1" )
				)
				( pin "b"
					( attribute "PN" "2"
						( Origin gPackager )
					)
					( objectStatus "C2P9.2" )
				)
			)
			( gate "@baseboard_fab2_lib.baseboard_fab2(sch_1):page185_i120"
				( attribute "BOM_COST" "SD_FLASH"
					( Origin gFrontEnd )
				)
				( attribute "CDS_LIB" "dev_discrete"
					( Origin gPackager )
				)
				( attribute "CDS_LOCATION" "C2T29"
					( Origin gPackager )
				)
				( attribute "CDS_SEC" "1"
					( Origin gPackager )
				)
				( attribute "LOCATION" "C2T29"
					( Origin gFrontEnd )
				)
				( attribute "MATERIAL" "X7R"
					( Origin gFrontEnd )
				)
				( attribute "PACK_TYPE" "0402V"
					( Origin gFrontEnd )
				)
				( attribute "PART_NUMBER" "A36096-030"
					( Origin gFrontEnd )
				)
				( attribute "PHYS_PAGE" "185"
					( Origin gFrontEnd )
				)
				( attribute "ROOM" "M_2"
					( Origin gFrontEnd )
				)
				( attribute "ROT" "0"
					( Origin gFrontEnd )
				)
				( attribute "SEC" "1"
					( Origin gFrontEnd )
				)
				( attribute "SEC_TYPE" "0402V"
					( Origin gFrontEnd )
				)
				( attribute "TOLERANCE" "10%"
					( Origin gFrontEnd )
				)
				( attribute "VALUE" "0.1UF"
					( Origin gFrontEnd )
				)
				( attribute "VER" "1"
					( Origin gFrontEnd )
				)
				( attribute "VOLTAGE" "16V"
					( Units "uVoltage" "V" 1.000000)
					( Origin gFrontEnd )
				)
				( attribute "XY" "(-1650,4500)"
					( Origin gFrontEnd )
				)
				( attribute "CHIPS_PART_NAME" "CAP_A"
					( Origin gPackager )
				)
				( attribute "CDS_PART_NAME" "CAP_A_0402V-0.1UF,16V,10%,X7R,A"
					( Origin gPackager )
				)
				( objectStatus "C2T29" )
				( pin "a"
					( attribute "PN" "1"
						( Origin gPackager )
					)
					( objectStatus "C2T29.1" )
				)
				( pin "b"
					( attribute "PN" "2"
						( Origin gPackager )
					)
					( objectStatus "C2T29.2" )
				)
			)
			( gate "@baseboard_fab2_lib.baseboard_fab2(sch_1):page185_i123"
				( attribute "BOM_COST" "SD_FLASH"
					( Origin gFrontEnd )
				)
				( attribute "CDS_LIB" "dev_discrete"
					( Origin gPackager )
				)
				( attribute "CDS_LOCATION" "C2T26"
					( Origin gPackager )
				)
				( attribute "CDS_SEC" "1"
					( Origin gPackager )
				)
				( attribute "LOCATION" "C2T26"
					( Origin gFrontEnd )
				)
				( attribute "MATERIAL" "X7R"
					( Origin gFrontEnd )
				)
				( attribute "PACK_TYPE" "0402V"
					( Origin gFrontEnd )
				)
				( attribute "PART_NUMBER" "A36096-030"
					( Origin gFrontEnd )
				)
				( attribute "PHYS_PAGE" "185"
					( Origin gFrontEnd )
				)
				( attribute "ROOM" "M_2"
					( Origin gFrontEnd )
				)
				( attribute "ROT" "0"
					( Origin gFrontEnd )
				)
				( attribute "SEC" "1"
					( Origin gFrontEnd )
				)
				( attribute "SEC_TYPE" "0402V"
					( Origin gFrontEnd )
				)
				( attribute "TOLERANCE" "10%"
					( Origin gFrontEnd )
				)
				( attribute "VALUE" "0.1UF"
					( Origin gFrontEnd )
				)
				( attribute "VER" "1"
					( Origin gFrontEnd )
				)
				( attribute "VOLTAGE" "16V"
					( Units "uVoltage" "V" 1.000000)
					( Origin gFrontEnd )
				)
				( attribute "XY" "(-1400,4500)"
					( Origin gFrontEnd )
				)
				( attribute "CHIPS_PART_NAME" "CAP_A"
					( Origin gPackager )
				)
				( attribute "CDS_PART_NAME" "CAP_A_0402V-0.1UF,16V,10%,X7R,A"
					( Origin gPackager )
				)
				( objectStatus "C2T26" )
				( pin "a"
					( attribute "PN" "1"
						( Origin gPackager )
					)
					( objectStatus "C2T26.1" )
				)
				( pin "b"
					( attribute "PN" "2"
						( Origin gPackager )
					)
					( objectStatus "C2T26.2" )
				)
			)
			( gate "@baseboard_fab2_lib.baseboard_fab2(sch_1):page185_i124"
				( attribute "BOM_COST" "SD_FLASH"
					( Origin gFrontEnd )
				)
				( attribute "CDS_LIB" "dev_discrete"
					( Origin gPackager )
				)
				( attribute "CDS_LOCATION" "C2T21"
					( Origin gPackager )
				)
				( attribute "CDS_SEC" "1"
					( Origin gPackager )
				)
				( attribute "LOCATION" "C2T21"
					( Origin gFrontEnd )
				)
				( attribute "MATERIAL" "X7R"
					( Origin gFrontEnd )
				)
				( attribute "PACK_TYPE" "0402V"
					( Origin gFrontEnd )
				)
				( attribute "PART_NUMBER" "A36096-030"
					( Origin gFrontEnd )
				)
				( attribute "PHYS_PAGE" "185"
					( Origin gFrontEnd )
				)
				( attribute "ROOM" "M_2"
					( Origin gFrontEnd )
				)
				( attribute "ROT" "0"
					( Origin gFrontEnd )
				)
				( attribute "SEC" "1"
					( Origin gFrontEnd )
				)
				( attribute "SEC_TYPE" "0402V"
					( Origin gFrontEnd )
				)
				( attribute "TOLERANCE" "10%"
					( Origin gFrontEnd )
				)
				( attribute "VALUE" "0.1UF"
					( Origin gFrontEnd )
				)
				( attribute "VER" "1"
					( Origin gFrontEnd )
				)
				( attribute "VOLTAGE" "16V"
					( Units "uVoltage" "V" 1.000000)
					( Origin gFrontEnd )
				)
				( attribute "XY" "(-1150,4500)"
					( Origin gFrontEnd )
				)
				( attribute "CHIPS_PART_NAME" "CAP_A"
					( Origin gPackager )
				)
				( attribute "CDS_PART_NAME" "CAP_A_0402V-0.1UF,16V,10%,X7R,A"
					( Origin gPackager )
				)
				( objectStatus "C2T21" )
				( pin "a"
					( attribute "PN" "1"
						( Origin gPackager )
					)
					( objectStatus "C2T21.1" )
				)
				( pin "b"
					( attribute "PN" "2"
						( Origin gPackager )
					)
					( objectStatus "C2T21.2" )
				)
			)
			( gate "@baseboard_fab2_lib.baseboard_fab2(sch_1):page185_i126"
				( attribute "BOM_COST" "SD_FLASH"
					( Origin gFrontEnd )
				)
				( attribute "CDS_LIB" "dev_discrete"
					( Origin gPackager )
				)
				( attribute "CDS_LOCATION" "C2T16"
					( Origin gPackager )
				)
				( attribute "CDS_SEC" "1"
					( Origin gPackager )
				)
				( attribute "LOCATION" "C2T16"
					( Origin gFrontEnd )
				)
				( attribute "MATERIAL" "X7R"
					( Origin gFrontEnd )
				)
				( attribute "PACK_TYPE" "0402V"
					( Origin gFrontEnd )
				)
				( attribute "PART_NUMBER" "A36096-030"
					( Origin gFrontEnd )
				)
				( attribute "PHYS_PAGE" "185"
					( Origin gFrontEnd )
				)
				( attribute "ROOM" "M_2"
					( Origin gFrontEnd )
				)
				( attribute "ROT" "0"
					( Origin gFrontEnd )
				)
				( attribute "SEC" "1"
					( Origin gFrontEnd )
				)
				( attribute "SEC_TYPE" "0402V"
					( Origin gFrontEnd )
				)
				( attribute "TOLERANCE" "10%"
					( Origin gFrontEnd )
				)
				( attribute "VALUE" "0.1UF"
					( Origin gFrontEnd )
				)
				( attribute "VER" "1"
					( Origin gFrontEnd )
				)
				( attribute "VOLTAGE" "16V"
					( Units "uVoltage" "V" 1.000000)
					( Origin gFrontEnd )
				)
				( attribute "XY" "(-1150,3650)"
					( Origin gFrontEnd )
				)
				( attribute "CHIPS_PART_NAME" "CAP_A"
					( Origin gPackager )
				)
				( attribute "CDS_PART_NAME" "CAP_A_0402V-0.1UF,16V,10%,X7R,A"
					( Origin gPackager )
				)
				( objectStatus "C2T16" )
				( pin "a"
					( attribute "PN" "1"
						( Origin gPackager )
					)
					( objectStatus "C2T16.1" )
				)
				( pin "b"
					( attribute "PN" "2"
						( Origin gPackager )
					)
					( objectStatus "C2T16.2" )
				)
			)
			( gate "@baseboard_fab2_lib.baseboard_fab2(sch_1):page185_i127"
				( attribute "BOM_COST" "SD_FLASH"
					( Origin gFrontEnd )
				)
				( attribute "CDS_LIB" "dev_discrete"
					( Origin gPackager )
				)
				( attribute "CDS_LOCATION" "C2T15"
					( Origin gPackager )
				)
				( attribute "CDS_SEC" "1"
					( Origin gPackager )
				)
				( attribute "LOCATION" "C2T15"
					( Origin gFrontEnd )
				)
				( attribute "MATERIAL" "X7R"
					( Origin gFrontEnd )
				)
				( attribute "PACK_TYPE" "0402V"
					( Origin gFrontEnd )
				)
				( attribute "PART_NUMBER" "A36096-030"
					( Origin gFrontEnd )
				)
				( attribute "PHYS_PAGE" "185"
					( Origin gFrontEnd )
				)
				( attribute "ROOM" "M_2"
					( Origin gFrontEnd )
				)
				( attribute "ROT" "0"
					( Origin gFrontEnd )
				)
				( attribute "SEC" "1"
					( Origin gFrontEnd )
				)
				( attribute "SEC_TYPE" "0402V"
					( Origin gFrontEnd )
				)
				( attribute "TOLERANCE" "10%"
					( Origin gFrontEnd )
				)
				( attribute "VALUE" "0.1UF"
					( Origin gFrontEnd )
				)
				( attribute "VER" "1"
					( Origin gFrontEnd )
				)
				( attribute "VOLTAGE" "16V"
					( Units "uVoltage" "V" 1.000000)
					( Origin gFrontEnd )
				)
				( attribute "XY" "(-1400,3650)"
					( Origin gFrontEnd )
				)
				( attribute "CHIPS_PART_NAME" "CAP_A"
					( Origin gPackager )
				)
				( attribute "CDS_PART_NAME" "CAP_A_0402V-0.1UF,16V,10%,X7R,A"
					( Origin gPackager )
				)
				( objectStatus "C2T15" )
				( pin "a"
					( attribute "PN" "1"
						( Origin gPackager )
					)
					( objectStatus "C2T15.1" )
				)
				( pin "b"
					( attribute "PN" "2"
						( Origin gPackager )
					)
					( objectStatus "C2T15.2" )
				)
			)
			( gate "@baseboard_fab2_lib.baseboard_fab2(sch_1):page185_i129"
				( attribute "BOM_COST" "SD_FLASH"
					( Origin gFrontEnd )
				)
				( attribute "CDS_LIB" "dev_discrete"
					( Origin gPackager )
				)
				( attribute "CDS_LOCATION" "C2T24"
					( Origin gPackager )
				)
				( attribute "CDS_SEC" "1"
					( Origin gPackager )
				)
				( attribute "LOCATION" "C2T24"
					( Origin gFrontEnd )
				)
				( attribute "MATERIAL" "X7R"
					( Origin gFrontEnd )
				)
				( attribute "PACK_TYPE" "0402V"
					( Origin gFrontEnd )
				)
				( attribute "PART_NUMBER" "A36096-030"
					( Origin gFrontEnd )
				)
				( attribute "PHYS_PAGE" "185"
					( Origin gFrontEnd )
				)
				( attribute "ROOM" "M_2"
					( Origin gFrontEnd )
				)
				( attribute "ROT" "0"
					( Origin gFrontEnd )
				)
				( attribute "SEC" "1"
					( Origin gFrontEnd )
				)
				( attribute "SEC_TYPE" "0402V"
					( Origin gFrontEnd )
				)
				( attribute "TOLERANCE" "10%"
					( Origin gFrontEnd )
				)
				( attribute "VALUE" "0.1UF"
					( Origin gFrontEnd )
				)
				( attribute "VER" "1"
					( Origin gFrontEnd )
				)
				( attribute "VOLTAGE" "16V"
					( Units "uVoltage" "V" 1.000000)
					( Origin gFrontEnd )
				)
				( attribute "XY" "(-1650,3650)"
					( Origin gFrontEnd )
				)
				( attribute "CHIPS_PART_NAME" "CAP_A"
					( Origin gPackager )
				)
				( attribute "CDS_PART_NAME" "CAP_A_0402V-0.1UF,16V,10%,X7R,A"
					( Origin gPackager )
				)
				( objectStatus "C2T24" )
				( pin "a"
					( attribute "PN" "1"
						( Origin gPackager )
					)
					( objectStatus "C2T24.1" )
				)
				( pin "b"
					( attribute "PN" "2"
						( Origin gPackager )
					)
					( objectStatus "C2T24.2" )
				)
			)
			( gate "@baseboard_fab2_lib.baseboard_fab2(sch_1):page185_i131"
				( attribute "BOM_COST" "SD_FLASH"
					( Origin gFrontEnd )
				)
				( attribute "CDS_LIB" "dev_discrete"
					( Origin gPackager )
				)
				( attribute "CDS_LOCATION" "C2T2"
					( Origin gPackager )
				)
				( attribute "CDS_SEC" "1"
					( Origin gPackager )
				)
				( attribute "LOCATION" "C2T2"
					( Origin gFrontEnd )
				)
				( attribute "MATERIAL" "X7R"
					( Origin gFrontEnd )
				)
				( attribute "PACK_TYPE" "0402V"
					( Origin gFrontEnd )
				)
				( attribute "PART_NUMBER" "A36096-030"
					( Origin gFrontEnd )
				)
				( attribute "PHYS_PAGE" "185"
					( Origin gFrontEnd )
				)
				( attribute "ROOM" "M_2"
					( Origin gFrontEnd )
				)
				( attribute "ROT" "0"
					( Origin gFrontEnd )
				)
				( attribute "SEC" "1"
					( Origin gFrontEnd )
				)
				( attribute "SEC_TYPE" "0402V"
					( Origin gFrontEnd )
				)
				( attribute "TOLERANCE" "10%"
					( Origin gFrontEnd )
				)
				( attribute "VALUE" "0.1UF"
					( Origin gFrontEnd )
				)
				( attribute "VER" "1"
					( Origin gFrontEnd )
				)
				( attribute "VOLTAGE" "16V"
					( Units "uVoltage" "V" 1.000000)
					( Origin gFrontEnd )
				)
				( attribute "XY" "(-1150,2800)"
					( Origin gFrontEnd )
				)
				( attribute "CHIPS_PART_NAME" "CAP_A"
					( Origin gPackager )
				)
				( attribute "CDS_PART_NAME" "CAP_A_0402V-0.1UF,16V,10%,X7R,A"
					( Origin gPackager )
				)
				( objectStatus "C2T2" )
				( pin "a"
					( attribute "PN" "1"
						( Origin gPackager )
					)
					( objectStatus "C2T2.1" )
				)
				( pin "b"
					( attribute "PN" "2"
						( Origin gPackager )
					)
					( objectStatus "C2T2.2" )
				)
			)
			( gate "@baseboard_fab2_lib.baseboard_fab2(sch_1):page185_i132"
				( attribute "BOM_COST" "SD_FLASH"
					( Origin gFrontEnd )
				)
				( attribute "CDS_LIB" "dev_discrete"
					( Origin gPackager )
				)
				( attribute "CDS_LOCATION" "C2T4"
					( Origin gPackager )
				)
				( attribute "CDS_SEC" "1"
					( Origin gPackager )
				)
				( attribute "LOCATION" "C2T4"
					( Origin gFrontEnd )
				)
				( attribute "MATERIAL" "X7R"
					( Origin gFrontEnd )
				)
				( attribute "PACK_TYPE" "0402V"
					( Origin gFrontEnd )
				)
				( attribute "PART_NUMBER" "A36096-030"
					( Origin gFrontEnd )
				)
				( attribute "PHYS_PAGE" "185"
					( Origin gFrontEnd )
				)
				( attribute "ROOM" "M_2"
					( Origin gFrontEnd )
				)
				( attribute "ROT" "0"
					( Origin gFrontEnd )
				)
				( attribute "SEC" "1"
					( Origin gFrontEnd )
				)
				( attribute "SEC_TYPE" "0402V"
					( Origin gFrontEnd )
				)
				( attribute "TOLERANCE" "10%"
					( Origin gFrontEnd )
				)
				( attribute "VALUE" "0.1UF"
					( Origin gFrontEnd )
				)
				( attribute "VER" "1"
					( Origin gFrontEnd )
				)
				( attribute "VOLTAGE" "16V"
					( Units "uVoltage" "V" 1.000000)
					( Origin gFrontEnd )
				)
				( attribute "XY" "(-1400,2800)"
					( Origin gFrontEnd )
				)
				( attribute "CHIPS_PART_NAME" "CAP_A"
					( Origin gPackager )
				)
				( attribute "CDS_PART_NAME" "CAP_A_0402V-0.1UF,16V,10%,X7R,A"
					( Origin gPackager )
				)
				( objectStatus "C2T4" )
				( pin "a"
					( attribute "PN" "1"
						( Origin gPackager )
					)
					( objectStatus "C2T4.1" )
				)
				( pin "b"
					( attribute "PN" "2"
						( Origin gPackager )
					)
					( objectStatus "C2T4.2" )
				)
			)
			( gate "@baseboard_fab2_lib.baseboard_fab2(sch_1):page185_i135"
				( attribute "BOM_COST" "SD_FLASH"
					( Origin gFrontEnd )
				)
				( attribute "CDS_LIB" "dev_discrete"
					( Origin gPackager )
				)
				( attribute "CDS_LOCATION" "C2T5"
					( Origin gPackager )
				)
				( attribute "CDS_SEC" "1"
					( Origin gPackager )
				)
				( attribute "LOCATION" "C2T5"
					( Origin gFrontEnd )
				)
				( attribute "MATERIAL" "X7R"
					( Origin gFrontEnd )
				)
				( attribute "PACK_TYPE" "0402V"
					( Origin gFrontEnd )
				)
				( attribute "PART_NUMBER" "A36096-030"
					( Origin gFrontEnd )
				)
				( attribute "PHYS_PAGE" "185"
					( Origin gFrontEnd )
				)
				( attribute "ROOM" "M_2"
					( Origin gFrontEnd )
				)
				( attribute "ROT" "0"
					( Origin gFrontEnd )
				)
				( attribute "SEC" "1"
					( Origin gFrontEnd )
				)
				( attribute "SEC_TYPE" "0402V"
					( Origin gFrontEnd )
				)
				( attribute "TOLERANCE" "10%"
					( Origin gFrontEnd )
				)
				( attribute "VALUE" "0.1UF"
					( Origin gFrontEnd )
				)
				( attribute "VER" "1"
					( Origin gFrontEnd )
				)
				( attribute "VOLTAGE" "16V"
					( Units "uVoltage" "V" 1.000000)
					( Origin gFrontEnd )
				)
				( attribute "XY" "(-1650,2800)"
					( Origin gFrontEnd )
				)
				( attribute "CHIPS_PART_NAME" "CAP_A"
					( Origin gPackager )
				)
				( attribute "CDS_PART_NAME" "CAP_A_0402V-0.1UF,16V,10%,X7R,A"
					( Origin gPackager )
				)
				( objectStatus "C2T5" )
				( pin "a"
					( attribute "PN" "1"
						( Origin gPackager )
					)
					( objectStatus "C2T5.1" )
				)
				( pin "b"
					( attribute "PN" "2"
						( Origin gPackager )
					)
					( objectStatus "C2T5.2" )
				)
			)
			( gate "@baseboard_fab2_lib.baseboard_fab2(sch_1):page185_i136"
				( attribute "BOM_COST" "ST_FLASH"
					( Origin gFrontEnd )
				)
				( attribute "CDS_LIB" "mstr_discrete"
					( Origin gPackager )
				)
				( attribute "CDS_LOCATION" "R8F36"
					( Origin gPackager )
				)
				( attribute "CDS_SEC" "1"
					( Origin gPackager )
				)
				( attribute "LOCATION" "R8F36"
					( Origin gFrontEnd )
				)
				( attribute "MATERIAL" "CHIP"
					( Origin gFrontEnd )
				)
				( attribute "PACK_TYPE" "0402"
					( Origin gFrontEnd )
				)
				( attribute "PART_NUMBER" "G21796-016"
					( Origin gFrontEnd )
				)
				( attribute "PHYS_PAGE" "185"
					( Origin gFrontEnd )
				)
				( attribute "ROOM" "M_2"
					( Origin gFrontEnd )
				)
				( attribute "ROT" "0"
					( Origin gFrontEnd )
				)
				( attribute "SEC" "1"
					( Origin gFrontEnd )
				)
				( attribute "SEC_TYPE" "0402"
					( Origin gFrontEnd )
				)
				( attribute "TOLERANCE" "1%"
					( Origin gFrontEnd )
				)
				( attribute "VALUE" "10.0K"
					( Origin gFrontEnd )
				)
				( attribute "VER" "2"
					( Origin gFrontEnd )
				)
				( attribute "WATTAGE" "1/16W"
					( Origin gFrontEnd )
				)
				( attribute "XY" "(-3300,3300)"
					( Origin gFrontEnd )
				)
				( attribute "CHIPS_PART_NAME" "RES"
					( Origin gPackager )
				)
				( attribute "CDS_PART_NAME" "RES_0402-10.0K,1%,1/16W,CHIP,GA"
					( Origin gPackager )
				)
				( objectStatus "R8F36" )
				( pin "a"
					( attribute "PN" "1"
						( Origin gPackager )
					)
					( objectStatus "R8F36.1" )
				)
				( pin "b"
					( attribute "PN" "2"
						( Origin gPackager )
					)
					( objectStatus "R8F36.2" )
				)
			)
			( gate "@baseboard_fab2_lib.baseboard_fab2(sch_1):page186_i3"
				( attribute "CDS_LIB" "mstr_discrete"
					( Origin gPackager )
				)
				( attribute "CDS_LOCATION" "C1M27"
					( Origin gPackager )
				)
				( attribute "CDS_SEC" "1"
					( Origin gPackager )
				)
				( attribute "LOCATION" "C1M27"
					( Origin gFrontEnd )
				)
				( attribute "MATERIAL" "X6S"
					( Origin gFrontEnd )
				)
				( attribute "PACK_TYPE" "0805"
					( Origin gFrontEnd )
				)
				( attribute "PART_NUMBER" "C95333-007"
					( Origin gFrontEnd )
				)
				( attribute "PHYS_PAGE" "186"
					( Origin gFrontEnd )
				)
				( attribute "ROOM" "IO_SLOT"
					( Origin gFrontEnd )
				)
				( attribute "ROT" "0"
					( Origin gFrontEnd )
				)
				( attribute "SEC" "1"
					( Origin gFrontEnd )
				)
				( attribute "SEC_TYPE" "0805"
					( Origin gFrontEnd )
				)
				( attribute "TOLERANCE" "10%"
					( Origin gFrontEnd )
				)
				( attribute "VALUE" "10UF"
					( Origin gFrontEnd )
				)
				( attribute "VER" "1"
					( Origin gFrontEnd )
				)
				( attribute "VOLTAGE" "16V"
					( Units "uVoltage" "V" 1.000000)
					( Origin gFrontEnd )
				)
				( attribute "XY" "(10450,3975)"
					( Origin gFrontEnd )
				)
				( attribute "CHIPS_PART_NAME" "CAP"
					( Origin gPackager )
				)
				( attribute "CDS_PART_NAME" "CAP_0805-10UF,16V,10%,X6S,C953A"
					( Origin gPackager )
				)
				( objectStatus "C1M27" )
				( pin "a"
					( attribute "PN" "1"
						( Origin gPackager )
					)
					( objectStatus "C1M27.1" )
				)
				( pin "b"
					( attribute "PN" "2"
						( Origin gPackager )
					)
					( objectStatus "C1M27.2" )
				)
			)
			( gate "@baseboard_fab2_lib.baseboard_fab2(sch_1):page186_i6"
				( attribute "CDS_LIB" "mstr_discrete"
					( Origin gPackager )
				)
				( attribute "CDS_LOCATION" "C1M26"
					( Origin gPackager )
				)
				( attribute "CDS_SEC" "1"
					( Origin gPackager )
				)
				( attribute "LOCATION" "C1M26"
					( Origin gFrontEnd )
				)
				( attribute "MATERIAL" "X6S"
					( Origin gFrontEnd )
				)
				( attribute "PACK_TYPE" "0805"
					( Origin gFrontEnd )
				)
				( attribute "PART_NUMBER" "C95333-007"
					( Origin gFrontEnd )
				)
				( attribute "PHYS_PAGE" "186"
					( Origin gFrontEnd )
				)
				( attribute "ROOM" "IO_SLOT"
					( Origin gFrontEnd )
				)
				( attribute "ROT" "0"
					( Origin gFrontEnd )
				)
				( attribute "SEC" "1"
					( Origin gFrontEnd )
				)
				( attribute "SEC_TYPE" "0805"
					( Origin gFrontEnd )
				)
				( attribute "TOLERANCE" "10%"
					( Origin gFrontEnd )
				)
				( attribute "VALUE" "10UF"
					( Origin gFrontEnd )
				)
				( attribute "VER" "1"
					( Origin gFrontEnd )
				)
				( attribute "VOLTAGE" "16V"
					( Units "uVoltage" "V" 1.000000)
					( Origin gFrontEnd )
				)
				( attribute "XY" "(10850,3950)"
					( Origin gFrontEnd )
				)
				( attribute "CHIPS_PART_NAME" "CAP"
					( Origin gPackager )
				)
				( attribute "CDS_PART_NAME" "CAP_0805-10UF,16V,10%,X6S,C953A"
					( Origin gPackager )
				)
				( objectStatus "C1M26" )
				( pin "a"
					( attribute "PN" "1"
						( Origin gPackager )
					)
					( objectStatus "C1M26.1" )
				)
				( pin "b"
					( attribute "PN" "2"
						( Origin gPackager )
					)
					( objectStatus "C1M26.2" )
				)
			)
			( gate "@baseboard_fab2_lib.baseboard_fab2(sch_1):page186_i7"
				( attribute "CDS_LIB" "dev_discrete"
					( Origin gPackager )
				)
				( attribute "CDS_LOCATION" "C1M23"
					( Origin gPackager )
				)
				( attribute "CDS_SEC" "1"
					( Origin gPackager )
				)
				( attribute "LOCATION" "C1M23"
					( Origin gFrontEnd )
				)
				( attribute "MATERIAL" "X7R"
					( Origin gFrontEnd )
				)
				( attribute "PACK_TYPE" "0402V"
					( Origin gFrontEnd )
				)
				( attribute "PART_NUMBER" "A36096-030"
					( Origin gFrontEnd )
				)
				( attribute "PHYS_PAGE" "186"
					( Origin gFrontEnd )
				)
				( attribute "ROOM" "IO_SLOT"
					( Origin gFrontEnd )
				)
				( attribute "ROT" "0"
					( Origin gFrontEnd )
				)
				( attribute "SEC" "1"
					( Origin gFrontEnd )
				)
				( attribute "SEC_TYPE" "0402V"
					( Origin gFrontEnd )
				)
				( attribute "TOLERANCE" "10%"
					( Origin gFrontEnd )
				)
				( attribute "VALUE" "0.1UF"
					( Origin gFrontEnd )
				)
				( attribute "VER" "1"
					( Origin gFrontEnd )
				)
				( attribute "VOLTAGE" "16V"
					( Units "uVoltage" "V" 1.000000)
					( Origin gFrontEnd )
				)
				( attribute "XY" "(11225,3950)"
					( Origin gFrontEnd )
				)
				( attribute "CHIPS_PART_NAME" "CAP_A"
					( Origin gPackager )
				)
				( attribute "CDS_PART_NAME" "CAP_A_0402V-0.1UF,16V,10%,X7R,A"
					( Origin gPackager )
				)
				( objectStatus "C1M23" )
				( pin "a"
					( attribute "PN" "1"
						( Origin gPackager )
					)
					( objectStatus "C1M23.1" )
				)
				( pin "b"
					( attribute "PN" "2"
						( Origin gPackager )
					)
					( objectStatus "C1M23.2" )
				)
			)
			( gate "@baseboard_fab2_lib.baseboard_fab2(sch_1):page186_i8"
				( attribute "CDS_LIB" "dev_discrete"
					( Origin gPackager )
				)
				( attribute "CDS_LOCATION" "C1M22"
					( Origin gPackager )
				)
				( attribute "CDS_SEC" "1"
					( Origin gPackager )
				)
				( attribute "LOCATION" "C1M22"
					( Origin gFrontEnd )
				)
				( attribute "MATERIAL" "X7R"
					( Origin gFrontEnd )
				)
				( attribute "PACK_TYPE" "0402V"
					( Origin gFrontEnd )
				)
				( attribute "PART_NUMBER" "A36096-030"
					( Origin gFrontEnd )
				)
				( attribute "PHYS_PAGE" "186"
					( Origin gFrontEnd )
				)
				( attribute "ROOM" "IO_SLOT"
					( Origin gFrontEnd )
				)
				( attribute "ROT" "0"
					( Origin gFrontEnd )
				)
				( attribute "SEC" "1"
					( Origin gFrontEnd )
				)
				( attribute "SEC_TYPE" "0402V"
					( Origin gFrontEnd )
				)
				( attribute "TOLERANCE" "10%"
					( Origin gFrontEnd )
				)
				( attribute "VALUE" "0.1UF"
					( Origin gFrontEnd )
				)
				( attribute "VER" "1"
					( Origin gFrontEnd )
				)
				( attribute "VOLTAGE" "16V"
					( Units "uVoltage" "V" 1.000000)
					( Origin gFrontEnd )
				)
				( attribute "XY" "(11650,3950)"
					( Origin gFrontEnd )
				)
				( attribute "CHIPS_PART_NAME" "CAP_A"
					( Origin gPackager )
				)
				( attribute "CDS_PART_NAME" "CAP_A_0402V-0.1UF,16V,10%,X7R,A"
					( Origin gPackager )
				)
				( objectStatus "C1M22" )
				( pin "a"
					( attribute "PN" "1"
						( Origin gPackager )
					)
					( objectStatus "C1M22.1" )
				)
				( pin "b"
					( attribute "PN" "2"
						( Origin gPackager )
					)
					( objectStatus "C1M22.2" )
				)
			)
			( gate "@baseboard_fab2_lib.baseboard_fab2(sch_1):page186_i10"
				( attribute "CDS_LIB" "dev_discrete"
					( Origin gPackager )
				)
				( attribute "CDS_LOCATION" "C1M24"
					( Origin gPackager )
				)
				( attribute "CDS_SEC" "1"
					( Origin gPackager )
				)
				( attribute "LOCATION" "C1M24"
					( Origin gFrontEnd )
				)
				( attribute "MATERIAL" "X7R"
					( Origin gFrontEnd )
				)
				( attribute "PACK_TYPE" "0402V"
					( Origin gFrontEnd )
				)
				( attribute "PART_NUMBER" "A36096-030"
					( Origin gFrontEnd )
				)
				( attribute "PHYS_PAGE" "186"
					( Origin gFrontEnd )
				)
				( attribute "ROOM" "IO_SLOT"
					( Origin gFrontEnd )
				)
				( attribute "ROT" "0"
					( Origin gFrontEnd )
				)
				( attribute "SEC" "1"
					( Origin gFrontEnd )
				)
				( attribute "SEC_TYPE" "0402V"
					( Origin gFrontEnd )
				)
				( attribute "TOLERANCE" "10%"
					( Origin gFrontEnd )
				)
				( attribute "VALUE" "0.1UF"
					( Origin gFrontEnd )
				)
				( attribute "VER" "1"
					( Origin gFrontEnd )
				)
				( attribute "VOLTAGE" "16V"
					( Units "uVoltage" "V" 1.000000)
					( Origin gFrontEnd )
				)
				( attribute "XY" "(10850,4675)"
					( Origin gFrontEnd )
				)
				( attribute "CHIPS_PART_NAME" "CAP_A"
					( Origin gPackager )
				)
				( attribute "CDS_PART_NAME" "CAP_A_0402V-0.1UF,16V,10%,X7R,A"
					( Origin gPackager )
				)
				( objectStatus "C1M24" )
				( pin "a"
					( attribute "PN" "1"
						( Origin gPackager )
					)
					( objectStatus "C1M24.1" )
				)
				( pin "b"
					( attribute "PN" "2"
						( Origin gPackager )
					)
					( objectStatus "C1M24.2" )
				)
			)
			( gate "@baseboard_fab2_lib.baseboard_fab2(sch_1):page186_i220"
				( attribute "CDS_LIB" "mstr_discrete"
					( Origin gPackager )
				)
				( attribute "CDS_LOCATION" "R1M14"
					( Origin gPackager )
				)
				( attribute "CDS_SEC" "1"
					( Origin gPackager )
				)
				( attribute "LOCATION" "R1M14"
					( Origin gFrontEnd )
				)
				( attribute "MATERIAL" "CHIP"
					( Origin gFrontEnd )
				)
				( attribute "PACK_TYPE" "0402"
					( Origin gFrontEnd )
				)
				( attribute "PART_NUMBER" "G21796-004"
					( Origin gFrontEnd )
				)
				( attribute "PHYS_PAGE" "186"
					( Origin gFrontEnd )
				)
				( attribute "ROOM" "IO_SLOT"
					( Origin gFrontEnd )
				)
				( attribute "ROT" "0"
					( Origin gFrontEnd )
				)
				( attribute "SEC" "1"
					( Origin gFrontEnd )
				)
				( attribute "SEC_TYPE" "0402"
					( Origin gFrontEnd )
				)
				( attribute "TOLERANCE" "1%"
					( Origin gFrontEnd )
				)
				( attribute "VALUE" "200.0"
					( Origin gFrontEnd )
				)
				( attribute "VER" "1"
					( Origin gFrontEnd )
				)
				( attribute "WATTAGE" "1/16W"
					( Origin gFrontEnd )
				)
				( attribute "XY" "(6000,3050)"
					( Origin gFrontEnd )
				)
				( attribute "CHIPS_PART_NAME" "RES"
					( Origin gPackager )
				)
				( attribute "CDS_PART_NAME" "RES_0402-200.0,1%,1/16W,CHIP,GA"
					( Origin gPackager )
				)
				( objectStatus "R1M14" )
				( pin "a"
					( attribute "PN" "1"
						( Origin gPackager )
					)
					( objectStatus "R1M14.1" )
				)
				( pin "b"
					( attribute "PN" "2"
						( Origin gPackager )
					)
					( objectStatus "R1M14.2" )
				)
			)
			( gate "@baseboard_fab2_lib.baseboard_fab2(sch_1):page186_i222"
				( attribute "CDS_LIB" "mstr_discrete"
					( Origin gPackager )
				)
				( attribute "CDS_LOCATION" "R9B7"
					( Origin gPackager )
				)
				( attribute "CDS_SEC" "1"
					( Origin gPackager )
				)
				( attribute "LOCATION" "R9B7"
					( Origin gFrontEnd )
				)
				( attribute "MATERIAL" "CHIP"
					( Origin gFrontEnd )
				)
				( attribute "PACK_TYPE" "0402"
					( Origin gFrontEnd )
				)
				( attribute "PART_NUMBER" "G21796-017"
					( Origin gFrontEnd )
				)
				( attribute "PHYS_PAGE" "186"
					( Origin gFrontEnd )
				)
				( attribute "ROOM" "IO_SLOT"
					( Origin gFrontEnd )
				)
				( attribute "ROT" "0"
					( Origin gFrontEnd )
				)
				( attribute "SEC" "1"
					( Origin gFrontEnd )
				)
				( attribute "SEC_TYPE" "0402"
					( Origin gFrontEnd )
				)
				( attribute "TOLERANCE" "1%"
					( Origin gFrontEnd )
				)
				( attribute "VALUE" "100.0"
					( Origin gFrontEnd )
				)
				( attribute "VER" "1"
					( Origin gFrontEnd )
				)
				( attribute "WATTAGE" "1/16W"
					( Origin gFrontEnd )
				)
				( attribute "XY" "(6500,3850)"
					( Origin gFrontEnd )
				)
				( attribute "CHIPS_PART_NAME" "RES"
					( Origin gPackager )
				)
				( attribute "CDS_PART_NAME" "RES_0402-100.0,1%,1/16W,CHIP,GA"
					( Origin gPackager )
				)
				( objectStatus "R9B7" )
				( pin "a"
					( attribute "PN" "1"
						( Origin gPackager )
					)
					( objectStatus "R9B7.1" )
				)
				( pin "b"
					( attribute "PN" "2"
						( Origin gPackager )
					)
					( objectStatus "R9B7.2" )
				)
			)
			( gate "@baseboard_fab2_lib.baseboard_fab2(sch_1):page186_i270"
				( attribute "CDS_LIB" "dev_discrete"
					( Origin gPackager )
				)
				( attribute "CDS_LOCATION" "C1M20"
					( Origin gPackager )
				)
				( attribute "CDS_SEC" "1"
					( Origin gPackager )
				)
				( attribute "LOCATION" "C1M20"
					( Origin gFrontEnd )
				)
				( attribute "MATERIAL" "X7R"
					( Origin gFrontEnd )
				)
				( attribute "PACK_TYPE" "0402V"
					( Origin gFrontEnd )
				)
				( attribute "PART_NUMBER" "A36096-030"
					( Origin gFrontEnd )
				)
				( attribute "PHYS_PAGE" "186"
					( Origin gFrontEnd )
				)
				( attribute "ROOM" "IO_SLOT"
					( Origin gFrontEnd )
				)
				( attribute "ROT" "0"
					( Origin gFrontEnd )
				)
				( attribute "SEC" "1"
					( Origin gPackager )
				)
				( attribute "TOLERANCE" "10%"
					( Origin gFrontEnd )
				)
				( attribute "VALUE" "0.1UF"
					( Origin gFrontEnd )
				)
				( attribute "VER" "1"
					( Origin gFrontEnd )
				)
				( attribute "VOLTAGE" "16V"
					( Units "uVoltage" "V" 1.000000)
					( Origin gFrontEnd )
				)
				( attribute "XY" "(11650,4675)"
					( Origin gFrontEnd )
				)
				( attribute "CHIPS_PART_NAME" "CAP_A"
					( Origin gPackager )
				)
				( attribute "CDS_PART_NAME" "CAP_A_0402V-0.1UF,16V,10%,X7R,A"
					( Origin gPackager )
				)
				( objectStatus "C1M20" )
				( pin "a"
					( attribute "PN" "1"
						( Origin gPackager )
					)
					( objectStatus "C1M20.1" )
				)
				( pin "b"
					( attribute "PN" "2"
						( Origin gPackager )
					)
					( objectStatus "C1M20.2" )
				)
			)
			( gate "@baseboard_fab2_lib.baseboard_fab2(sch_1):page186_i334"
				( attribute "CDS_LIB" "dev_discrete"
					( Origin gPackager )
				)
				( attribute "CDS_LOCATION" "C1M21"
					( Origin gPackager )
				)
				( attribute "CDS_SEC" "1"
					( Origin gPackager )
				)
				( attribute "LOCATION" "C1M21"
					( Origin gFrontEnd )
				)
				( attribute "MATERIAL" "X6S"
					( Origin gFrontEnd )
				)
				( attribute "PACK_TYPE" "0402V"
					( Origin gFrontEnd )
				)
				( attribute "PART_NUMBER" "D97712-004"
					( Origin gFrontEnd )
				)
				( attribute "PHYS_PAGE" "186"
					( Origin gFrontEnd )
				)
				( attribute "ROOM" "IO_SLOT"
					( Origin gFrontEnd )
				)
				( attribute "ROT" "0"
					( Origin gFrontEnd )
				)
				( attribute "SEC" "1"
					( Origin gFrontEnd )
				)
				( attribute "SEC_TYPE" "0402V"
					( Origin gFrontEnd )
				)
				( attribute "TOLERANCE" "10%"
					( Origin gFrontEnd )
				)
				( attribute "VALUE" "1.0UF"
					( Origin gFrontEnd )
				)
				( attribute "VER" "1"
					( Origin gFrontEnd )
				)
				( attribute "VOLTAGE" "6.3V"
					( Units "uVoltage" "V" 1.000000)
					( Origin gFrontEnd )
				)
				( attribute "XY" "(10450,4700)"
					( Origin gFrontEnd )
				)
				( attribute "CHIPS_PART_NAME" "CAP_A"
					( Origin gPackager )
				)
				( attribute "CDS_PART_NAME" "CAP_A_0402V-1.0UF,6.3V,10%,X6SA"
					( Origin gPackager )
				)
				( objectStatus "C1M21" )
				( pin "a"
					( attribute "PN" "1"
						( Origin gPackager )
					)
					( objectStatus "C1M21.1" )
				)
				( pin "b"
					( attribute "PN" "2"
						( Origin gPackager )
					)
					( objectStatus "C1M21.2" )
				)
			)
			( gate "@baseboard_fab2_lib.baseboard_fab2(sch_1):page186_i335"
				( attribute "CDS_LIB" "dev_discrete"
					( Origin gPackager )
				)
				( attribute "CDS_LOCATION" "C1M25"
					( Origin gPackager )
				)
				( attribute "CDS_SEC" "1"
					( Origin gPackager )
				)
				( attribute "LOCATION" "C1M25"
					( Origin gFrontEnd )
				)
				( attribute "MATERIAL" "X6S"
					( Origin gFrontEnd )
				)
				( attribute "PACK_TYPE" "0402V"
					( Origin gFrontEnd )
				)
				( attribute "PART_NUMBER" "D97712-004"
					( Origin gFrontEnd )
				)
				( attribute "PHYS_PAGE" "186"
					( Origin gFrontEnd )
				)
				( attribute "ROOM" "IO_SLOT"
					( Origin gFrontEnd )
				)
				( attribute "ROT" "0"
					( Origin gFrontEnd )
				)
				( attribute "SEC" "1"
					( Origin gFrontEnd )
				)
				( attribute "SEC_TYPE" "0402V"
					( Origin gFrontEnd )
				)
				( attribute "TOLERANCE" "10%"
					( Origin gFrontEnd )
				)
				( attribute "VALUE" "1.0UF"
					( Origin gFrontEnd )
				)
				( attribute "VER" "1"
					( Origin gFrontEnd )
				)
				( attribute "VOLTAGE" "6.3V"
					( Units "uVoltage" "V" 1.000000)
					( Origin gFrontEnd )
				)
				( attribute "XY" "(11250,4700)"
					( Origin gFrontEnd )
				)
				( attribute "CHIPS_PART_NAME" "CAP_A"
					( Origin gPackager )
				)
				( attribute "CDS_PART_NAME" "CAP_A_0402V-1.0UF,6.3V,10%,X6SA"
					( Origin gPackager )
				)
				( objectStatus "C1M25" )
				( pin "a"
					( attribute "PN" "1"
						( Origin gPackager )
					)
					( objectStatus "C1M25.1" )
				)
				( pin "b"
					( attribute "PN" "2"
						( Origin gPackager )
					)
					( objectStatus "C1M25.2" )
				)
			)
			( gate "@baseboard_fab2_lib.baseboard_fab2(sch_1):page186_i336"
				( attribute "CDS_LIB" "mstr_sconn"
					( Origin gPackager )
				)
				( attribute "CDS_LOCATION" "J9B3"
					( Origin gPackager )
				)
				( attribute "CDS_SEC" "1"
					( Origin gPackager )
				)
				( attribute "LOCATION" "J9B3"
					( Origin gFrontEnd )
				)
				( attribute "MATERIAL" "SCONN"
					( Origin gFrontEnd )
				)
				( attribute "PACK_TYPE" "SM"
					( Origin gFrontEnd )
				)
				( attribute "PART_NUMBER" "A28699-018"
					( Origin gFrontEnd )
				)
				( attribute "PHYS_PAGE" "186"
					( Origin gFrontEnd )
				)
				( attribute "ROOM" "IO_SLOT"
					( Origin gFrontEnd )
				)
				( attribute "ROT" "0"
					( Origin gFrontEnd )
				)
				( attribute "SEC" "1"
					( Origin gFrontEnd )
				)
				( attribute "SEC_TYPE" "SM"
					( Origin gFrontEnd )
				)
				( attribute "VER" "1"
					( Origin gFrontEnd )
				)
				( attribute "XY" "(8250,2350)"
					( Origin gFrontEnd )
				)
				( attribute "CHIPS_PART_NAME" "SCONN120_A28699018"
					( Origin gPackager )
				)
				( attribute "CDS_PART_NAME" "SCONN120_A28699018_SM-SCONN,A2A"
					( Origin gPackager )
				)
				( objectStatus "J9B3" )
				( pin "io1"
					( attribute "PN" "1"
						( Origin gPackager )
					)
					( objectStatus "J9B3.1" )
				)
				( pin "io2"
					( attribute "PN" "2"
						( Origin gPackager )
					)
					( objectStatus "J9B3.2" )
				)
				( pin "io3"
					( attribute "PN" "3"
						( Origin gPackager )
					)
					( objectStatus "J9B3.3" )
				)
				( pin "io4"
					( attribute "PN" "4"
						( Origin gPackager )
					)
					( objectStatus "J9B3.4" )
				)
				( pin "io5"
					( attribute "PN" "5"
						( Origin gPackager )
					)
					( objectStatus "J9B3.5" )
				)
				( pin "io6"
					( attribute "PN" "6"
						( Origin gPackager )
					)
					( objectStatus "J9B3.6" )
				)
				( pin "io7"
					( attribute "PN" "7"
						( Origin gPackager )
					)
					( objectStatus "J9B3.7" )
				)
				( pin "io8"
					( attribute "PN" "8"
						( Origin gPackager )
					)
					( objectStatus "J9B3.8" )
				)
				( pin "io9"
					( attribute "PN" "9"
						( Origin gPackager )
					)
					( objectStatus "J9B3.9" )
				)
				( pin "io10"
					( attribute "PN" "10"
						( Origin gPackager )
					)
					( objectStatus "J9B3.10" )
				)
				( pin "io11"
					( attribute "PN" "11"
						( Origin gPackager )
					)
					( objectStatus "J9B3.11" )
				)
				( pin "io12"
					( attribute "PN" "12"
						( Origin gPackager )
					)
					( objectStatus "J9B3.12" )
				)
				( pin "io13"
					( attribute "PN" "13"
						( Origin gPackager )
					)
					( objectStatus "J9B3.13" )
				)
				( pin "io14"
					( attribute "PN" "14"
						( Origin gPackager )
					)
					( objectStatus "J9B3.14" )
				)
				( pin "io15"
					( attribute "PN" "15"
						( Origin gPackager )
					)
					( objectStatus "J9B3.15" )
				)
				( pin "io16"
					( attribute "PN" "16"
						( Origin gPackager )
					)
					( objectStatus "J9B3.16" )
				)
				( pin "io17"
					( attribute "PN" "17"
						( Origin gPackager )
					)
					( objectStatus "J9B3.17" )
				)
				( pin "io18"
					( attribute "PN" "18"
						( Origin gPackager )
					)
					( objectStatus "J9B3.18" )
				)
				( pin "io19"
					( attribute "PN" "19"
						( Origin gPackager )
					)
					( objectStatus "J9B3.19" )
				)
				( pin "io20"
					( attribute "PN" "20"
						( Origin gPackager )
					)
					( objectStatus "J9B3.20" )
				)
				( pin "io21"
					( attribute "PN" "21"
						( Origin gPackager )
					)
					( objectStatus "J9B3.21" )
				)
				( pin "io22"
					( attribute "PN" "22"
						( Origin gPackager )
					)
					( objectStatus "J9B3.22" )
				)
				( pin "io23"
					( attribute "PN" "23"
						( Origin gPackager )
					)
					( objectStatus "J9B3.23" )
				)
				( pin "io24"
					( attribute "PN" "24"
						( Origin gPackager )
					)
					( objectStatus "J9B3.24" )
				)
				( pin "io25"
					( attribute "PN" "25"
						( Origin gPackager )
					)
					( objectStatus "J9B3.25" )
				)
				( pin "io26"
					( attribute "PN" "26"
						( Origin gPackager )
					)
					( objectStatus "J9B3.26" )
				)
				( pin "io27"
					( attribute "PN" "27"
						( Origin gPackager )
					)
					( objectStatus "J9B3.27" )
				)
				( pin "io28"
					( attribute "PN" "28"
						( Origin gPackager )
					)
					( objectStatus "J9B3.28" )
				)
				( pin "io29"
					( attribute "PN" "29"
						( Origin gPackager )
					)
					( objectStatus "J9B3.29" )
				)
				( pin "io30"
					( attribute "PN" "30"
						( Origin gPackager )
					)
					( objectStatus "J9B3.30" )
				)
				( pin "io31"
					( attribute "PN" "31"
						( Origin gPackager )
					)
					( objectStatus "J9B3.31" )
				)
				( pin "io32"
					( attribute "PN" "32"
						( Origin gPackager )
					)
					( objectStatus "J9B3.32" )
				)
				( pin "io33"
					( attribute "PN" "33"
						( Origin gPackager )
					)
					( objectStatus "J9B3.33" )
				)
				( pin "io34"
					( attribute "PN" "34"
						( Origin gPackager )
					)
					( objectStatus "J9B3.34" )
				)
				( pin "io35"
					( attribute "PN" "35"
						( Origin gPackager )
					)
					( objectStatus "J9B3.35" )
				)
				( pin "io36"
					( attribute "PN" "36"
						( Origin gPackager )
					)
					( objectStatus "J9B3.36" )
				)
				( pin "io37"
					( attribute "PN" "37"
						( Origin gPackager )
					)
					( objectStatus "J9B3.37" )
				)
				( pin "io38"
					( attribute "PN" "38"
						( Origin gPackager )
					)
					( objectStatus "J9B3.38" )
				)
				( pin "io39"
					( attribute "PN" "39"
						( Origin gPackager )
					)
					( objectStatus "J9B3.39" )
				)
				( pin "io40"
					( attribute "PN" "40"
						( Origin gPackager )
					)
					( objectStatus "J9B3.40" )
				)
				( pin "io41"
					( attribute "PN" "41"
						( Origin gPackager )
					)
					( objectStatus "J9B3.41" )
				)
				( pin "io42"
					( attribute "PN" "42"
						( Origin gPackager )
					)
					( objectStatus "J9B3.42" )
				)
				( pin "io43"
					( attribute "PN" "43"
						( Origin gPackager )
					)
					( objectStatus "J9B3.43" )
				)
				( pin "io44"
					( attribute "PN" "44"
						( Origin gPackager )
					)
					( objectStatus "J9B3.44" )
				)
				( pin "io45"
					( attribute "PN" "45"
						( Origin gPackager )
					)
					( objectStatus "J9B3.45" )
				)
				( pin "io46"
					( attribute "PN" "46"
						( Origin gPackager )
					)
					( objectStatus "J9B3.46" )
				)
				( pin "io47"
					( attribute "PN" "47"
						( Origin gPackager )
					)
					( objectStatus "J9B3.47" )
				)
				( pin "io48"
					( attribute "PN" "48"
						( Origin gPackager )
					)
					( objectStatus "J9B3.48" )
				)
				( pin "io49"
					( attribute "PN" "49"
						( Origin gPackager )
					)
					( objectStatus "J9B3.49" )
				)
				( pin "io50"
					( attribute "PN" "50"
						( Origin gPackager )
					)
					( objectStatus "J9B3.50" )
				)
				( pin "io51"
					( attribute "PN" "51"
						( Origin gPackager )
					)
					( objectStatus "J9B3.51" )
				)
				( pin "io52"
					( attribute "PN" "52"
						( Origin gPackager )
					)
					( objectStatus "J9B3.52" )
				)
				( pin "io53"
					( attribute "PN" "53"
						( Origin gPackager )
					)
					( objectStatus "J9B3.53" )
				)
				( pin "io54"
					( attribute "PN" "54"
						( Origin gPackager )
					)
					( objectStatus "J9B3.54" )
				)
				( pin "io55"
					( attribute "PN" "55"
						( Origin gPackager )
					)
					( objectStatus "J9B3.55" )
				)
				( pin "io56"
					( attribute "PN" "56"
						( Origin gPackager )
					)
					( objectStatus "J9B3.56" )
				)
				( pin "io57"
					( attribute "PN" "57"
						( Origin gPackager )
					)
					( objectStatus "J9B3.57" )
				)
				( pin "io58"
					( attribute "PN" "58"
						( Origin gPackager )
					)
					( objectStatus "J9B3.58" )
				)
				( pin "io59"
					( attribute "PN" "59"
						( Origin gPackager )
					)
					( objectStatus "J9B3.59" )
				)
				( pin "io60"
					( attribute "PN" "60"
						( Origin gPackager )
					)
					( objectStatus "J9B3.60" )
				)
				( pin "io61"
					( attribute "PN" "61"
						( Origin gPackager )
					)
					( objectStatus "J9B3.61" )
				)
				( pin "io62"
					( attribute "PN" "62"
						( Origin gPackager )
					)
					( objectStatus "J9B3.62" )
				)
				( pin "io63"
					( attribute "PN" "63"
						( Origin gPackager )
					)
					( objectStatus "J9B3.63" )
				)
				( pin "io64"
					( attribute "PN" "64"
						( Origin gPackager )
					)
					( objectStatus "J9B3.64" )
				)
				( pin "io65"
					( attribute "PN" "65"
						( Origin gPackager )
					)
					( objectStatus "J9B3.65" )
				)
				( pin "io66"
					( attribute "PN" "66"
						( Origin gPackager )
					)
					( objectStatus "J9B3.66" )
				)
				( pin "io67"
					( attribute "PN" "67"
						( Origin gPackager )
					)
					( objectStatus "J9B3.67" )
				)
				( pin "io68"
					( attribute "PN" "68"
						( Origin gPackager )
					)
					( objectStatus "J9B3.68" )
				)
				( pin "io69"
					( attribute "PN" "69"
						( Origin gPackager )
					)
					( objectStatus "J9B3.69" )
				)
				( pin "io70"
					( attribute "PN" "70"
						( Origin gPackager )
					)
					( objectStatus "J9B3.70" )
				)
				( pin "io71"
					( attribute "PN" "71"
						( Origin gPackager )
					)
					( objectStatus "J9B3.71" )
				)
				( pin "io72"
					( attribute "PN" "72"
						( Origin gPackager )
					)
					( objectStatus "J9B3.72" )
				)
				( pin "io73"
					( attribute "PN" "73"
						( Origin gPackager )
					)
					( objectStatus "J9B3.73" )
				)
				( pin "io74"
					( attribute "PN" "74"
						( Origin gPackager )
					)
					( objectStatus "J9B3.74" )
				)
				( pin "io75"
					( attribute "PN" "75"
						( Origin gPackager )
					)
					( objectStatus "J9B3.75" )
				)
				( pin "io76"
					( attribute "PN" "76"
						( Origin gPackager )
					)
					( objectStatus "J9B3.76" )
				)
				( pin "io77"
					( attribute "PN" "77"
						( Origin gPackager )
					)
					( objectStatus "J9B3.77" )
				)
				( pin "io78"
					( attribute "PN" "78"
						( Origin gPackager )
					)
					( objectStatus "J9B3.78" )
				)
				( pin "io79"
					( attribute "PN" "79"
						( Origin gPackager )
					)
					( objectStatus "J9B3.79" )
				)
				( pin "io80"
					( attribute "PN" "80"
						( Origin gPackager )
					)
					( objectStatus "J9B3.80" )
				)
				( pin "io81"
					( attribute "PN" "81"
						( Origin gPackager )
					)
					( objectStatus "J9B3.81" )
				)
				( pin "io82"
					( attribute "PN" "82"
						( Origin gPackager )
					)
					( objectStatus "J9B3.82" )
				)
				( pin "io83"
					( attribute "PN" "83"
						( Origin gPackager )
					)
					( objectStatus "J9B3.83" )
				)
				( pin "io84"
					( attribute "PN" "84"
						( Origin gPackager )
					)
					( objectStatus "J9B3.84" )
				)
				( pin "io85"
					( attribute "PN" "85"
						( Origin gPackager )
					)
					( objectStatus "J9B3.85" )
				)
				( pin "io86"
					( attribute "PN" "86"
						( Origin gPackager )
					)
					( objectStatus "J9B3.86" )
				)
				( pin "io87"
					( attribute "PN" "87"
						( Origin gPackager )
					)
					( objectStatus "J9B3.87" )
				)
				( pin "io88"
					( attribute "PN" "88"
						( Origin gPackager )
					)
					( objectStatus "J9B3.88" )
				)
				( pin "io89"
					( attribute "PN" "89"
						( Origin gPackager )
					)
					( objectStatus "J9B3.89" )
				)
				( pin "io90"
					( attribute "PN" "90"
						( Origin gPackager )
					)
					( objectStatus "J9B3.90" )
				)
				( pin "io91"
					( attribute "PN" "91"
						( Origin gPackager )
					)
					( objectStatus "J9B3.91" )
				)
				( pin "io92"
					( attribute "PN" "92"
						( Origin gPackager )
					)
					( objectStatus "J9B3.92" )
				)
				( pin "io93"
					( attribute "PN" "93"
						( Origin gPackager )
					)
					( objectStatus "J9B3.93" )
				)
				( pin "io94"
					( attribute "PN" "94"
						( Origin gPackager )
					)
					( objectStatus "J9B3.94" )
				)
				( pin "io95"
					( attribute "PN" "95"
						( Origin gPackager )
					)
					( objectStatus "J9B3.95" )
				)
				( pin "io96"
					( attribute "PN" "96"
						( Origin gPackager )
					)
					( objectStatus "J9B3.96" )
				)
				( pin "io97"
					( attribute "PN" "97"
						( Origin gPackager )
					)
					( objectStatus "J9B3.97" )
				)
				( pin "io98"
					( attribute "PN" "98"
						( Origin gPackager )
					)
					( objectStatus "J9B3.98" )
				)
				( pin "io99"
					( attribute "PN" "99"
						( Origin gPackager )
					)
					( objectStatus "J9B3.99" )
				)
				( pin "io100"
					( attribute "PN" "100"
						( Origin gPackager )
					)
					( objectStatus "J9B3.100" )
				)
				( pin "io101"
					( attribute "PN" "101"
						( Origin gPackager )
					)
					( objectStatus "J9B3.101" )
				)
				( pin "io102"
					( attribute "PN" "102"
						( Origin gPackager )
					)
					( objectStatus "J9B3.102" )
				)
				( pin "io103"
					( attribute "PN" "103"
						( Origin gPackager )
					)
					( objectStatus "J9B3.103" )
				)
				( pin "io104"
					( attribute "PN" "104"
						( Origin gPackager )
					)
					( objectStatus "J9B3.104" )
				)
				( pin "io105"
					( attribute "PN" "105"
						( Origin gPackager )
					)
					( objectStatus "J9B3.105" )
				)
				( pin "io106"
					( attribute "PN" "106"
						( Origin gPackager )
					)
					( objectStatus "J9B3.106" )
				)
				( pin "io107"
					( attribute "PN" "107"
						( Origin gPackager )
					)
					( objectStatus "J9B3.107" )
				)
				( pin "io108"
					( attribute "PN" "108"
						( Origin gPackager )
					)
					( objectStatus "J9B3.108" )
				)
				( pin "io109"
					( attribute "PN" "109"
						( Origin gPackager )
					)
					( objectStatus "J9B3.109" )
				)
				( pin "io110"
					( attribute "PN" "110"
						( Origin gPackager )
					)
					( objectStatus "J9B3.110" )
				)
				( pin "io111"
					( attribute "PN" "111"
						( Origin gPackager )
					)
					( objectStatus "J9B3.111" )
				)
				( pin "io112"
					( attribute "PN" "112"
						( Origin gPackager )
					)
					( objectStatus "J9B3.112" )
				)
				( pin "io113"
					( attribute "PN" "113"
						( Origin gPackager )
					)
					( objectStatus "J9B3.113" )
				)
				( pin "io114"
					( attribute "PN" "114"
						( Origin gPackager )
					)
					( objectStatus "J9B3.114" )
				)
				( pin "io115"
					( attribute "PN" "115"
						( Origin gPackager )
					)
					( objectStatus "J9B3.115" )
				)
				( pin "io116"
					( attribute "PN" "116"
						( Origin gPackager )
					)
					( objectStatus "J9B3.116" )
				)
				( pin "io117"
					( attribute "PN" "117"
						( Origin gPackager )
					)
					( objectStatus "J9B3.117" )
				)
				( pin "io118"
					( attribute "PN" "118"
						( Origin gPackager )
					)
					( objectStatus "J9B3.118" )
				)
				( pin "io119"
					( attribute "PN" "119"
						( Origin gPackager )
					)
					( objectStatus "J9B3.119" )
				)
				( pin "io120"
					( attribute "PN" "120"
						( Origin gPackager )
					)
					( objectStatus "J9B3.120" )
				)
			)
			( gate "@baseboard_fab2_lib.baseboard_fab2(sch_1):page186_i337"
				( attribute "CDS_LIB" "mstr_discrete"
					( Origin gPackager )
				)
				( attribute "CDS_LOCATION" "R1M16"
					( Origin gPackager )
				)
				( attribute "CDS_SEC" "1"
					( Origin gPackager )
				)
				( attribute "LOCATION" "R1M16"
					( Origin gFrontEnd )
				)
				( attribute "MATERIAL" "CHIP"
					( Origin gFrontEnd )
				)
				( attribute "PACK_TYPE" "0402"
					( Origin gFrontEnd )
				)
				( attribute "PART_NUMBER" "G21497-005"
					( Origin gFrontEnd )
				)
				( attribute "PHYS_PAGE" "186"
					( Origin gFrontEnd )
				)
				( attribute "ROOM" "IO_SLOT"
					( Origin gFrontEnd )
				)
				( attribute "ROT" "0"
					( Origin gFrontEnd )
				)
				( attribute "SEC" "1"
					( Origin gFrontEnd )
				)
				( attribute "SEC_TYPE" "0402"
					( Origin gFrontEnd )
				)
				( attribute "TOLERANCE" "5%"
					( Origin gFrontEnd )
				)
				( attribute "VALUE" "0.0"
					( Origin gFrontEnd )
				)
				( attribute "VER" "1"
					( Origin gFrontEnd )
				)
				( attribute "WATTAGE" "1/16W"
					( Origin gFrontEnd )
				)
				( attribute "XY" "(6700,2750)"
					( Origin gFrontEnd )
				)
				( attribute "CHIPS_PART_NAME" "RES"
					( Origin gPackager )
				)
				( attribute "CDS_PART_NAME" "RES_0402-0.0,5%,1/16W,CHIP,G21A"
					( Origin gPackager )
				)
				( objectStatus "R1M16" )
				( pin "a"
					( attribute "PN" "1"
						( Origin gPackager )
					)
					( objectStatus "R1M16.1" )
				)
				( pin "b"
					( attribute "PN" "2"
						( Origin gPackager )
					)
					( objectStatus "R1M16.2" )
				)
			)
			( gate "@baseboard_fab2_lib.baseboard_fab2(sch_1):page186_i338"
				( attribute "CDS_LIB" "mstr_discrete"
					( Origin gPackager )
				)
				( attribute "CDS_LOCATION" "R1M17"
					( Origin gPackager )
				)
				( attribute "CDS_SEC" "1"
					( Origin gPackager )
				)
				( attribute "LOCATION" "R1M17"
					( Origin gFrontEnd )
				)
				( attribute "MATERIAL" "CHIP"
					( Origin gFrontEnd )
				)
				( attribute "PACK_TYPE" "0402"
					( Origin gFrontEnd )
				)
				( attribute "PART_NUMBER" "G21497-005"
					( Origin gFrontEnd )
				)
				( attribute "PHYS_PAGE" "186"
					( Origin gFrontEnd )
				)
				( attribute "ROOM" "IO_SLOT"
					( Origin gFrontEnd )
				)
				( attribute "ROT" "0"
					( Origin gFrontEnd )
				)
				( attribute "SEC" "1"
					( Origin gFrontEnd )
				)
				( attribute "SEC_TYPE" "0402"
					( Origin gFrontEnd )
				)
				( attribute "TOLERANCE" "5%"
					( Origin gFrontEnd )
				)
				( attribute "VALUE" "0.0"
					( Origin gFrontEnd )
				)
				( attribute "VER" "1"
					( Origin gFrontEnd )
				)
				( attribute "WATTAGE" "1/16W"
					( Origin gFrontEnd )
				)
				( attribute "XY" "(6375,2800)"
					( Origin gFrontEnd )
				)
				( attribute "CHIPS_PART_NAME" "RES"
					( Origin gPackager )
				)
				( attribute "CDS_PART_NAME" "RES_0402-0.0,5%,1/16W,CHIP,G21A"
					( Origin gPackager )
				)
				( objectStatus "R1M17" )
				( pin "a"
					( attribute "PN" "1"
						( Origin gPackager )
					)
					( objectStatus "R1M17.1" )
				)
				( pin "b"
					( attribute "PN" "2"
						( Origin gPackager )
					)
					( objectStatus "R1M17.2" )
				)
			)
			( gate "@baseboard_fab2_lib.baseboard_fab2(sch_1):page186_i339"
				( attribute "CDS_LIB" "mstr_discrete"
					( Origin gPackager )
				)
				( attribute "CDS_LOCATION" "R1M15"
					( Origin gPackager )
				)
				( attribute "CDS_SEC" "1"
					( Origin gPackager )
				)
				( attribute "LOCATION" "R1M15"
					( Origin gFrontEnd )
				)
				( attribute "MATERIAL" "CHIP"
					( Origin gFrontEnd )
				)
				( attribute "PACK_TYPE" "0402"
					( Origin gFrontEnd )
				)
				( attribute "PART_NUMBER" "G21497-005"
					( Origin gFrontEnd )
				)
				( attribute "PHYS_PAGE" "186"
					( Origin gFrontEnd )
				)
				( attribute "ROOM" "IO_SLOT"
					( Origin gFrontEnd )
				)
				( attribute "ROT" "0"
					( Origin gFrontEnd )
				)
				( attribute "SEC" "1"
					( Origin gFrontEnd )
				)
				( attribute "SEC_TYPE" "0402"
					( Origin gFrontEnd )
				)
				( attribute "TOLERANCE" "5%"
					( Origin gFrontEnd )
				)
				( attribute "VALUE" "0.0"
					( Origin gFrontEnd )
				)
				( attribute "VER" "1"
					( Origin gFrontEnd )
				)
				( attribute "WATTAGE" "1/16W"
					( Origin gFrontEnd )
				)
				( attribute "XY" "(6375,3200)"
					( Origin gFrontEnd )
				)
				( attribute "CHIPS_PART_NAME" "RES"
					( Origin gPackager )
				)
				( attribute "CDS_PART_NAME" "RES_0402-0.0,5%,1/16W,CHIP,G21A"
					( Origin gPackager )
				)
				( objectStatus "R1M15" )
				( pin "a"
					( attribute "PN" "1"
						( Origin gPackager )
					)
					( objectStatus "R1M15.1" )
				)
				( pin "b"
					( attribute "PN" "2"
						( Origin gPackager )
					)
					( objectStatus "R1M15.2" )
				)
			)
			( gate "@baseboard_fab2_lib.baseboard_fab2(sch_1):page186_i340"
				( attribute "CDS_LIB" "mstr_discrete"
					( Origin gPackager )
				)
				( attribute "CDS_LOCATION" "R1M18"
					( Origin gPackager )
				)
				( attribute "CDS_SEC" "1"
					( Origin gPackager )
				)
				( attribute "LOCATION" "R1M18"
					( Origin gFrontEnd )
				)
				( attribute "MATERIAL" "CHIP"
					( Origin gFrontEnd )
				)
				( attribute "PACK_TYPE" "0402"
					( Origin gFrontEnd )
				)
				( attribute "PART_NUMBER" "G21497-005"
					( Origin gFrontEnd )
				)
				( attribute "PHYS_PAGE" "186"
					( Origin gFrontEnd )
				)
				( attribute "ROOM" "IO_SLOT"
					( Origin gFrontEnd )
				)
				( attribute "ROT" "0"
					( Origin gFrontEnd )
				)
				( attribute "SEC" "1"
					( Origin gFrontEnd )
				)
				( attribute "SEC_TYPE" "0402"
					( Origin gFrontEnd )
				)
				( attribute "TOLERANCE" "5%"
					( Origin gFrontEnd )
				)
				( attribute "VALUE" "0.0"
					( Origin gFrontEnd )
				)
				( attribute "VER" "1"
					( Origin gFrontEnd )
				)
				( attribute "WATTAGE" "1/16W"
					( Origin gFrontEnd )
				)
				( attribute "XY" "(10250,3000)"
					( Origin gFrontEnd )
				)
				( attribute "CHIPS_PART_NAME" "RES"
					( Origin gPackager )
				)
				( attribute "CDS_PART_NAME" "RES_0402-0.0,5%,1/16W,CHIP,G21A"
					( Origin gPackager )
				)
				( objectStatus "R1M18" )
				( pin "a"
					( attribute "PN" "1"
						( Origin gPackager )
					)
					( objectStatus "R1M18.1" )
				)
				( pin "b"
					( attribute "PN" "2"
						( Origin gPackager )
					)
					( objectStatus "R1M18.2" )
				)
			)
			( gate "@baseboard_fab2_lib.baseboard_fab2(sch_1):page186_i345"
				( attribute "CDS_LIB" "dev_discrete"
					( Origin gPackager )
				)
				( attribute "CDS_LOCATION" "C9B10"
					( Origin gPackager )
				)
				( attribute "CDS_SEC" "1"
					( Origin gPackager )
				)
				( attribute "LOCATION" "C9B10"
					( Origin gFrontEnd )
				)
				( attribute "MATERIAL" "X7R"
					( Origin gFrontEnd )
				)
				( attribute "PACK_TYPE" "0402V"
					( Origin gFrontEnd )
				)
				( attribute "PART_NUMBER" "A36096-030"
					( Origin gFrontEnd )
				)
				( attribute "PHYS_PAGE" "186"
					( Origin gFrontEnd )
				)
				( attribute "ROOM" "IO_SLOT"
					( Origin gFrontEnd )
				)
				( attribute "ROT" "0"
					( Origin gFrontEnd )
				)
				( attribute "SEC" "1"
					( Origin gFrontEnd )
				)
				( attribute "SEC_TYPE" "0402V"
					( Origin gFrontEnd )
				)
				( attribute "TOLERANCE" "10%"
					( Origin gFrontEnd )
				)
				( attribute "VALUE" "0.1UF"
					( Origin gFrontEnd )
				)
				( attribute "VER" "1"
					( Origin gFrontEnd )
				)
				( attribute "VOLTAGE" "16V"
					( Units "uVoltage" "V" 1.000000)
					( Origin gFrontEnd )
				)
				( attribute "XY" "(10050,3950)"
					( Origin gFrontEnd )
				)
				( attribute "CHIPS_PART_NAME" "CAP_A"
					( Origin gPackager )
				)
				( attribute "CDS_PART_NAME" "CAP_A_0402V-0.1UF,16V,10%,X7R,A"
					( Origin gPackager )
				)
				( objectStatus "C9B10" )
				( pin "a"
					( attribute "PN" "1"
						( Origin gPackager )
					)
					( objectStatus "C9B10.1" )
				)
				( pin "b"
					( attribute "PN" "2"
						( Origin gPackager )
					)
					( objectStatus "C9B10.2" )
				)
			)
			( gate "@baseboard_fab2_lib.baseboard_fab2(sch_1):page186_i347"
				( attribute "CDS_LIB" "dev_discrete"
					( Origin gPackager )
				)
				( attribute "CDS_LOCATION" "C9B9"
					( Origin gPackager )
				)
				( attribute "CDS_SEC" "1"
					( Origin gPackager )
				)
				( attribute "LOCATION" "C9B9"
					( Origin gFrontEnd )
				)
				( attribute "MATERIAL" "X6S"
					( Origin gFrontEnd )
				)
				( attribute "PACK_TYPE" "0402V"
					( Origin gFrontEnd )
				)
				( attribute "PART_NUMBER" "D97712-004"
					( Origin gFrontEnd )
				)
				( attribute "PHYS_PAGE" "186"
					( Origin gFrontEnd )
				)
				( attribute "ROOM" "IO_SLOT"
					( Origin gFrontEnd )
				)
				( attribute "ROT" "0"
					( Origin gFrontEnd )
				)
				( attribute "SEC" "1"
					( Origin gFrontEnd )
				)
				( attribute "SEC_TYPE" "0402V"
					( Origin gFrontEnd )
				)
				( attribute "TOLERANCE" "10%"
					( Origin gFrontEnd )
				)
				( attribute "VALUE" "1.0UF"
					( Origin gFrontEnd )
				)
				( attribute "VER" "1"
					( Origin gFrontEnd )
				)
				( attribute "VOLTAGE" "6.3V"
					( Units "uVoltage" "V" 1.000000)
					( Origin gFrontEnd )
				)
				( attribute "XY" "(9650,3950)"
					( Origin gFrontEnd )
				)
				( attribute "CHIPS_PART_NAME" "CAP_A"
					( Origin gPackager )
				)
				( attribute "CDS_PART_NAME" "CAP_A_0402V-1.0UF,6.3V,10%,X6SA"
					( Origin gPackager )
				)
				( objectStatus "C9B9" )
				( pin "a"
					( attribute "PN" "1"
						( Origin gPackager )
					)
					( objectStatus "C9B9.1" )
				)
				( pin "b"
					( attribute "PN" "2"
						( Origin gPackager )
					)
					( objectStatus "C9B9.2" )
				)
			)
			( gate "@baseboard_fab2_lib.baseboard_fab2(sch_1):page187_i18"
				( attribute "CDS_LIB" "mstr_discrete"
					( Origin gPackager )
				)
				( attribute "CDS_LOCATION" "R2R8"
					( Origin gPackager )
				)
				( attribute "CDS_SEC" "1"
					( Origin gPackager )
				)
				( attribute "LOCATION" "R2R8"
					( Origin gFrontEnd )
				)
				( attribute "MATERIAL" "CHIP"
					( Origin gFrontEnd )
				)
				( attribute "PACK_TYPE" "0402"
					( Origin gFrontEnd )
				)
				( attribute "PART_NUMBER" "G21796-017"
					( Origin gFrontEnd )
				)
				( attribute "PHYS_PAGE" "187"
					( Origin gFrontEnd )
				)
				( attribute "ROOM" "IO_SLOT"
					( Origin gFrontEnd )
				)
				( attribute "ROT" "0"
					( Origin gFrontEnd )
				)
				( attribute "SEC" "1"
					( Origin gFrontEnd )
				)
				( attribute "SEC_TYPE" "0402"
					( Origin gFrontEnd )
				)
				( attribute "TOLERANCE" "1%"
					( Origin gFrontEnd )
				)
				( attribute "VALUE" "100.0"
					( Origin gFrontEnd )
				)
				( attribute "VER" "1"
					( Origin gFrontEnd )
				)
				( attribute "WATTAGE" "1/16W"
					( Origin gFrontEnd )
				)
				( attribute "XY" "(975,4050)"
					( Origin gFrontEnd )
				)
				( attribute "CHIPS_PART_NAME" "RES"
					( Origin gPackager )
				)
				( attribute "CDS_PART_NAME" "RES_0402-100.0,1%,1/16W,CHIP,GA"
					( Origin gPackager )
				)
				( objectStatus "R2R8" )
				( pin "a"
					( attribute "PN" "1"
						( Origin gPackager )
					)
					( objectStatus "R2R8.1" )
				)
				( pin "b"
					( attribute "PN" "2"
						( Origin gPackager )
					)
					( objectStatus "R2R8.2" )
				)
			)
			( gate "@baseboard_fab2_lib.baseboard_fab2(sch_1):page187_i119"
				( attribute "CDS_LIB" "mstr_sconn"
					( Origin gPackager )
				)
				( attribute "CDS_LMAN_SYM_OUTLINE" "-250,1100,250,-1100"
					( Origin gPackager )
				)
				( attribute "CDS_LOCATION" "J8E3"
					( Origin gPackager )
				)
				( attribute "CDS_SEC" "1"
					( Origin gPackager )
				)
				( attribute "LOCATION" "J8E3"
					( Origin gFrontEnd )
				)
				( attribute "MATERIAL" "CONN"
					( Origin gFrontEnd )
				)
				( attribute "PACK_TYPE" "SM"
					( Origin gFrontEnd )
				)
				( attribute "PART_NUMBER" "E67482-007"
					( Origin gFrontEnd )
				)
				( attribute "PHYS_PAGE" "187"
					( Origin gFrontEnd )
				)
				( attribute "ROOM" "IO_SLOT"
					( Origin gFrontEnd )
				)
				( attribute "ROT" "2"
					( Origin gFrontEnd )
				)
				( attribute "SEC" "1"
					( Origin gFrontEnd )
				)
				( attribute "SEC_TYPE" "SM"
					( Origin gFrontEnd )
				)
				( attribute "VER" "1"
					( Origin gFrontEnd )
				)
				( attribute "XY" "(-50,3100)"
					( Origin gFrontEnd )
				)
				( attribute "CHIPS_PART_NAME" "SCONN80_E67482007"
					( Origin gPackager )
				)
				( attribute "CDS_PART_NAME" "SCONN80_E67482007_SM-CONN,E674A"
					( Origin gPackager )
				)
				( objectStatus "J8E3" )
				( pin "io1"
					( attribute "PN" "1"
						( Origin gPackager )
					)
					( objectStatus "J8E3.1" )
				)
				( pin "io2"
					( attribute "PN" "2"
						( Origin gPackager )
					)
					( objectStatus "J8E3.2" )
				)
				( pin "io3"
					( attribute "PN" "3"
						( Origin gPackager )
					)
					( objectStatus "J8E3.3" )
				)
				( pin "io4"
					( attribute "PN" "4"
						( Origin gPackager )
					)
					( objectStatus "J8E3.4" )
				)
				( pin "io5"
					( attribute "PN" "5"
						( Origin gPackager )
					)
					( objectStatus "J8E3.5" )
				)
				( pin "io6"
					( attribute "PN" "6"
						( Origin gPackager )
					)
					( objectStatus "J8E3.6" )
				)
				( pin "io7"
					( attribute "PN" "7"
						( Origin gPackager )
					)
					( objectStatus "J8E3.7" )
				)
				( pin "io8"
					( attribute "PN" "8"
						( Origin gPackager )
					)
					( objectStatus "J8E3.8" )
				)
				( pin "io9"
					( attribute "PN" "9"
						( Origin gPackager )
					)
					( objectStatus "J8E3.9" )
				)
				( pin "io10"
					( attribute "PN" "10"
						( Origin gPackager )
					)
					( objectStatus "J8E3.10" )
				)
				( pin "io11"
					( attribute "PN" "11"
						( Origin gPackager )
					)
					( objectStatus "J8E3.11" )
				)
				( pin "io12"
					( attribute "PN" "12"
						( Origin gPackager )
					)
					( objectStatus "J8E3.12" )
				)
				( pin "io13"
					( attribute "PN" "13"
						( Origin gPackager )
					)
					( objectStatus "J8E3.13" )
				)
				( pin "io14"
					( attribute "PN" "14"
						( Origin gPackager )
					)
					( objectStatus "J8E3.14" )
				)
				( pin "io15"
					( attribute "PN" "15"
						( Origin gPackager )
					)
					( objectStatus "J8E3.15" )
				)
				( pin "io16"
					( attribute "PN" "16"
						( Origin gPackager )
					)
					( objectStatus "J8E3.16" )
				)
				( pin "io17"
					( attribute "PN" "17"
						( Origin gPackager )
					)
					( objectStatus "J8E3.17" )
				)
				( pin "io18"
					( attribute "PN" "18"
						( Origin gPackager )
					)
					( objectStatus "J8E3.18" )
				)
				( pin "io19"
					( attribute "PN" "19"
						( Origin gPackager )
					)
					( objectStatus "J8E3.19" )
				)
				( pin "io20"
					( attribute "PN" "20"
						( Origin gPackager )
					)
					( objectStatus "J8E3.20" )
				)
				( pin "io21"
					( attribute "PN" "21"
						( Origin gPackager )
					)
					( objectStatus "J8E3.21" )
				)
				( pin "io22"
					( attribute "PN" "22"
						( Origin gPackager )
					)
					( objectStatus "J8E3.22" )
				)
				( pin "io23"
					( attribute "PN" "23"
						( Origin gPackager )
					)
					( objectStatus "J8E3.23" )
				)
				( pin "io24"
					( attribute "PN" "24"
						( Origin gPackager )
					)
					( objectStatus "J8E3.24" )
				)
				( pin "io25"
					( attribute "PN" "25"
						( Origin gPackager )
					)
					( objectStatus "J8E3.25" )
				)
				( pin "io26"
					( attribute "PN" "26"
						( Origin gPackager )
					)
					( objectStatus "J8E3.26" )
				)
				( pin "io27"
					( attribute "PN" "27"
						( Origin gPackager )
					)
					( objectStatus "J8E3.27" )
				)
				( pin "io28"
					( attribute "PN" "28"
						( Origin gPackager )
					)
					( objectStatus "J8E3.28" )
				)
				( pin "io29"
					( attribute "PN" "29"
						( Origin gPackager )
					)
					( objectStatus "J8E3.29" )
				)
				( pin "io30"
					( attribute "PN" "30"
						( Origin gPackager )
					)
					( objectStatus "J8E3.30" )
				)
				( pin "io31"
					( attribute "PN" "31"
						( Origin gPackager )
					)
					( objectStatus "J8E3.31" )
				)
				( pin "io32"
					( attribute "PN" "32"
						( Origin gPackager )
					)
					( objectStatus "J8E3.32" )
				)
				( pin "io33"
					( attribute "PN" "33"
						( Origin gPackager )
					)
					( objectStatus "J8E3.33" )
				)
				( pin "io34"
					( attribute "PN" "34"
						( Origin gPackager )
					)
					( objectStatus "J8E3.34" )
				)
				( pin "io35"
					( attribute "PN" "35"
						( Origin gPackager )
					)
					( objectStatus "J8E3.35" )
				)
				( pin "io36"
					( attribute "PN" "36"
						( Origin gPackager )
					)
					( objectStatus "J8E3.36" )
				)
				( pin "io37"
					( attribute "PN" "37"
						( Origin gPackager )
					)
					( objectStatus "J8E3.37" )
				)
				( pin "io38"
					( attribute "PN" "38"
						( Origin gPackager )
					)
					( objectStatus "J8E3.38" )
				)
				( pin "io39"
					( attribute "PN" "39"
						( Origin gPackager )
					)
					( objectStatus "J8E3.39" )
				)
				( pin "io40"
					( attribute "PN" "40"
						( Origin gPackager )
					)
					( objectStatus "J8E3.40" )
				)
				( pin "io41"
					( attribute "PN" "41"
						( Origin gPackager )
					)
					( objectStatus "J8E3.41" )
				)
				( pin "io42"
					( attribute "PN" "42"
						( Origin gPackager )
					)
					( objectStatus "J8E3.42" )
				)
				( pin "io43"
					( attribute "PN" "43"
						( Origin gPackager )
					)
					( objectStatus "J8E3.43" )
				)
				( pin "io44"
					( attribute "PN" "44"
						( Origin gPackager )
					)
					( objectStatus "J8E3.44" )
				)
				( pin "io45"
					( attribute "PN" "45"
						( Origin gPackager )
					)
					( objectStatus "J8E3.45" )
				)
				( pin "io46"
					( attribute "PN" "46"
						( Origin gPackager )
					)
					( objectStatus "J8E3.46" )
				)
				( pin "io47"
					( attribute "PN" "47"
						( Origin gPackager )
					)
					( objectStatus "J8E3.47" )
				)
				( pin "io48"
					( attribute "PN" "48"
						( Origin gPackager )
					)
					( objectStatus "J8E3.48" )
				)
				( pin "io49"
					( attribute "PN" "49"
						( Origin gPackager )
					)
					( objectStatus "J8E3.49" )
				)
				( pin "io50"
					( attribute "PN" "50"
						( Origin gPackager )
					)
					( objectStatus "J8E3.50" )
				)
				( pin "io51"
					( attribute "PN" "51"
						( Origin gPackager )
					)
					( objectStatus "J8E3.51" )
				)
				( pin "io52"
					( attribute "PN" "52"
						( Origin gPackager )
					)
					( objectStatus "J8E3.52" )
				)
				( pin "io53"
					( attribute "PN" "53"
						( Origin gPackager )
					)
					( objectStatus "J8E3.53" )
				)
				( pin "io54"
					( attribute "PN" "54"
						( Origin gPackager )
					)
					( objectStatus "J8E3.54" )
				)
				( pin "io55"
					( attribute "PN" "55"
						( Origin gPackager )
					)
					( objectStatus "J8E3.55" )
				)
				( pin "io56"
					( attribute "PN" "56"
						( Origin gPackager )
					)
					( objectStatus "J8E3.56" )
				)
				( pin "io57"
					( attribute "PN" "57"
						( Origin gPackager )
					)
					( objectStatus "J8E3.57" )
				)
				( pin "io58"
					( attribute "PN" "58"
						( Origin gPackager )
					)
					( objectStatus "J8E3.58" )
				)
				( pin "io59"
					( attribute "PN" "59"
						( Origin gPackager )
					)
					( objectStatus "J8E3.59" )
				)
				( pin "io60"
					( attribute "PN" "60"
						( Origin gPackager )
					)
					( objectStatus "J8E3.60" )
				)
				( pin "io61"
					( attribute "PN" "61"
						( Origin gPackager )
					)
					( objectStatus "J8E3.61" )
				)
				( pin "io62"
					( attribute "PN" "62"
						( Origin gPackager )
					)
					( objectStatus "J8E3.62" )
				)
				( pin "io63"
					( attribute "PN" "63"
						( Origin gPackager )
					)
					( objectStatus "J8E3.63" )
				)
				( pin "io64"
					( attribute "PN" "64"
						( Origin gPackager )
					)
					( objectStatus "J8E3.64" )
				)
				( pin "io65"
					( attribute "PN" "65"
						( Origin gPackager )
					)
					( objectStatus "J8E3.65" )
				)
				( pin "io66"
					( attribute "PN" "66"
						( Origin gPackager )
					)
					( objectStatus "J8E3.66" )
				)
				( pin "io67"
					( attribute "PN" "67"
						( Origin gPackager )
					)
					( objectStatus "J8E3.67" )
				)
				( pin "io68"
					( attribute "PN" "68"
						( Origin gPackager )
					)
					( objectStatus "J8E3.68" )
				)
				( pin "io69"
					( attribute "PN" "69"
						( Origin gPackager )
					)
					( objectStatus "J8E3.69" )
				)
				( pin "io70"
					( attribute "PN" "70"
						( Origin gPackager )
					)
					( objectStatus "J8E3.70" )
				)
				( pin "io71"
					( attribute "PN" "71"
						( Origin gPackager )
					)
					( objectStatus "J8E3.71" )
				)
				( pin "io72"
					( attribute "PN" "72"
						( Origin gPackager )
					)
					( objectStatus "J8E3.72" )
				)
				( pin "io73"
					( attribute "PN" "73"
						( Origin gPackager )
					)
					( objectStatus "J8E3.73" )
				)
				( pin "io74"
					( attribute "PN" "74"
						( Origin gPackager )
					)
					( objectStatus "J8E3.74" )
				)
				( pin "io75"
					( attribute "PN" "75"
						( Origin gPackager )
					)
					( objectStatus "J8E3.75" )
				)
				( pin "io76"
					( attribute "PN" "76"
						( Origin gPackager )
					)
					( objectStatus "J8E3.76" )
				)
				( pin "io77"
					( attribute "PN" "77"
						( Origin gPackager )
					)
					( objectStatus "J8E3.77" )
				)
				( pin "io78"
					( attribute "PN" "78"
						( Origin gPackager )
					)
					( objectStatus "J8E3.78" )
				)
				( pin "io79"
					( attribute "PN" "79"
						( Origin gPackager )
					)
					( objectStatus "J8E3.79" )
				)
				( pin "io80"
					( attribute "PN" "80"
						( Origin gPackager )
					)
					( objectStatus "J8E3.80" )
				)
			)
			( gate "@baseboard_fab2_lib.baseboard_fab2(sch_1):page187_i145"
				( attribute "CDS_LIB" "mstr_discrete"
					( Origin gPackager )
				)
				( attribute "CDS_LOCATION" "R9E10"
					( Origin gPackager )
				)
				( attribute "CDS_SEC" "1"
					( Origin gPackager )
				)
				( attribute "LOCATION" "R9E10"
					( Origin gFrontEnd )
				)
				( attribute "MATERIAL" "CHIP"
					( Origin gFrontEnd )
				)
				( attribute "PACK_TYPE" "0402"
					( Origin gFrontEnd )
				)
				( attribute "PART_NUMBER" "G21796-004"
					( Origin gFrontEnd )
				)
				( attribute "PHYS_PAGE" "187"
					( Origin gFrontEnd )
				)
				( attribute "ROOM" "IO_SLOT"
					( Origin gFrontEnd )
				)
				( attribute "ROT" "0"
					( Origin gFrontEnd )
				)
				( attribute "SEC" "1"
					( Origin gFrontEnd )
				)
				( attribute "SEC_TYPE" "0402"
					( Origin gFrontEnd )
				)
				( attribute "TOLERANCE" "1%"
					( Origin gFrontEnd )
				)
				( attribute "VALUE" "200.0"
					( Origin gFrontEnd )
				)
				( attribute "VER" "1"
					( Origin gFrontEnd )
				)
				( attribute "WATTAGE" "1/16W"
					( Origin gFrontEnd )
				)
				( attribute "XY" "(2275,2200)"
					( Origin gFrontEnd )
				)
				( attribute "CHIPS_PART_NAME" "RES"
					( Origin gPackager )
				)
				( attribute "CDS_PART_NAME" "RES_0402-200.0,1%,1/16W,CHIP,GA"
					( Origin gPackager )
				)
				( objectStatus "R9E10" )
				( pin "a"
					( attribute "PN" "1"
						( Origin gPackager )
					)
					( objectStatus "R9E10.1" )
				)
				( pin "b"
					( attribute "PN" "2"
						( Origin gPackager )
					)
					( objectStatus "R9E10.2" )
				)
			)
			( gate "@baseboard_fab2_lib.baseboard_fab2(sch_1):page187_i150"
				( attribute "CDS_LIB" "mstr_discrete"
					( Origin gPackager )
				)
				( attribute "CDS_LOCATION" "R9E11"
					( Origin gPackager )
				)
				( attribute "CDS_SEC" "1"
					( Origin gPackager )
				)
				( attribute "LOCATION" "R9E11"
					( Origin gFrontEnd )
				)
				( attribute "MATERIAL" "CHIP"
					( Origin gFrontEnd )
				)
				( attribute "PACK_TYPE" "0402"
					( Origin gFrontEnd )
				)
				( attribute "PART_NUMBER" "G21796-004"
					( Origin gFrontEnd )
				)
				( attribute "PHYS_PAGE" "187"
					( Origin gFrontEnd )
				)
				( attribute "ROOM" "IO_SLOT"
					( Origin gFrontEnd )
				)
				( attribute "ROT" "0"
					( Origin gFrontEnd )
				)
				( attribute "SEC" "1"
					( Origin gFrontEnd )
				)
				( attribute "SEC_TYPE" "0402"
					( Origin gFrontEnd )
				)
				( attribute "TOLERANCE" "1%"
					( Origin gFrontEnd )
				)
				( attribute "VALUE" "200.0"
					( Origin gFrontEnd )
				)
				( attribute "VER" "1"
					( Origin gFrontEnd )
				)
				( attribute "WATTAGE" "1/16W"
					( Origin gFrontEnd )
				)
				( attribute "XY" "(1725,2150)"
					( Origin gFrontEnd )
				)
				( attribute "CHIPS_PART_NAME" "RES"
					( Origin gPackager )
				)
				( attribute "CDS_PART_NAME" "RES_0402-200.0,1%,1/16W,CHIP,GA"
					( Origin gPackager )
				)
				( objectStatus "R9E11" )
				( pin "a"
					( attribute "PN" "1"
						( Origin gPackager )
					)
					( objectStatus "R9E11.1" )
				)
				( pin "b"
					( attribute "PN" "2"
						( Origin gPackager )
					)
					( objectStatus "R9E11.2" )
				)
			)
			( gate "@baseboard_fab2_lib.baseboard_fab2(sch_1):page187_i153"
				( attribute "CDS_LIB" "mstr_discrete"
					( Origin gPackager )
				)
				( attribute "CDS_LOCATION" "R9E12"
					( Origin gPackager )
				)
				( attribute "CDS_SEC" "1"
					( Origin gPackager )
				)
				( attribute "LOCATION" "R9E12"
					( Origin gFrontEnd )
				)
				( attribute "MATERIAL" "CHIP"
					( Origin gFrontEnd )
				)
				( attribute "PACK_TYPE" "0402"
					( Origin gFrontEnd )
				)
				( attribute "PART_NUMBER" "G21796-004"
					( Origin gFrontEnd )
				)
				( attribute "PHYS_PAGE" "187"
					( Origin gFrontEnd )
				)
				( attribute "ROOM" "IO_SLOT"
					( Origin gFrontEnd )
				)
				( attribute "ROT" "0"
					( Origin gFrontEnd )
				)
				( attribute "SEC" "1"
					( Origin gFrontEnd )
				)
				( attribute "SEC_TYPE" "0402"
					( Origin gFrontEnd )
				)
				( attribute "TOLERANCE" "1%"
					( Origin gFrontEnd )
				)
				( attribute "VALUE" "200.0"
					( Origin gFrontEnd )
				)
				( attribute "VER" "1"
					( Origin gFrontEnd )
				)
				( attribute "WATTAGE" "1/16W"
					( Origin gFrontEnd )
				)
				( attribute "XY" "(1275,2100)"
					( Origin gFrontEnd )
				)
				( attribute "CHIPS_PART_NAME" "RES"
					( Origin gPackager )
				)
				( attribute "CDS_PART_NAME" "RES_0402-200.0,1%,1/16W,CHIP,GA"
					( Origin gPackager )
				)
				( objectStatus "R9E12" )
				( pin "a"
					( attribute "PN" "1"
						( Origin gPackager )
					)
					( objectStatus "R9E12.1" )
				)
				( pin "b"
					( attribute "PN" "2"
						( Origin gPackager )
					)
					( objectStatus "R9E12.2" )
				)
			)
			( gate "@baseboard_fab2_lib.baseboard_fab2(sch_1):page188_i2"
				( attribute "BOM_COST" "IO_MODULE"
					( Origin gFrontEnd )
				)
				( attribute "CDS_LIB" "dev_discrete"
					( Origin gPackager )
				)
				( attribute "CDS_LOCATION" "C2R15"
					( Origin gPackager )
				)
				( attribute "CDS_SEC" "1"
					( Origin gPackager )
				)
				( attribute "LOCATION" "C2R15"
					( Origin gFrontEnd )
				)
				( attribute "MATERIAL" "X7R"
					( Origin gFrontEnd )
				)
				( attribute "PACK_TYPE" "0402V"
					( Origin gFrontEnd )
				)
				( attribute "PART_NUMBER" "A36096-030"
					( Origin gFrontEnd )
				)
				( attribute "PHYS_PAGE" "188"
					( Origin gFrontEnd )
				)
				( attribute "ROOM" "IO_MODULE"
					( Origin gFrontEnd )
				)
				( attribute "ROT" "0"
					( Origin gFrontEnd )
				)
				( attribute "SEC" "1"
					( Origin gFrontEnd )
				)
				( attribute "SEC_TYPE" "0402V"
					( Origin gFrontEnd )
				)
				( attribute "TOLERANCE" "10%"
					( Origin gFrontEnd )
				)
				( attribute "VALUE" "0.1UF"
					( Origin gFrontEnd )
				)
				( attribute "VER" "1"
					( Origin gFrontEnd )
				)
				( attribute "VOLTAGE" "16V"
					( Units "uVoltage" "V" 1.000000)
					( Origin gFrontEnd )
				)
				( attribute "XY" "(3300,1275)"
					( Origin gFrontEnd )
				)
				( attribute "CHIPS_PART_NAME" "CAP_A"
					( Origin gPackager )
				)
				( attribute "CDS_PART_NAME" "CAP_A_0402V-0.1UF,16V,10%,X7R,A"
					( Origin gPackager )
				)
				( objectStatus "C2R15" )
				( pin "a"
					( attribute "PN" "1"
						( Origin gPackager )
					)
					( objectStatus "C2R15.1" )
				)
				( pin "b"
					( attribute "PN" "2"
						( Origin gPackager )
					)
					( objectStatus "C2R15.2" )
				)
			)
			( gate "@baseboard_fab2_lib.baseboard_fab2(sch_1):page188_i3"
				( attribute "BOM_COST" "IO_MODULE"
					( Origin gFrontEnd )
				)
				( attribute "CDS_LIB" "dev_discrete"
					( Origin gPackager )
				)
				( attribute "CDS_LOCATION" "C2R18"
					( Origin gPackager )
				)
				( attribute "CDS_SEC" "1"
					( Origin gPackager )
				)
				( attribute "LOCATION" "C2R18"
					( Origin gFrontEnd )
				)
				( attribute "MATERIAL" "X7R"
					( Origin gFrontEnd )
				)
				( attribute "PACK_TYPE" "0402V"
					( Origin gFrontEnd )
				)
				( attribute "PART_NUMBER" "A36096-030"
					( Origin gFrontEnd )
				)
				( attribute "PHYS_PAGE" "188"
					( Origin gFrontEnd )
				)
				( attribute "ROOM" "IO_MODULE"
					( Origin gFrontEnd )
				)
				( attribute "ROT" "0"
					( Origin gFrontEnd )
				)
				( attribute "SEC" "1"
					( Origin gPackager )
				)
				( attribute "TOLERANCE" "10%"
					( Origin gFrontEnd )
				)
				( attribute "VALUE" "0.1UF"
					( Origin gFrontEnd )
				)
				( attribute "VER" "1"
					( Origin gFrontEnd )
				)
				( attribute "VOLTAGE" "16V"
					( Units "uVoltage" "V" 1.000000)
					( Origin gFrontEnd )
				)
				( attribute "XY" "(2925,1300)"
					( Origin gFrontEnd )
				)
				( attribute "CHIPS_PART_NAME" "CAP_A"
					( Origin gPackager )
				)
				( attribute "CDS_PART_NAME" "CAP_A_0402V-0.1UF,16V,10%,X7R,A"
					( Origin gPackager )
				)
				( objectStatus "C2R18" )
				( pin "a"
					( attribute "PN" "1"
						( Origin gPackager )
					)
					( objectStatus "C2R18.1" )
				)
				( pin "b"
					( attribute "PN" "2"
						( Origin gPackager )
					)
					( objectStatus "C2R18.2" )
				)
			)
			( gate "@baseboard_fab2_lib.baseboard_fab2(sch_1):page188_i21"
				( attribute "BOM_COST" "IO_MODULE"
					( Origin gFrontEnd )
				)
				( attribute "CDS_LIB" "dev_discrete"
					( Origin gPackager )
				)
				( attribute "CDS_LOCATION" "C2P11"
					( Origin gPackager )
				)
				( attribute "CDS_SEC" "1"
					( Origin gPackager )
				)
				( attribute "LOCATION" "C2P11"
					( Origin gFrontEnd )
				)
				( attribute "MATERIAL" "X7R"
					( Origin gFrontEnd )
				)
				( attribute "PACK_TYPE" "0402V"
					( Origin gFrontEnd )
				)
				( attribute "PART_NUMBER" "A36096-030"
					( Origin gFrontEnd )
				)
				( attribute "PHYS_PAGE" "188"
					( Origin gFrontEnd )
				)
				( attribute "ROOM" "IO_MODULE"
					( Origin gFrontEnd )
				)
				( attribute "ROT" "0"
					( Origin gFrontEnd )
				)
				( attribute "SEC" "1"
					( Origin gFrontEnd )
				)
				( attribute "SEC_TYPE" "0402V"
					( Origin gFrontEnd )
				)
				( attribute "TOLERANCE" "10%"
					( Origin gFrontEnd )
				)
				( attribute "VALUE" "0.1UF"
					( Origin gFrontEnd )
				)
				( attribute "VER" "1"
					( Origin gFrontEnd )
				)
				( attribute "VOLTAGE" "16V"
					( Units "uVoltage" "V" 1.000000)
					( Origin gFrontEnd )
				)
				( attribute "XY" "(2400,1300)"
					( Origin gFrontEnd )
				)
				( attribute "CHIPS_PART_NAME" "CAP_A"
					( Origin gPackager )
				)
				( attribute "CDS_PART_NAME" "CAP_A_0402V-0.1UF,16V,10%,X7R,A"
					( Origin gPackager )
				)
				( objectStatus "C2P11" )
				( pin "a"
					( attribute "PN" "1"
						( Origin gPackager )
					)
					( objectStatus "C2P11.1" )
				)
				( pin "b"
					( attribute "PN" "2"
						( Origin gPackager )
					)
					( objectStatus "C2P11.2" )
				)
			)
			( gate "@baseboard_fab2_lib.baseboard_fab2(sch_1):page188_i23"
				( attribute "BOM_COST" "IO_MODULE"
					( Origin gFrontEnd )
				)
				( attribute "CDS_LIB" "dev_discrete"
					( Origin gPackager )
				)
				( attribute "CDS_LOCATION" "C2P12"
					( Origin gPackager )
				)
				( attribute "CDS_SEC" "1"
					( Origin gPackager )
				)
				( attribute "LOCATION" "C2P12"
					( Origin gFrontEnd )
				)
				( attribute "MATERIAL" "X7R"
					( Origin gFrontEnd )
				)
				( attribute "PACK_TYPE" "0402V"
					( Origin gFrontEnd )
				)
				( attribute "PART_NUMBER" "A36096-030"
					( Origin gFrontEnd )
				)
				( attribute "PHYS_PAGE" "188"
					( Origin gFrontEnd )
				)
				( attribute "ROOM" "IO_MODULE"
					( Origin gFrontEnd )
				)
				( attribute "ROT" "0"
					( Origin gFrontEnd )
				)
				( attribute "SEC" "1"
					( Origin gFrontEnd )
				)
				( attribute "SEC_TYPE" "0402V"
					( Origin gFrontEnd )
				)
				( attribute "TOLERANCE" "10%"
					( Origin gFrontEnd )
				)
				( attribute "VALUE" "0.1UF"
					( Origin gFrontEnd )
				)
				( attribute "VER" "1"
					( Origin gFrontEnd )
				)
				( attribute "VOLTAGE" "16V"
					( Units "uVoltage" "V" 1.000000)
					( Origin gFrontEnd )
				)
				( attribute "XY" "(2050,1300)"
					( Origin gFrontEnd )
				)
				( attribute "CHIPS_PART_NAME" "CAP_A"
					( Origin gPackager )
				)
				( attribute "CDS_PART_NAME" "CAP_A_0402V-0.1UF,16V,10%,X7R,A"
					( Origin gPackager )
				)
				( objectStatus "C2P12" )
				( pin "a"
					( attribute "PN" "1"
						( Origin gPackager )
					)
					( objectStatus "C2P12.1" )
				)
				( pin "b"
					( attribute "PN" "2"
						( Origin gPackager )
					)
					( objectStatus "C2P12.2" )
				)
			)
			( gate "@baseboard_fab2_lib.baseboard_fab2(sch_1):page188_i25"
				( attribute "BOM_COST" "IO_MODULE"
					( Origin gFrontEnd )
				)
				( attribute "CDS_LIB" "dev_discrete"
					( Origin gPackager )
				)
				( attribute "CDS_LOCATION" "C2R17"
					( Origin gPackager )
				)
				( attribute "CDS_SEC" "1"
					( Origin gPackager )
				)
				( attribute "LOCATION" "C2R17"
					( Origin gFrontEnd )
				)
				( attribute "MATERIAL" "X7R"
					( Origin gFrontEnd )
				)
				( attribute "PACK_TYPE" "0402V"
					( Origin gFrontEnd )
				)
				( attribute "PART_NUMBER" "A36096-030"
					( Origin gFrontEnd )
				)
				( attribute "PHYS_PAGE" "188"
					( Origin gFrontEnd )
				)
				( attribute "ROOM" "IO_MODULE"
					( Origin gFrontEnd )
				)
				( attribute "ROT" "0"
					( Origin gFrontEnd )
				)
				( attribute "SEC" "1"
					( Origin gPackager )
				)
				( attribute "TOLERANCE" "10%"
					( Origin gFrontEnd )
				)
				( attribute "VALUE" "0.1UF"
					( Origin gFrontEnd )
				)
				( attribute "VER" "1"
					( Origin gFrontEnd )
				)
				( attribute "VOLTAGE" "16V"
					( Units "uVoltage" "V" 1.000000)
					( Origin gFrontEnd )
				)
				( attribute "XY" "(1000,1300)"
					( Origin gFrontEnd )
				)
				( attribute "CHIPS_PART_NAME" "CAP_A"
					( Origin gPackager )
				)
				( attribute "CDS_PART_NAME" "CAP_A_0402V-0.1UF,16V,10%,X7R,A"
					( Origin gPackager )
				)
				( objectStatus "C2R17" )
				( pin "a"
					( attribute "PN" "1"
						( Origin gPackager )
					)
					( objectStatus "C2R17.1" )
				)
				( pin "b"
					( attribute "PN" "2"
						( Origin gPackager )
					)
					( objectStatus "C2R17.2" )
				)
			)
			( gate "@baseboard_fab2_lib.baseboard_fab2(sch_1):page188_i27"
				( attribute "CDS_LIB" "mstr_sconn"
					( Origin gPackager )
				)
				( attribute "CDS_LOCATION" "J8E4"
					( Origin gPackager )
				)
				( attribute "CDS_SEC" "1"
					( Origin gPackager )
				)
				( attribute "LOCATION" "J8E4"
					( Origin gFrontEnd )
				)
				( attribute "MATERIAL" "CONN"
					( Origin gFrontEnd )
				)
				( attribute "PACK_TYPE" "SMT"
					( Origin gFrontEnd )
				)
				( attribute "PART_NUMBER" "H87568-002"
					( Origin gFrontEnd )
				)
				( attribute "PHYS_PAGE" "188"
					( Origin gFrontEnd )
				)
				( attribute "ROOM" "IO_MODULE"
					( Origin gFrontEnd )
				)
				( attribute "ROT" "0"
					( Origin gFrontEnd )
				)
				( attribute "SEC" "1"
					( Origin gFrontEnd )
				)
				( attribute "SEC_TYPE" "SMT"
					( Origin gFrontEnd )
				)
				( attribute "VER" "1"
					( Origin gFrontEnd )
				)
				( attribute "XY" "(150,3025)"
					( Origin gFrontEnd )
				)
				( attribute "CHIPS_PART_NAME" "SCONN64_H87568002_A"
					( Origin gPackager )
				)
				( attribute "CDS_PART_NAME" "SCONN64_H87568002_A_SMT-CONN,HA"
					( Origin gPackager )
				)
				( objectStatus "J8E4" )
				( pin "io1"
					( attribute "PN" "1"
						( Origin gPackager )
					)
					( objectStatus "J8E4.1" )
				)
				( pin "io2"
					( attribute "PN" "2"
						( Origin gPackager )
					)
					( objectStatus "J8E4.2" )
				)
				( pin "io3"
					( attribute "PN" "3"
						( Origin gPackager )
					)
					( objectStatus "J8E4.3" )
				)
				( pin "io4"
					( attribute "PN" "4"
						( Origin gPackager )
					)
					( objectStatus "J8E4.4" )
				)
				( pin "io5"
					( attribute "PN" "5"
						( Origin gPackager )
					)
					( objectStatus "J8E4.5" )
				)
				( pin "io6"
					( attribute "PN" "6"
						( Origin gPackager )
					)
					( objectStatus "J8E4.6" )
				)
				( pin "io7"
					( attribute "PN" "7"
						( Origin gPackager )
					)
					( objectStatus "J8E4.7" )
				)
				( pin "io8"
					( attribute "PN" "8"
						( Origin gPackager )
					)
					( objectStatus "J8E4.8" )
				)
				( pin "io9"
					( attribute "PN" "9"
						( Origin gPackager )
					)
					( objectStatus "J8E4.9" )
				)
				( pin "io10"
					( attribute "PN" "10"
						( Origin gPackager )
					)
					( objectStatus "J8E4.10" )
				)
				( pin "io11"
					( attribute "PN" "11"
						( Origin gPackager )
					)
					( objectStatus "J8E4.11" )
				)
				( pin "io12"
					( attribute "PN" "12"
						( Origin gPackager )
					)
					( objectStatus "J8E4.12" )
				)
				( pin "io13"
					( attribute "PN" "13"
						( Origin gPackager )
					)
					( objectStatus "J8E4.13" )
				)
				( pin "io14"
					( attribute "PN" "14"
						( Origin gPackager )
					)
					( objectStatus "J8E4.14" )
				)
				( pin "io15"
					( attribute "PN" "15"
						( Origin gPackager )
					)
					( objectStatus "J8E4.15" )
				)
				( pin "io16"
					( attribute "PN" "16"
						( Origin gPackager )
					)
					( objectStatus "J8E4.16" )
				)
				( pin "io17"
					( attribute "PN" "17"
						( Origin gPackager )
					)
					( objectStatus "J8E4.17" )
				)
				( pin "io18"
					( attribute "PN" "18"
						( Origin gPackager )
					)
					( objectStatus "J8E4.18" )
				)
				( pin "io19"
					( attribute "PN" "19"
						( Origin gPackager )
					)
					( objectStatus "J8E4.19" )
				)
				( pin "io20"
					( attribute "PN" "20"
						( Origin gPackager )
					)
					( objectStatus "J8E4.20" )
				)
				( pin "io21"
					( attribute "PN" "21"
						( Origin gPackager )
					)
					( objectStatus "J8E4.21" )
				)
				( pin "io22"
					( attribute "PN" "22"
						( Origin gPackager )
					)
					( objectStatus "J8E4.22" )
				)
				( pin "io23"
					( attribute "PN" "23"
						( Origin gPackager )
					)
					( objectStatus "J8E4.23" )
				)
				( pin "io24"
					( attribute "PN" "24"
						( Origin gPackager )
					)
					( objectStatus "J8E4.24" )
				)
				( pin "io25"
					( attribute "PN" "25"
						( Origin gPackager )
					)
					( objectStatus "J8E4.25" )
				)
				( pin "io26"
					( attribute "PN" "26"
						( Origin gPackager )
					)
					( objectStatus "J8E4.26" )
				)
				( pin "io27"
					( attribute "PN" "27"
						( Origin gPackager )
					)
					( objectStatus "J8E4.27" )
				)
				( pin "io28"
					( attribute "PN" "28"
						( Origin gPackager )
					)
					( objectStatus "J8E4.28" )
				)
				( pin "io29"
					( attribute "PN" "29"
						( Origin gPackager )
					)
					( objectStatus "J8E4.29" )
				)
				( pin "io30"
					( attribute "PN" "30"
						( Origin gPackager )
					)
					( objectStatus "J8E4.30" )
				)
				( pin "io31"
					( attribute "PN" "31"
						( Origin gPackager )
					)
					( objectStatus "J8E4.31" )
				)
				( pin "io32"
					( attribute "PN" "32"
						( Origin gPackager )
					)
					( objectStatus "J8E4.32" )
				)
				( pin "io33"
					( attribute "PN" "33"
						( Origin gPackager )
					)
					( objectStatus "J8E4.33" )
				)
				( pin "io34"
					( attribute "PN" "34"
						( Origin gPackager )
					)
					( objectStatus "J8E4.34" )
				)
				( pin "io35"
					( attribute "PN" "35"
						( Origin gPackager )
					)
					( objectStatus "J8E4.35" )
				)
				( pin "io36"
					( attribute "PN" "36"
						( Origin gPackager )
					)
					( objectStatus "J8E4.36" )
				)
				( pin "io37"
					( attribute "PN" "37"
						( Origin gPackager )
					)
					( objectStatus "J8E4.37" )
				)
				( pin "io38"
					( attribute "PN" "38"
						( Origin gPackager )
					)
					( objectStatus "J8E4.38" )
				)
				( pin "io39"
					( attribute "PN" "39"
						( Origin gPackager )
					)
					( objectStatus "J8E4.39" )
				)
				( pin "io40"
					( attribute "PN" "40"
						( Origin gPackager )
					)
					( objectStatus "J8E4.40" )
				)
				( pin "io41"
					( attribute "PN" "41"
						( Origin gPackager )
					)
					( objectStatus "J8E4.41" )
				)
				( pin "io42"
					( attribute "PN" "42"
						( Origin gPackager )
					)
					( objectStatus "J8E4.42" )
				)
				( pin "io43"
					( attribute "PN" "43"
						( Origin gPackager )
					)
					( objectStatus "J8E4.43" )
				)
				( pin "io44"
					( attribute "PN" "44"
						( Origin gPackager )
					)
					( objectStatus "J8E4.44" )
				)
				( pin "io45"
					( attribute "PN" "45"
						( Origin gPackager )
					)
					( objectStatus "J8E4.45" )
				)
				( pin "io46"
					( attribute "PN" "46"
						( Origin gPackager )
					)
					( objectStatus "J8E4.46" )
				)
				( pin "io47"
					( attribute "PN" "47"
						( Origin gPackager )
					)
					( objectStatus "J8E4.47" )
				)
				( pin "io48"
					( attribute "PN" "48"
						( Origin gPackager )
					)
					( objectStatus "J8E4.48" )
				)
				( pin "io49"
					( attribute "PN" "49"
						( Origin gPackager )
					)
					( objectStatus "J8E4.49" )
				)
				( pin "io50"
					( attribute "PN" "50"
						( Origin gPackager )
					)
					( objectStatus "J8E4.50" )
				)
				( pin "io51"
					( attribute "PN" "51"
						( Origin gPackager )
					)
					( objectStatus "J8E4.51" )
				)
				( pin "io52"
					( attribute "PN" "52"
						( Origin gPackager )
					)
					( objectStatus "J8E4.52" )
				)
				( pin "io53"
					( attribute "PN" "53"
						( Origin gPackager )
					)
					( objectStatus "J8E4.53" )
				)
				( pin "io54"
					( attribute "PN" "54"
						( Origin gPackager )
					)
					( objectStatus "J8E4.54" )
				)
				( pin "io55"
					( attribute "PN" "55"
						( Origin gPackager )
					)
					( objectStatus "J8E4.55" )
				)
				( pin "io56"
					( attribute "PN" "56"
						( Origin gPackager )
					)
					( objectStatus "J8E4.56" )
				)
				( pin "io57"
					( attribute "PN" "57"
						( Origin gPackager )
					)
					( objectStatus "J8E4.57" )
				)
				( pin "io58"
					( attribute "PN" "58"
						( Origin gPackager )
					)
					( objectStatus "J8E4.58" )
				)
				( pin "io59"
					( attribute "PN" "59"
						( Origin gPackager )
					)
					( objectStatus "J8E4.59" )
				)
				( pin "io60"
					( attribute "PN" "60"
						( Origin gPackager )
					)
					( objectStatus "J8E4.60" )
				)
				( pin "io61"
					( attribute "PN" "61"
						( Origin gPackager )
					)
					( objectStatus "J8E4.61" )
				)
				( pin "io62"
					( attribute "PN" "62"
						( Origin gPackager )
					)
					( objectStatus "J8E4.62" )
				)
				( pin "io63"
					( attribute "PN" "63"
						( Origin gPackager )
					)
					( objectStatus "J8E4.63" )
				)
				( pin "io64"
					( attribute "PN" "64"
						( Origin gPackager )
					)
					( objectStatus "J8E4.64" )
				)
			)
			( gate "@baseboard_fab2_lib.baseboard_fab2(sch_1):page188_i40"
				( attribute "BOM_COST" "IO_MODULE"
					( Origin gFrontEnd )
				)
				( attribute "CDS_LIB" "dev_discrete"
					( Origin gPackager )
				)
				( attribute "CDS_LOCATION" "C2R16"
					( Origin gPackager )
				)
				( attribute "CDS_SEC" "1"
					( Origin gPackager )
				)
				( attribute "LOCATION" "C2R16"
					( Origin gFrontEnd )
				)
				( attribute "MATERIAL" "X7R"
					( Origin gFrontEnd )
				)
				( attribute "PACK_TYPE" "0402V"
					( Origin gFrontEnd )
				)
				( attribute "PART_NUMBER" "A36096-030"
					( Origin gFrontEnd )
				)
				( attribute "PHYS_PAGE" "188"
					( Origin gFrontEnd )
				)
				( attribute "ROOM" "IO_MODULE"
					( Origin gFrontEnd )
				)
				( attribute "ROT" "0"
					( Origin gFrontEnd )
				)
				( attribute "SEC" "1"
					( Origin gPackager )
				)
				( attribute "TOLERANCE" "10%"
					( Origin gFrontEnd )
				)
				( attribute "VALUE" "0.1UF"
					( Origin gFrontEnd )
				)
				( attribute "VER" "1"
					( Origin gFrontEnd )
				)
				( attribute "VOLTAGE" "16V"
					( Units "uVoltage" "V" 1.000000)
					( Origin gFrontEnd )
				)
				( attribute "XY" "(475,1300)"
					( Origin gFrontEnd )
				)
				( attribute "CHIPS_PART_NAME" "CAP_A"
					( Origin gPackager )
				)
				( attribute "CDS_PART_NAME" "CAP_A_0402V-0.1UF,16V,10%,X7R,A"
					( Origin gPackager )
				)
				( objectStatus "C2R16" )
				( pin "a"
					( attribute "PN" "1"
						( Origin gPackager )
					)
					( objectStatus "C2R16.1" )
				)
				( pin "b"
					( attribute "PN" "2"
						( Origin gPackager )
					)
					( objectStatus "C2R16.2" )
				)
			)
			( gate "@baseboard_fab2_lib.baseboard_fab2(sch_1):page188_i41"
				( attribute "BOM_COST" "IO_MODULE"
					( Origin gFrontEnd )
				)
				( attribute "CDS_LIB" "mstr_discrete"
					( Origin gPackager )
				)
				( attribute "CDS_LOCATION" "C2P10"
					( Origin gPackager )
				)
				( attribute "CDS_SEC" "1"
					( Origin gPackager )
				)
				( attribute "LOCATION" "C2P10"
					( Origin gFrontEnd )
				)
				( attribute "MATERIAL" "X6S"
					( Origin gFrontEnd )
				)
				( attribute "PACK_TYPE" "1206LF"
					( Origin gFrontEnd )
				)
				( attribute "PART_NUMBER" "D38464-005"
					( Origin gFrontEnd )
				)
				( attribute "PHYS_PAGE" "188"
					( Origin gFrontEnd )
				)
				( attribute "ROOM" "IO_MODULE"
					( Origin gFrontEnd )
				)
				( attribute "ROT" "0"
					( Origin gFrontEnd )
				)
				( attribute "SEC" "1"
					( Origin gFrontEnd )
				)
				( attribute "SEC_TYPE" "1206LF"
					( Origin gFrontEnd )
				)
				( attribute "TOLERANCE" "10%"
					( Origin gFrontEnd )
				)
				( attribute "VALUE" "22UF"
					( Origin gFrontEnd )
				)
				( attribute "VER" "1"
					( Origin gFrontEnd )
				)
				( attribute "VOLTAGE" "16V"
					( Units "uVoltage" "V" 1.000000)
					( Origin gFrontEnd )
				)
				( attribute "XY" "(-75,1300)"
					( Origin gFrontEnd )
				)
				( attribute "CHIPS_PART_NAME" "CAP"
					( Origin gPackager )
				)
				( attribute "CDS_PART_NAME" "CAP_1206LF-22UF,16V,10%,X6S,D3A"
					( Origin gPackager )
				)
				( objectStatus "C2P10" )
				( pin "a"
					( attribute "PN" "1"
						( Origin gPackager )
					)
					( objectStatus "C2P10.1" )
				)
				( pin "b"
					( attribute "PN" "2"
						( Origin gPackager )
					)
					( objectStatus "C2P10.2" )
				)
			)
			( gate "@baseboard_fab2_lib.baseboard_fab2(sch_1):page188_i53"
				( attribute "BOM_COST" "IO_MODULE"
					( Origin gFrontEnd )
				)
				( attribute "CDS_LIB" "dev_discrete"
					( Origin gPackager )
				)
				( attribute "CDS_LOCATION" "C2P16"
					( Origin gPackager )
				)
				( attribute "CDS_SEC" "1"
					( Origin gPackager )
				)
				( attribute "LOCATION" "C2P16"
					( Origin gFrontEnd )
				)
				( attribute "MATERIAL" "X7R"
					( Origin gFrontEnd )
				)
				( attribute "PACK_TYPE" "0402V"
					( Origin gFrontEnd )
				)
				( attribute "PART_NUMBER" "A36096-030"
					( Origin gFrontEnd )
				)
				( attribute "PHYS_PAGE" "188"
					( Origin gFrontEnd )
				)
				( attribute "ROOM" "IO_MODULE"
					( Origin gFrontEnd )
				)
				( attribute "ROT" "0"
					( Origin gFrontEnd )
				)
				( attribute "SEC" "1"
					( Origin gPackager )
				)
				( attribute "TOLERANCE" "10%"
					( Origin gFrontEnd )
				)
				( attribute "VALUE" "0.1UF"
					( Origin gFrontEnd )
				)
				( attribute "VER" "1"
					( Origin gFrontEnd )
				)
				( attribute "VOLTAGE" "16V"
					( Units "uVoltage" "V" 1.000000)
					( Origin gFrontEnd )
				)
				( attribute "XY" "(-525,1300)"
					( Origin gFrontEnd )
				)
				( attribute "CHIPS_PART_NAME" "CAP_A"
					( Origin gPackager )
				)
				( attribute "CDS_PART_NAME" "CAP_A_0402V-0.1UF,16V,10%,X7R,A"
					( Origin gPackager )
				)
				( objectStatus "C2P16" )
				( pin "a"
					( attribute "PN" "1"
						( Origin gPackager )
					)
					( objectStatus "C2P16.1" )
				)
				( pin "b"
					( attribute "PN" "2"
						( Origin gPackager )
					)
					( objectStatus "C2P16.2" )
				)
			)
			( gate "@baseboard_fab2_lib.baseboard_fab2(sch_1):page188_i55"
				( attribute "BOM_COST" "IO_MODULE"
					( Origin gFrontEnd )
				)
				( attribute "CDS_LIB" "dev_discrete"
					( Origin gPackager )
				)
				( attribute "CDS_LOCATION" "C2P15"
					( Origin gPackager )
				)
				( attribute "CDS_SEC" "1"
					( Origin gPackager )
				)
				( attribute "LOCATION" "C2P15"
					( Origin gFrontEnd )
				)
				( attribute "MATERIAL" "X7R"
					( Origin gFrontEnd )
				)
				( attribute "PACK_TYPE" "0402V"
					( Origin gFrontEnd )
				)
				( attribute "PART_NUMBER" "A36096-030"
					( Origin gFrontEnd )
				)
				( attribute "PHYS_PAGE" "188"
					( Origin gFrontEnd )
				)
				( attribute "ROOM" "IO_MODULE"
					( Origin gFrontEnd )
				)
				( attribute "ROT" "0"
					( Origin gFrontEnd )
				)
				( attribute "SEC" "1"
					( Origin gPackager )
				)
				( attribute "TOLERANCE" "10%"
					( Origin gFrontEnd )
				)
				( attribute "VALUE" "0.1UF"
					( Origin gFrontEnd )
				)
				( attribute "VER" "1"
					( Origin gFrontEnd )
				)
				( attribute "VOLTAGE" "16V"
					( Units "uVoltage" "V" 1.000000)
					( Origin gFrontEnd )
				)
				( attribute "XY" "(-950,1300)"
					( Origin gFrontEnd )
				)
				( attribute "CHIPS_PART_NAME" "CAP_A"
					( Origin gPackager )
				)
				( attribute "CDS_PART_NAME" "CAP_A_0402V-0.1UF,16V,10%,X7R,A"
					( Origin gPackager )
				)
				( objectStatus "C2P15" )
				( pin "a"
					( attribute "PN" "1"
						( Origin gPackager )
					)
					( objectStatus "C2P15.1" )
				)
				( pin "b"
					( attribute "PN" "2"
						( Origin gPackager )
					)
					( objectStatus "C2P15.2" )
				)
			)
			( gate "@baseboard_fab2_lib.baseboard_fab2(sch_1):page188_i56"
				( attribute "BOM_COST" "IO_MODULE"
					( Origin gFrontEnd )
				)
				( attribute "CDS_LIB" "dev_discrete"
					( Origin gPackager )
				)
				( attribute "CDS_LOCATION" "C2P14"
					( Origin gPackager )
				)
				( attribute "CDS_SEC" "1"
					( Origin gPackager )
				)
				( attribute "LOCATION" "C2P14"
					( Origin gFrontEnd )
				)
				( attribute "MATERIAL" "X7R"
					( Origin gFrontEnd )
				)
				( attribute "PACK_TYPE" "0402V"
					( Origin gFrontEnd )
				)
				( attribute "PART_NUMBER" "A36096-030"
					( Origin gFrontEnd )
				)
				( attribute "PHYS_PAGE" "188"
					( Origin gFrontEnd )
				)
				( attribute "ROOM" "IO_MODULE"
					( Origin gFrontEnd )
				)
				( attribute "ROT" "0"
					( Origin gFrontEnd )
				)
				( attribute "SEC" "1"
					( Origin gPackager )
				)
				( attribute "TOLERANCE" "10%"
					( Origin gFrontEnd )
				)
				( attribute "VALUE" "0.1UF"
					( Origin gFrontEnd )
				)
				( attribute "VER" "1"
					( Origin gFrontEnd )
				)
				( attribute "VOLTAGE" "16V"
					( Units "uVoltage" "V" 1.000000)
					( Origin gFrontEnd )
				)
				( attribute "XY" "(-1400,1300)"
					( Origin gFrontEnd )
				)
				( attribute "CHIPS_PART_NAME" "CAP_A"
					( Origin gPackager )
				)
				( attribute "CDS_PART_NAME" "CAP_A_0402V-0.1UF,16V,10%,X7R,A"
					( Origin gPackager )
				)
				( objectStatus "C2P14" )
				( pin "a"
					( attribute "PN" "1"
						( Origin gPackager )
					)
					( objectStatus "C2P14.1" )
				)
				( pin "b"
					( attribute "PN" "2"
						( Origin gPackager )
					)
					( objectStatus "C2P14.2" )
				)
			)
			( gate "@baseboard_fab2_lib.baseboard_fab2(sch_1):page188_i57"
				( attribute "BOM_COST" "IO_MODULE"
					( Origin gFrontEnd )
				)
				( attribute "CDS_LIB" "dev_discrete"
					( Origin gPackager )
				)
				( attribute "CDS_LOCATION" "C2P13"
					( Origin gPackager )
				)
				( attribute "CDS_SEC" "1"
					( Origin gPackager )
				)
				( attribute "LOCATION" "C2P13"
					( Origin gFrontEnd )
				)
				( attribute "MATERIAL" "X7R"
					( Origin gFrontEnd )
				)
				( attribute "PACK_TYPE" "0402V"
					( Origin gFrontEnd )
				)
				( attribute "PART_NUMBER" "A36096-030"
					( Origin gFrontEnd )
				)
				( attribute "PHYS_PAGE" "188"
					( Origin gFrontEnd )
				)
				( attribute "ROOM" "IO_MODULE"
					( Origin gFrontEnd )
				)
				( attribute "ROT" "0"
					( Origin gFrontEnd )
				)
				( attribute "SEC" "1"
					( Origin gPackager )
				)
				( attribute "TOLERANCE" "10%"
					( Origin gFrontEnd )
				)
				( attribute "VALUE" "0.1UF"
					( Origin gFrontEnd )
				)
				( attribute "VER" "1"
					( Origin gFrontEnd )
				)
				( attribute "VOLTAGE" "16V"
					( Units "uVoltage" "V" 1.000000)
					( Origin gFrontEnd )
				)
				( attribute "XY" "(-1825,1300)"
					( Origin gFrontEnd )
				)
				( attribute "CHIPS_PART_NAME" "CAP_A"
					( Origin gPackager )
				)
				( attribute "CDS_PART_NAME" "CAP_A_0402V-0.1UF,16V,10%,X7R,A"
					( Origin gPackager )
				)
				( objectStatus "C2P13" )
				( pin "a"
					( attribute "PN" "1"
						( Origin gPackager )
					)
					( objectStatus "C2P13.1" )
				)
				( pin "b"
					( attribute "PN" "2"
						( Origin gPackager )
					)
					( objectStatus "C2P13.2" )
				)
			)
			( gate "@baseboard_fab2_lib.baseboard_fab2(sch_1):page188_i64"
				( attribute "CDS_LIB" "dev_discrete"
					( Origin gPackager )
				)
				( attribute "CDS_LOCATION" "C8C8"
					( Origin gPackager )
				)
				( attribute "CDS_SEC" "1"
					( Origin gPackager )
				)
				( attribute "LOCATION" "C8C8"
					( Origin gFrontEnd )
				)
				( attribute "MATERIAL" "X7R"
					( Origin gFrontEnd )
				)
				( attribute "PACK_TYPE" "0402V"
					( Origin gFrontEnd )
				)
				( attribute "PART_NUMBER" "A36096-030"
					( Origin gFrontEnd )
				)
				( attribute "PHYS_PAGE" "188"
					( Origin gFrontEnd )
				)
				( attribute "ROT" "0"
					( Origin gFrontEnd )
				)
				( attribute "SEC" "1"
					( Origin gFrontEnd )
				)
				( attribute "SEC_TYPE" "0402V"
					( Origin gFrontEnd )
				)
				( attribute "TOLERANCE" "10%"
					( Origin gFrontEnd )
				)
				( attribute "VALUE" "0.1UF"
					( Origin gFrontEnd )
				)
				( attribute "VER" "2"
					( Origin gFrontEnd )
				)
				( attribute "VOLTAGE" "16V"
					( Units "uVoltage" "V" 1.000000)
					( Origin gFrontEnd )
				)
				( attribute "XY" "(3075,4925)"
					( Origin gFrontEnd )
				)
				( attribute "CHIPS_PART_NAME" "CAP_A"
					( Origin gPackager )
				)
				( attribute "CDS_PART_NAME" "CAP_A_0402V-0.1UF,16V,10%,X7R,A"
					( Origin gPackager )
				)
				( objectStatus "C8C8" )
				( pin "a"
					( attribute "PN" "1"
						( Origin gPackager )
					)
					( objectStatus "C8C8.1" )
				)
				( pin "b"
					( attribute "PN" "2"
						( Origin gPackager )
					)
					( objectStatus "C8C8.2" )
				)
			)
			( gate "@baseboard_fab2_lib.baseboard_fab2(sch_1):page188_i68"
				( attribute "CDS_LIB" "dev_discrete"
					( Origin gPackager )
				)
				( attribute "CDS_LOCATION" "C8C9"
					( Origin gPackager )
				)
				( attribute "CDS_SEC" "1"
					( Origin gPackager )
				)
				( attribute "LOCATION" "C8C9"
					( Origin gFrontEnd )
				)
				( attribute "MATERIAL" "X7R"
					( Origin gFrontEnd )
				)
				( attribute "PACK_TYPE" "0402V"
					( Origin gFrontEnd )
				)
				( attribute "PART_NUMBER" "A36096-030"
					( Origin gFrontEnd )
				)
				( attribute "PHYS_PAGE" "188"
					( Origin gFrontEnd )
				)
				( attribute "ROT" "0"
					( Origin gFrontEnd )
				)
				( attribute "SEC" "1"
					( Origin gFrontEnd )
				)
				( attribute "SEC_TYPE" "0402V"
					( Origin gFrontEnd )
				)
				( attribute "TOLERANCE" "10%"
					( Origin gFrontEnd )
				)
				( attribute "VALUE" "0.1UF"
					( Origin gFrontEnd )
				)
				( attribute "VER" "2"
					( Origin gFrontEnd )
				)
				( attribute "VOLTAGE" "16V"
					( Units "uVoltage" "V" 1.000000)
					( Origin gFrontEnd )
				)
				( attribute "XY" "(3075,4600)"
					( Origin gFrontEnd )
				)
				( attribute "CHIPS_PART_NAME" "CAP_A"
					( Origin gPackager )
				)
				( attribute "CDS_PART_NAME" "CAP_A_0402V-0.1UF,16V,10%,X7R,A"
					( Origin gPackager )
				)
				( objectStatus "C8C9" )
				( pin "a"
					( attribute "PN" "1"
						( Origin gPackager )
					)
					( objectStatus "C8C9.1" )
				)
				( pin "b"
					( attribute "PN" "2"
						( Origin gPackager )
					)
					( objectStatus "C8C9.2" )
				)
			)
			( gate "@baseboard_fab2_lib.baseboard_fab2(sch_1):page188_i72"
				( attribute "CDS_LIB" "dev_discrete"
					( Origin gPackager )
				)
				( attribute "CDS_LOCATION" "C8C11"
					( Origin gPackager )
				)
				( attribute "CDS_SEC" "1"
					( Origin gPackager )
				)
				( attribute "LOCATION" "C8C11"
					( Origin gFrontEnd )
				)
				( attribute "MATERIAL" "X7R"
					( Origin gFrontEnd )
				)
				( attribute "PACK_TYPE" "0402V"
					( Origin gFrontEnd )
				)
				( attribute "PART_NUMBER" "A36096-030"
					( Origin gFrontEnd )
				)
				( attribute "PHYS_PAGE" "188"
					( Origin gFrontEnd )
				)
				( attribute "ROT" "0"
					( Origin gFrontEnd )
				)
				( attribute "SEC" "1"
					( Origin gFrontEnd )
				)
				( attribute "SEC_TYPE" "0402V"
					( Origin gFrontEnd )
				)
				( attribute "TOLERANCE" "10%"
					( Origin gFrontEnd )
				)
				( attribute "VALUE" "0.1UF"
					( Origin gFrontEnd )
				)
				( attribute "VER" "2"
					( Origin gFrontEnd )
				)
				( attribute "VOLTAGE" "16V"
					( Units "uVoltage" "V" 1.000000)
					( Origin gFrontEnd )
				)
				( attribute "XY" "(3075,4250)"
					( Origin gFrontEnd )
				)
				( attribute "CHIPS_PART_NAME" "CAP_A"
					( Origin gPackager )
				)
				( attribute "CDS_PART_NAME" "CAP_A_0402V-0.1UF,16V,10%,X7R,A"
					( Origin gPackager )
				)
				( objectStatus "C8C11" )
				( pin "a"
					( attribute "PN" "1"
						( Origin gPackager )
					)
					( objectStatus "C8C11.1" )
				)
				( pin "b"
					( attribute "PN" "2"
						( Origin gPackager )
					)
					( objectStatus "C8C11.2" )
				)
			)
			( gate "@baseboard_fab2_lib.baseboard_fab2(sch_1):page188_i73"
				( attribute "CDS_LIB" "dev_discrete"
					( Origin gPackager )
				)
				( attribute "CDS_LOCATION" "C8C10"
					( Origin gPackager )
				)
				( attribute "CDS_SEC" "1"
					( Origin gPackager )
				)
				( attribute "LOCATION" "C8C10"
					( Origin gFrontEnd )
				)
				( attribute "MATERIAL" "X7R"
					( Origin gFrontEnd )
				)
				( attribute "PACK_TYPE" "0402V"
					( Origin gFrontEnd )
				)
				( attribute "PART_NUMBER" "A36096-030"
					( Origin gFrontEnd )
				)
				( attribute "PHYS_PAGE" "188"
					( Origin gFrontEnd )
				)
				( attribute "ROT" "0"
					( Origin gFrontEnd )
				)
				( attribute "SEC" "1"
					( Origin gFrontEnd )
				)
				( attribute "SEC_TYPE" "0402V"
					( Origin gFrontEnd )
				)
				( attribute "TOLERANCE" "10%"
					( Origin gFrontEnd )
				)
				( attribute "VALUE" "0.1UF"
					( Origin gFrontEnd )
				)
				( attribute "VER" "2"
					( Origin gFrontEnd )
				)
				( attribute "VOLTAGE" "16V"
					( Units "uVoltage" "V" 1.000000)
					( Origin gFrontEnd )
				)
				( attribute "XY" "(3075,3925)"
					( Origin gFrontEnd )
				)
				( attribute "CHIPS_PART_NAME" "CAP_A"
					( Origin gPackager )
				)
				( attribute "CDS_PART_NAME" "CAP_A_0402V-0.1UF,16V,10%,X7R,A"
					( Origin gPackager )
				)
				( objectStatus "C8C10" )
				( pin "a"
					( attribute "PN" "1"
						( Origin gPackager )
					)
					( objectStatus "C8C10.1" )
				)
				( pin "b"
					( attribute "PN" "2"
						( Origin gPackager )
					)
					( objectStatus "C8C10.2" )
				)
			)
			( gate "@baseboard_fab2_lib.baseboard_fab2(sch_1):page188_i80"
				( attribute "CDS_LIB" "dev_discrete"
					( Origin gPackager )
				)
				( attribute "CDS_LOCATION" "C8C12"
					( Origin gPackager )
				)
				( attribute "CDS_SEC" "1"
					( Origin gPackager )
				)
				( attribute "LOCATION" "C8C12"
					( Origin gFrontEnd )
				)
				( attribute "MATERIAL" "X7R"
					( Origin gFrontEnd )
				)
				( attribute "PACK_TYPE" "0402V"
					( Origin gFrontEnd )
				)
				( attribute "PART_NUMBER" "A36096-030"
					( Origin gFrontEnd )
				)
				( attribute "PHYS_PAGE" "188"
					( Origin gFrontEnd )
				)
				( attribute "ROT" "0"
					( Origin gFrontEnd )
				)
				( attribute "SEC" "1"
					( Origin gFrontEnd )
				)
				( attribute "SEC_TYPE" "0402V"
					( Origin gFrontEnd )
				)
				( attribute "TOLERANCE" "10%"
					( Origin gFrontEnd )
				)
				( attribute "VALUE" "0.1UF"
					( Origin gFrontEnd )
				)
				( attribute "VER" "2"
					( Origin gFrontEnd )
				)
				( attribute "VOLTAGE" "16V"
					( Units "uVoltage" "V" 1.000000)
					( Origin gFrontEnd )
				)
				( attribute "XY" "(3075,3600)"
					( Origin gFrontEnd )
				)
				( attribute "CHIPS_PART_NAME" "CAP_A"
					( Origin gPackager )
				)
				( attribute "CDS_PART_NAME" "CAP_A_0402V-0.1UF,16V,10%,X7R,A"
					( Origin gPackager )
				)
				( objectStatus "C8C12" )
				( pin "a"
					( attribute "PN" "1"
						( Origin gPackager )
					)
					( objectStatus "C8C12.1" )
				)
				( pin "b"
					( attribute "PN" "2"
						( Origin gPackager )
					)
					( objectStatus "C8C12.2" )
				)
			)
			( gate "@baseboard_fab2_lib.baseboard_fab2(sch_1):page188_i81"
				( attribute "CDS_LIB" "dev_discrete"
					( Origin gPackager )
				)
				( attribute "CDS_LOCATION" "C8C13"
					( Origin gPackager )
				)
				( attribute "CDS_SEC" "1"
					( Origin gPackager )
				)
				( attribute "LOCATION" "C8C13"
					( Origin gFrontEnd )
				)
				( attribute "MATERIAL" "X7R"
					( Origin gFrontEnd )
				)
				( attribute "PACK_TYPE" "0402V"
					( Origin gFrontEnd )
				)
				( attribute "PART_NUMBER" "A36096-030"
					( Origin gFrontEnd )
				)
				( attribute "PHYS_PAGE" "188"
					( Origin gFrontEnd )
				)
				( attribute "ROT" "0"
					( Origin gFrontEnd )
				)
				( attribute "SEC" "1"
					( Origin gFrontEnd )
				)
				( attribute "SEC_TYPE" "0402V"
					( Origin gFrontEnd )
				)
				( attribute "TOLERANCE" "10%"
					( Origin gFrontEnd )
				)
				( attribute "VALUE" "0.1UF"
					( Origin gFrontEnd )
				)
				( attribute "VER" "2"
					( Origin gFrontEnd )
				)
				( attribute "VOLTAGE" "16V"
					( Units "uVoltage" "V" 1.000000)
					( Origin gFrontEnd )
				)
				( attribute "XY" "(3075,3275)"
					( Origin gFrontEnd )
				)
				( attribute "CHIPS_PART_NAME" "CAP_A"
					( Origin gPackager )
				)
				( attribute "CDS_PART_NAME" "CAP_A_0402V-0.1UF,16V,10%,X7R,A"
					( Origin gPackager )
				)
				( objectStatus "C8C13" )
				( pin "a"
					( attribute "PN" "1"
						( Origin gPackager )
					)
					( objectStatus "C8C13.1" )
				)
				( pin "b"
					( attribute "PN" "2"
						( Origin gPackager )
					)
					( objectStatus "C8C13.2" )
				)
			)
			( gate "@baseboard_fab2_lib.baseboard_fab2(sch_1):page188_i82"
				( attribute "CDS_LIB" "dev_discrete"
					( Origin gPackager )
				)
				( attribute "CDS_LOCATION" "C8C15"
					( Origin gPackager )
				)
				( attribute "CDS_SEC" "1"
					( Origin gPackager )
				)
				( attribute "LOCATION" "C8C15"
					( Origin gFrontEnd )
				)
				( attribute "MATERIAL" "X7R"
					( Origin gFrontEnd )
				)
				( attribute "PACK_TYPE" "0402V"
					( Origin gFrontEnd )
				)
				( attribute "PART_NUMBER" "A36096-030"
					( Origin gFrontEnd )
				)
				( attribute "PHYS_PAGE" "188"
					( Origin gFrontEnd )
				)
				( attribute "ROT" "0"
					( Origin gFrontEnd )
				)
				( attribute "SEC" "1"
					( Origin gFrontEnd )
				)
				( attribute "SEC_TYPE" "0402V"
					( Origin gFrontEnd )
				)
				( attribute "TOLERANCE" "10%"
					( Origin gFrontEnd )
				)
				( attribute "VALUE" "0.1UF"
					( Origin gFrontEnd )
				)
				( attribute "VER" "2"
					( Origin gFrontEnd )
				)
				( attribute "VOLTAGE" "16V"
					( Units "uVoltage" "V" 1.000000)
					( Origin gFrontEnd )
				)
				( attribute "XY" "(3075,2925)"
					( Origin gFrontEnd )
				)
				( attribute "CHIPS_PART_NAME" "CAP_A"
					( Origin gPackager )
				)
				( attribute "CDS_PART_NAME" "CAP_A_0402V-0.1UF,16V,10%,X7R,A"
					( Origin gPackager )
				)
				( objectStatus "C8C15" )
				( pin "a"
					( attribute "PN" "1"
						( Origin gPackager )
					)
					( objectStatus "C8C15.1" )
				)
				( pin "b"
					( attribute "PN" "2"
						( Origin gPackager )
					)
					( objectStatus "C8C15.2" )
				)
			)
			( gate "@baseboard_fab2_lib.baseboard_fab2(sch_1):page188_i86"
				( attribute "CDS_LIB" "dev_discrete"
					( Origin gPackager )
				)
				( attribute "CDS_LOCATION" "C8C14"
					( Origin gPackager )
				)
				( attribute "CDS_SEC" "1"
					( Origin gPackager )
				)
				( attribute "LOCATION" "C8C14"
					( Origin gFrontEnd )
				)
				( attribute "MATERIAL" "X7R"
					( Origin gFrontEnd )
				)
				( attribute "PACK_TYPE" "0402V"
					( Origin gFrontEnd )
				)
				( attribute "PART_NUMBER" "A36096-030"
					( Origin gFrontEnd )
				)
				( attribute "PHYS_PAGE" "188"
					( Origin gFrontEnd )
				)
				( attribute "ROT" "0"
					( Origin gFrontEnd )
				)
				( attribute "SEC" "1"
					( Origin gFrontEnd )
				)
				( attribute "SEC_TYPE" "0402V"
					( Origin gFrontEnd )
				)
				( attribute "TOLERANCE" "10%"
					( Origin gFrontEnd )
				)
				( attribute "VALUE" "0.1UF"
					( Origin gFrontEnd )
				)
				( attribute "VER" "2"
					( Origin gFrontEnd )
				)
				( attribute "VOLTAGE" "16V"
					( Units "uVoltage" "V" 1.000000)
					( Origin gFrontEnd )
				)
				( attribute "XY" "(3075,2600)"
					( Origin gFrontEnd )
				)
				( attribute "CHIPS_PART_NAME" "CAP_A"
					( Origin gPackager )
				)
				( attribute "CDS_PART_NAME" "CAP_A_0402V-0.1UF,16V,10%,X7R,A"
					( Origin gPackager )
				)
				( objectStatus "C8C14" )
				( pin "a"
					( attribute "PN" "1"
						( Origin gPackager )
					)
					( objectStatus "C8C14.1" )
				)
				( pin "b"
					( attribute "PN" "2"
						( Origin gPackager )
					)
					( objectStatus "C8C14.2" )
				)
			)
			( gate "@baseboard_fab2_lib.baseboard_fab2(sch_1):page188_i88"
				( attribute "CDS_LIB" "mstr_discrete"
					( Origin gPackager )
				)
				( attribute "CDS_LOCATION" "R1R18"
					( Origin gPackager )
				)
				( attribute "CDS_SEC" "1"
					( Origin gPackager )
				)
				( attribute "LOCATION" "R1R18"
					( Origin gFrontEnd )
				)
				( attribute "MATERIAL" "CHIP"
					( Origin gFrontEnd )
				)
				( attribute "PACK_TYPE" "0402"
					( Origin gFrontEnd )
				)
				( attribute "PART_NUMBER" "G21796-112"
					( Origin gFrontEnd )
				)
				( attribute "PHYS_PAGE" "188"
					( Origin gFrontEnd )
				)
				( attribute "ROT" "0"
					( Origin gFrontEnd )
				)
				( attribute "SEC" "1"
					( Origin gFrontEnd )
				)
				( attribute "SEC_TYPE" "0402"
					( Origin gFrontEnd )
				)
				( attribute "TOLERANCE" "1%"
					( Origin gFrontEnd )
				)
				( attribute "VALUE" "2.21K"
					( Origin gFrontEnd )
				)
				( attribute "VER" "1"
					( Origin gFrontEnd )
				)
				( attribute "WATTAGE" "1/16W"
					( Origin gFrontEnd )
				)
				( attribute "XY" "(-3250,3950)"
					( Origin gFrontEnd )
				)
				( attribute "CHIPS_PART_NAME" "RES"
					( Origin gPackager )
				)
				( attribute "CDS_PART_NAME" "RES_0402-2.21K,1%,1/16W,CHIP,GA"
					( Origin gPackager )
				)
				( objectStatus "R1R18" )
				( pin "a"
					( attribute "PN" "1"
						( Origin gPackager )
					)
					( objectStatus "R1R18.1" )
				)
				( pin "b"
					( attribute "PN" "2"
						( Origin gPackager )
					)
					( objectStatus "R1R18.2" )
				)
			)
			( gate "@baseboard_fab2_lib.baseboard_fab2(sch_1):page188_i89"
				( attribute "CDS_LIB" "mstr_discrete"
					( Origin gPackager )
				)
				( attribute "CDS_LOCATION" "R1R19"
					( Origin gPackager )
				)
				( attribute "CDS_SEC" "1"
					( Origin gPackager )
				)
				( attribute "LOCATION" "R1R19"
					( Origin gFrontEnd )
				)
				( attribute "MATERIAL" "CHIP"
					( Origin gFrontEnd )
				)
				( attribute "PACK_TYPE" "0402"
					( Origin gFrontEnd )
				)
				( attribute "PART_NUMBER" "G21796-112"
					( Origin gFrontEnd )
				)
				( attribute "PHYS_PAGE" "188"
					( Origin gFrontEnd )
				)
				( attribute "ROT" "0"
					( Origin gFrontEnd )
				)
				( attribute "SEC" "1"
					( Origin gFrontEnd )
				)
				( attribute "SEC_TYPE" "0402"
					( Origin gFrontEnd )
				)
				( attribute "TOLERANCE" "1%"
					( Origin gFrontEnd )
				)
				( attribute "VALUE" "2.21K"
					( Origin gFrontEnd )
				)
				( attribute "VER" "1"
					( Origin gFrontEnd )
				)
				( attribute "WATTAGE" "1/16W"
					( Origin gFrontEnd )
				)
				( attribute "XY" "(-3250,3650)"
					( Origin gFrontEnd )
				)
				( attribute "CHIPS_PART_NAME" "RES"
					( Origin gPackager )
				)
				( attribute "CDS_PART_NAME" "RES_0402-2.21K,1%,1/16W,CHIP,GA"
					( Origin gPackager )
				)
				( objectStatus "R1R19" )
				( pin "a"
					( attribute "PN" "1"
						( Origin gPackager )
					)
					( objectStatus "R1R19.1" )
				)
				( pin "b"
					( attribute "PN" "2"
						( Origin gPackager )
					)
					( objectStatus "R1R19.2" )
				)
			)
			( gate "@baseboard_fab2_lib.baseboard_fab2(sch_1):page188_i90"
				( attribute "CDS_LIB" "mstr_discrete"
					( Origin gPackager )
				)
				( attribute "CDS_LOCATION" "R1R21"
					( Origin gPackager )
				)
				( attribute "CDS_SEC" "1"
					( Origin gPackager )
				)
				( attribute "LOCATION" "R1R21"
					( Origin gFrontEnd )
				)
				( attribute "MATERIAL" "CHIP"
					( Origin gFrontEnd )
				)
				( attribute "PACK_TYPE" "0402"
					( Origin gFrontEnd )
				)
				( attribute "PART_NUMBER" "G21796-112"
					( Origin gFrontEnd )
				)
				( attribute "PHYS_PAGE" "188"
					( Origin gFrontEnd )
				)
				( attribute "ROT" "0"
					( Origin gFrontEnd )
				)
				( attribute "SEC" "1"
					( Origin gFrontEnd )
				)
				( attribute "SEC_TYPE" "0402"
					( Origin gFrontEnd )
				)
				( attribute "TOLERANCE" "1%"
					( Origin gFrontEnd )
				)
				( attribute "VALUE" "2.21K"
					( Origin gFrontEnd )
				)
				( attribute "VER" "1"
					( Origin gFrontEnd )
				)
				( attribute "WATTAGE" "1/16W"
					( Origin gFrontEnd )
				)
				( attribute "XY" "(-3250,3050)"
					( Origin gFrontEnd )
				)
				( attribute "CHIPS_PART_NAME" "RES"
					( Origin gPackager )
				)
				( attribute "CDS_PART_NAME" "RES_0402-2.21K,1%,1/16W,CHIP,GA"
					( Origin gPackager )
				)
				( objectStatus "R1R21" )
				( pin "a"
					( attribute "PN" "1"
						( Origin gPackager )
					)
					( objectStatus "R1R21.1" )
				)
				( pin "b"
					( attribute "PN" "2"
						( Origin gPackager )
					)
					( objectStatus "R1R21.2" )
				)
			)
			( gate "@baseboard_fab2_lib.baseboard_fab2(sch_1):page188_i91"
				( attribute "CDS_LIB" "mstr_discrete"
					( Origin gPackager )
				)
				( attribute "CDS_LOCATION" "R1R20"
					( Origin gPackager )
				)
				( attribute "CDS_SEC" "1"
					( Origin gPackager )
				)
				( attribute "LOCATION" "R1R20"
					( Origin gFrontEnd )
				)
				( attribute "MATERIAL" "CHIP"
					( Origin gFrontEnd )
				)
				( attribute "PACK_TYPE" "0402"
					( Origin gFrontEnd )
				)
				( attribute "PART_NUMBER" "G21796-112"
					( Origin gFrontEnd )
				)
				( attribute "PHYS_PAGE" "188"
					( Origin gFrontEnd )
				)
				( attribute "ROT" "0"
					( Origin gFrontEnd )
				)
				( attribute "SEC" "1"
					( Origin gFrontEnd )
				)
				( attribute "SEC_TYPE" "0402"
					( Origin gFrontEnd )
				)
				( attribute "TOLERANCE" "1%"
					( Origin gFrontEnd )
				)
				( attribute "VALUE" "2.21K"
					( Origin gFrontEnd )
				)
				( attribute "VER" "1"
					( Origin gFrontEnd )
				)
				( attribute "WATTAGE" "1/16W"
					( Origin gFrontEnd )
				)
				( attribute "XY" "(-3250,3350)"
					( Origin gFrontEnd )
				)
				( attribute "CHIPS_PART_NAME" "RES"
					( Origin gPackager )
				)
				( attribute "CDS_PART_NAME" "RES_0402-2.21K,1%,1/16W,CHIP,GA"
					( Origin gPackager )
				)
				( objectStatus "R1R20" )
				( pin "a"
					( attribute "PN" "1"
						( Origin gPackager )
					)
					( objectStatus "R1R20.1" )
				)
				( pin "b"
					( attribute "PN" "2"
						( Origin gPackager )
					)
					( objectStatus "R1R20.2" )
				)
			)
			( gate "@baseboard_fab2_lib.baseboard_fab2(sch_1):page188_i92"
				( attribute "CDS_LIB" "mstr_discrete"
					( Origin gPackager )
				)
				( attribute "CDS_LOCATION" "R1R22"
					( Origin gPackager )
				)
				( attribute "CDS_SEC" "1"
					( Origin gPackager )
				)
				( attribute "LOCATION" "R1R22"
					( Origin gFrontEnd )
				)
				( attribute "MATERIAL" "CHIP"
					( Origin gFrontEnd )
				)
				( attribute "PACK_TYPE" "0402"
					( Origin gFrontEnd )
				)
				( attribute "PART_NUMBER" "G21796-112"
					( Origin gFrontEnd )
				)
				( attribute "PHYS_PAGE" "188"
					( Origin gFrontEnd )
				)
				( attribute "ROT" "0"
					( Origin gFrontEnd )
				)
				( attribute "SEC" "1"
					( Origin gFrontEnd )
				)
				( attribute "SEC_TYPE" "0402"
					( Origin gFrontEnd )
				)
				( attribute "TOLERANCE" "1%"
					( Origin gFrontEnd )
				)
				( attribute "VALUE" "2.21K"
					( Origin gFrontEnd )
				)
				( attribute "VER" "1"
					( Origin gFrontEnd )
				)
				( attribute "WATTAGE" "1/16W"
					( Origin gFrontEnd )
				)
				( attribute "XY" "(-3250,1825)"
					( Origin gFrontEnd )
				)
				( attribute "CHIPS_PART_NAME" "RES"
					( Origin gPackager )
				)
				( attribute "CDS_PART_NAME" "RES_0402-2.21K,1%,1/16W,CHIP,GA"
					( Origin gPackager )
				)
				( objectStatus "R1R22" )
				( pin "a"
					( attribute "PN" "1"
						( Origin gPackager )
					)
					( objectStatus "R1R22.1" )
				)
				( pin "b"
					( attribute "PN" "2"
						( Origin gPackager )
					)
					( objectStatus "R1R22.2" )
				)
			)
			( gate "@baseboard_fab2_lib.baseboard_fab2(sch_1):page188_i93"
				( attribute "CDS_LIB" "mstr_discrete"
					( Origin gPackager )
				)
				( attribute "CDS_LOCATION" "R1R16"
					( Origin gPackager )
				)
				( attribute "CDS_SEC" "1"
					( Origin gPackager )
				)
				( attribute "LOCATION" "R1R16"
					( Origin gFrontEnd )
				)
				( attribute "MATERIAL" "CHIP"
					( Origin gFrontEnd )
				)
				( attribute "PACK_TYPE" "0402"
					( Origin gFrontEnd )
				)
				( attribute "PART_NUMBER" "G21796-112"
					( Origin gFrontEnd )
				)
				( attribute "PHYS_PAGE" "188"
					( Origin gFrontEnd )
				)
				( attribute "ROT" "0"
					( Origin gFrontEnd )
				)
				( attribute "SEC" "1"
					( Origin gFrontEnd )
				)
				( attribute "SEC_TYPE" "0402"
					( Origin gFrontEnd )
				)
				( attribute "TOLERANCE" "1%"
					( Origin gFrontEnd )
				)
				( attribute "VALUE" "2.21K"
					( Origin gFrontEnd )
				)
				( attribute "VER" "1"
					( Origin gFrontEnd )
				)
				( attribute "WATTAGE" "1/16W"
					( Origin gFrontEnd )
				)
				( attribute "XY" "(-3250,2725)"
					( Origin gFrontEnd )
				)
				( attribute "CHIPS_PART_NAME" "RES"
					( Origin gPackager )
				)
				( attribute "CDS_PART_NAME" "RES_0402-2.21K,1%,1/16W,CHIP,GA"
					( Origin gPackager )
				)
				( objectStatus "R1R16" )
				( pin "a"
					( attribute "PN" "1"
						( Origin gPackager )
					)
					( objectStatus "R1R16.1" )
				)
				( pin "b"
					( attribute "PN" "2"
						( Origin gPackager )
					)
					( objectStatus "R1R16.2" )
				)
			)
			( gate "@baseboard_fab2_lib.baseboard_fab2(sch_1):page188_i94"
				( attribute "CDS_LIB" "mstr_discrete"
					( Origin gPackager )
				)
				( attribute "CDS_LOCATION" "R1R17"
					( Origin gPackager )
				)
				( attribute "CDS_SEC" "1"
					( Origin gPackager )
				)
				( attribute "LOCATION" "R1R17"
					( Origin gFrontEnd )
				)
				( attribute "MATERIAL" "CHIP"
					( Origin gFrontEnd )
				)
				( attribute "PACK_TYPE" "0402"
					( Origin gFrontEnd )
				)
				( attribute "PART_NUMBER" "G21796-112"
					( Origin gFrontEnd )
				)
				( attribute "PHYS_PAGE" "188"
					( Origin gFrontEnd )
				)
				( attribute "ROT" "0"
					( Origin gFrontEnd )
				)
				( attribute "SEC" "1"
					( Origin gFrontEnd )
				)
				( attribute "SEC_TYPE" "0402"
					( Origin gFrontEnd )
				)
				( attribute "TOLERANCE" "1%"
					( Origin gFrontEnd )
				)
				( attribute "VALUE" "2.21K"
					( Origin gFrontEnd )
				)
				( attribute "VER" "1"
					( Origin gFrontEnd )
				)
				( attribute "WATTAGE" "1/16W"
					( Origin gFrontEnd )
				)
				( attribute "XY" "(-3250,2425)"
					( Origin gFrontEnd )
				)
				( attribute "CHIPS_PART_NAME" "RES"
					( Origin gPackager )
				)
				( attribute "CDS_PART_NAME" "RES_0402-2.21K,1%,1/16W,CHIP,GA"
					( Origin gPackager )
				)
				( objectStatus "R1R17" )
				( pin "a"
					( attribute "PN" "1"
						( Origin gPackager )
					)
					( objectStatus "R1R17.1" )
				)
				( pin "b"
					( attribute "PN" "2"
						( Origin gPackager )
					)
					( objectStatus "R1R17.2" )
				)
			)
			( gate "@baseboard_fab2_lib.baseboard_fab2(sch_1):page188_i95"
				( attribute "CDS_LIB" "mstr_discrete"
					( Origin gPackager )
				)
				( attribute "CDS_LOCATION" "R1R23"
					( Origin gPackager )
				)
				( attribute "CDS_SEC" "1"
					( Origin gPackager )
				)
				( attribute "LOCATION" "R1R23"
					( Origin gFrontEnd )
				)
				( attribute "MATERIAL" "CHIP"
					( Origin gFrontEnd )
				)
				( attribute "PACK_TYPE" "0402"
					( Origin gFrontEnd )
				)
				( attribute "PART_NUMBER" "G21796-112"
					( Origin gFrontEnd )
				)
				( attribute "PHYS_PAGE" "188"
					( Origin gFrontEnd )
				)
				( attribute "ROT" "0"
					( Origin gFrontEnd )
				)
				( attribute "SEC" "1"
					( Origin gFrontEnd )
				)
				( attribute "SEC_TYPE" "0402"
					( Origin gFrontEnd )
				)
				( attribute "TOLERANCE" "1%"
					( Origin gFrontEnd )
				)
				( attribute "VALUE" "2.21K"
					( Origin gFrontEnd )
				)
				( attribute "VER" "1"
					( Origin gFrontEnd )
				)
				( attribute "WATTAGE" "1/16W"
					( Origin gFrontEnd )
				)
				( attribute "XY" "(-3250,2125)"
					( Origin gFrontEnd )
				)
				( attribute "CHIPS_PART_NAME" "RES"
					( Origin gPackager )
				)
				( attribute "CDS_PART_NAME" "RES_0402-2.21K,1%,1/16W,CHIP,GA"
					( Origin gPackager )
				)
				( objectStatus "R1R23" )
				( pin "a"
					( attribute "PN" "1"
						( Origin gPackager )
					)
					( objectStatus "R1R23.1" )
				)
				( pin "b"
					( attribute "PN" "2"
						( Origin gPackager )
					)
					( objectStatus "R1R23.2" )
				)
			)
			( gate "@baseboard_fab2_lib.baseboard_fab2(sch_1):page189_i7"
				( attribute "BOM_COST" "DEBUG"
					( Origin gFrontEnd )
				)
				( attribute "CDS_LIB" "mstr_discrete"
					( Origin gPackager )
				)
				( attribute "CDS_LOCATION" "R8G10"
					( Origin gPackager )
				)
				( attribute "CDS_SEC" "1"
					( Origin gPackager )
				)
				( attribute "LOCATION" "R8G10"
					( Origin gFrontEnd )
				)
				( attribute "MATERIAL" "CHIP"
					( Origin gFrontEnd )
				)
				( attribute "PACK_TYPE" "0402"
					( Origin gFrontEnd )
				)
				( attribute "PART_NUMBER" "G21497-005"
					( Origin gFrontEnd )
				)
				( attribute "PHYS_PAGE" "189"
					( Origin gFrontEnd )
				)
				( attribute "ROOM" "BMC_DEBUG_HEADER"
					( Origin gFrontEnd )
				)
				( attribute "ROT" "0"
					( Origin gFrontEnd )
				)
				( attribute "SEC" "1"
					( Origin gFrontEnd )
				)
				( attribute "SEC_TYPE" "0402"
					( Origin gFrontEnd )
				)
				( attribute "TOLERANCE" "5%"
					( Origin gFrontEnd )
				)
				( attribute "VALUE" "0.0"
					( Origin gFrontEnd )
				)
				( attribute "VER" "1"
					( Origin gFrontEnd )
				)
				( attribute "WATTAGE" "1/16W"
					( Origin gFrontEnd )
				)
				( attribute "XY" "(-1900,4675)"
					( Origin gFrontEnd )
				)
				( attribute "CHIPS_PART_NAME" "RES"
					( Origin gPackager )
				)
				( attribute "CDS_PART_NAME" "RES_0402-0.0,5%,1/16W,CHIP,G21A"
					( Origin gPackager )
				)
				( objectStatus "R8G10" )
				( pin "a"
					( attribute "PN" "1"
						( Origin gPackager )
					)
					( objectStatus "R8G10.1" )
				)
				( pin "b"
					( attribute "PN" "2"
						( Origin gPackager )
					)
					( objectStatus "R8G10.2" )
				)
			)
			( gate "@baseboard_fab2_lib.baseboard_fab2(sch_1):page189_i8"
				( attribute "BOM_COST" "DEBUG"
					( Origin gFrontEnd )
				)
				( attribute "CDS_LIB" "mstr_discrete"
					( Origin gPackager )
				)
				( attribute "CDS_LOCATION" "R7G19"
					( Origin gPackager )
				)
				( attribute "CDS_SEC" "1"
					( Origin gPackager )
				)
				( attribute "LOCATION" "R7G19"
					( Origin gFrontEnd )
				)
				( attribute "MATERIAL" "EMPTY"
					( Origin gFrontEnd )
				)
				( attribute "PACK_TYPE" "0402"
					( Origin gFrontEnd )
				)
				( attribute "PART_NUMBER" "G21497-005"
					( Origin gFrontEnd )
				)
				( attribute "PHYS_PAGE" "189"
					( Origin gFrontEnd )
				)
				( attribute "ROOM" "BMC_DEBUG_HEADER"
					( Origin gFrontEnd )
				)
				( attribute "ROT" "0"
					( Origin gFrontEnd )
				)
				( attribute "SEC" "1"
					( Origin gFrontEnd )
				)
				( attribute "SEC_TYPE" "0402"
					( Origin gFrontEnd )
				)
				( attribute "TOLERANCE" "5%"
					( Origin gFrontEnd )
				)
				( attribute "VALUE" "0.0"
					( Origin gFrontEnd )
				)
				( attribute "VER" "1"
					( Origin gFrontEnd )
				)
				( attribute "WATTAGE" "1/16W"
					( Origin gFrontEnd )
				)
				( attribute "XY" "(-1900,4300)"
					( Origin gFrontEnd )
				)
				( attribute "CHIPS_PART_NAME" "RES"
					( Origin gPackager )
				)
				( attribute "CDS_PART_NAME" "RES_0402-0.0,5%,1/16W,EMPTY,G2A"
					( Origin gPackager )
				)
				( objectStatus "R7G19" )
				( pin "a"
					( attribute "PN" "1"
						( Origin gPackager )
					)
					( objectStatus "R7G19.1" )
				)
				( pin "b"
					( attribute "PN" "2"
						( Origin gPackager )
					)
					( objectStatus "R7G19.2" )
				)
			)
			( gate "@baseboard_fab2_lib.baseboard_fab2(sch_1):page189_i9"
				( attribute "BOM_COST" "DEBUG"
					( Origin gFrontEnd )
				)
				( attribute "CDS_LIB" "mstr_discrete"
					( Origin gPackager )
				)
				( attribute "CDS_LOCATION" "R8G9"
					( Origin gPackager )
				)
				( attribute "CDS_SEC" "1"
					( Origin gPackager )
				)
				( attribute "LOCATION" "R8G9"
					( Origin gFrontEnd )
				)
				( attribute "MATERIAL" "EMPTY"
					( Origin gFrontEnd )
				)
				( attribute "PACK_TYPE" "0402"
					( Origin gFrontEnd )
				)
				( attribute "PART_NUMBER" "G21497-005"
					( Origin gFrontEnd )
				)
				( attribute "PHYS_PAGE" "189"
					( Origin gFrontEnd )
				)
				( attribute "ROOM" "BMC_DEBUG_HEADER"
					( Origin gFrontEnd )
				)
				( attribute "ROT" "0"
					( Origin gFrontEnd )
				)
				( attribute "SEC" "1"
					( Origin gPackager )
				)
				( attribute "TOLERANCE" "5%"
					( Origin gFrontEnd )
				)
				( attribute "VALUE" "0.0"
					( Origin gFrontEnd )
				)
				( attribute "VER" "1"
					( Origin gFrontEnd )
				)
				( attribute "WATTAGE" "1/16W"
					( Origin gFrontEnd )
				)
				( attribute "XY" "(-1900,4500)"
					( Origin gFrontEnd )
				)
				( attribute "CHIPS_PART_NAME" "RES"
					( Origin gPackager )
				)
				( attribute "CDS_PART_NAME" "RES_0402-0.0,5%,1/16W,EMPTY,G2A"
					( Origin gPackager )
				)
				( objectStatus "R8G9" )
				( pin "a"
					( attribute "PN" "1"
						( Origin gPackager )
					)
					( objectStatus "R8G9.1" )
				)
				( pin "b"
					( attribute "PN" "2"
						( Origin gPackager )
					)
					( objectStatus "R8G9.2" )
				)
			)
			( gate "@baseboard_fab2_lib.baseboard_fab2(sch_1):page189_i13"
				( attribute "BOM_COST" "DEBUG"
					( Origin gFrontEnd )
				)
				( attribute "CDS_LIB" "mstr_discrete"
					( Origin gPackager )
				)
				( attribute "CDS_LOCATION" "R7G18"
					( Origin gPackager )
				)
				( attribute "CDS_SEC" "1"
					( Origin gPackager )
				)
				( attribute "LOCATION" "R7G18"
					( Origin gFrontEnd )
				)
				( attribute "MATERIAL" "EMPTY"
					( Origin gFrontEnd )
				)
				( attribute "PACK_TYPE" "0402"
					( Origin gFrontEnd )
				)
				( attribute "PART_NUMBER" "G21497-005"
					( Origin gFrontEnd )
				)
				( attribute "PHYS_PAGE" "189"
					( Origin gFrontEnd )
				)
				( attribute "ROOM" "BMC_DEBUG_HEADER"
					( Origin gFrontEnd )
				)
				( attribute "ROT" "0"
					( Origin gFrontEnd )
				)
				( attribute "SEC" "1"
					( Origin gFrontEnd )
				)
				( attribute "SEC_TYPE" "0402"
					( Origin gFrontEnd )
				)
				( attribute "TOLERANCE" "5%"
					( Origin gFrontEnd )
				)
				( attribute "VALUE" "0.0"
					( Origin gFrontEnd )
				)
				( attribute "VER" "1"
					( Origin gFrontEnd )
				)
				( attribute "WATTAGE" "1/16W"
					( Origin gFrontEnd )
				)
				( attribute "XY" "(-1900,4125)"
					( Origin gFrontEnd )
				)
				( attribute "CHIPS_PART_NAME" "RES"
					( Origin gPackager )
				)
				( attribute "CDS_PART_NAME" "RES_0402-0.0,5%,1/16W,EMPTY,G2A"
					( Origin gPackager )
				)
				( objectStatus "R7G18" )
				( pin "a"
					( attribute "PN" "1"
						( Origin gPackager )
					)
					( objectStatus "R7G18.1" )
				)
				( pin "b"
					( attribute "PN" "2"
						( Origin gPackager )
					)
					( objectStatus "R7G18.2" )
				)
			)
			( gate "@baseboard_fab2_lib.baseboard_fab2(sch_1):page189_i17"
				( attribute "BOM_COST" "DEBUG"
					( Origin gFrontEnd )
				)
				( attribute "CDS_LIB" "mstr_discrete"
					( Origin gPackager )
				)
				( attribute "CDS_LOCATION" "R8G8"
					( Origin gPackager )
				)
				( attribute "CDS_SEC" "1"
					( Origin gPackager )
				)
				( attribute "LOCATION" "R8G8"
					( Origin gFrontEnd )
				)
				( attribute "MATERIAL" "CHIP"
					( Origin gFrontEnd )
				)
				( attribute "PACK_TYPE" "0402"
					( Origin gFrontEnd )
				)
				( attribute "PART_NUMBER" "G21497-005"
					( Origin gFrontEnd )
				)
				( attribute "PHYS_PAGE" "189"
					( Origin gFrontEnd )
				)
				( attribute "ROOM" "BMC_DEBUG_HEADER"
					( Origin gFrontEnd )
				)
				( attribute "ROT" "0"
					( Origin gFrontEnd )
				)
				( attribute "SEC" "1"
					( Origin gFrontEnd )
				)
				( attribute "SEC_TYPE" "0402"
					( Origin gFrontEnd )
				)
				( attribute "TOLERANCE" "5%"
					( Origin gFrontEnd )
				)
				( attribute "VALUE" "0.0"
					( Origin gFrontEnd )
				)
				( attribute "VER" "1"
					( Origin gFrontEnd )
				)
				( attribute "WATTAGE" "1/16W"
					( Origin gFrontEnd )
				)
				( attribute "XY" "(-1900,3950)"
					( Origin gFrontEnd )
				)
				( attribute "CHIPS_PART_NAME" "RES"
					( Origin gPackager )
				)
				( attribute "CDS_PART_NAME" "RES_0402-0.0,5%,1/16W,CHIP,G21A"
					( Origin gPackager )
				)
				( objectStatus "R8G8" )
				( pin "a"
					( attribute "PN" "1"
						( Origin gPackager )
					)
					( objectStatus "R8G8.1" )
				)
				( pin "b"
					( attribute "PN" "2"
						( Origin gPackager )
					)
					( objectStatus "R8G8.2" )
				)
			)
			( gate "@baseboard_fab2_lib.baseboard_fab2(sch_1):page189_i18"
				( attribute "BOM_COST" "DEBUG"
					( Origin gFrontEnd )
				)
				( attribute "CDS_LIB" "mstr_discrete"
					( Origin gPackager )
				)
				( attribute "CDS_LOCATION" "R8G7"
					( Origin gPackager )
				)
				( attribute "CDS_SEC" "1"
					( Origin gPackager )
				)
				( attribute "LOCATION" "R8G7"
					( Origin gFrontEnd )
				)
				( attribute "MATERIAL" "CHIP"
					( Origin gFrontEnd )
				)
				( attribute "PACK_TYPE" "0402"
					( Origin gFrontEnd )
				)
				( attribute "PART_NUMBER" "G21497-005"
					( Origin gFrontEnd )
				)
				( attribute "PHYS_PAGE" "189"
					( Origin gFrontEnd )
				)
				( attribute "ROOM" "BMC_DEBUG_HEADER"
					( Origin gFrontEnd )
				)
				( attribute "ROT" "0"
					( Origin gFrontEnd )
				)
				( attribute "SEC" "1"
					( Origin gFrontEnd )
				)
				( attribute "SEC_TYPE" "0402"
					( Origin gFrontEnd )
				)
				( attribute "TOLERANCE" "5%"
					( Origin gFrontEnd )
				)
				( attribute "VALUE" "0.0"
					( Origin gFrontEnd )
				)
				( attribute "VER" "1"
					( Origin gFrontEnd )
				)
				( attribute "WATTAGE" "1/16W"
					( Origin gFrontEnd )
				)
				( attribute "XY" "(-1900,3775)"
					( Origin gFrontEnd )
				)
				( attribute "CHIPS_PART_NAME" "RES"
					( Origin gPackager )
				)
				( attribute "CDS_PART_NAME" "RES_0402-0.0,5%,1/16W,CHIP,G21A"
					( Origin gPackager )
				)
				( objectStatus "R8G7" )
				( pin "a"
					( attribute "PN" "1"
						( Origin gPackager )
					)
					( objectStatus "R8G7.1" )
				)
				( pin "b"
					( attribute "PN" "2"
						( Origin gPackager )
					)
					( objectStatus "R8G7.2" )
				)
			)
			( gate "@baseboard_fab2_lib.baseboard_fab2(sch_1):page189_i19"
				( attribute "BOM_COST" "DEBUG"
					( Origin gFrontEnd )
				)
				( attribute "CDS_LIB" "mstr_discrete"
					( Origin gPackager )
				)
				( attribute "CDS_LOCATION" "R8G11"
					( Origin gPackager )
				)
				( attribute "CDS_SEC" "1"
					( Origin gPackager )
				)
				( attribute "LOCATION" "R8G11"
					( Origin gFrontEnd )
				)
				( attribute "MATERIAL" "EMPTY"
					( Origin gFrontEnd )
				)
				( attribute "PACK_TYPE" "0402"
					( Origin gFrontEnd )
				)
				( attribute "PART_NUMBER" "G21497-005"
					( Origin gFrontEnd )
				)
				( attribute "PHYS_PAGE" "189"
					( Origin gFrontEnd )
				)
				( attribute "ROOM" "BMC_DEBUG_HEADER"
					( Origin gFrontEnd )
				)
				( attribute "ROT" "0"
					( Origin gFrontEnd )
				)
				( attribute "SEC" "1"
					( Origin gFrontEnd )
				)
				( attribute "SEC_TYPE" "0402"
					( Origin gFrontEnd )
				)
				( attribute "TOLERANCE" "5%"
					( Origin gFrontEnd )
				)
				( attribute "VALUE" "0.0"
					( Origin gFrontEnd )
				)
				( attribute "VER" "1"
					( Origin gFrontEnd )
				)
				( attribute "WATTAGE" "1/16W"
					( Origin gFrontEnd )
				)
				( attribute "XY" "(-1900,3400)"
					( Origin gFrontEnd )
				)
				( attribute "CHIPS_PART_NAME" "RES"
					( Origin gPackager )
				)
				( attribute "CDS_PART_NAME" "RES_0402-0.0,5%,1/16W,EMPTY,G2A"
					( Origin gPackager )
				)
				( objectStatus "R8G11" )
				( pin "a"
					( attribute "PN" "1"
						( Origin gPackager )
					)
					( objectStatus "R8G11.1" )
				)
				( pin "b"
					( attribute "PN" "2"
						( Origin gPackager )
					)
					( objectStatus "R8G11.2" )
				)
			)
			( gate "@baseboard_fab2_lib.baseboard_fab2(sch_1):page189_i20"
				( attribute "BOM_COST" "DEBUG"
					( Origin gFrontEnd )
				)
				( attribute "CDS_LIB" "mstr_discrete"
					( Origin gPackager )
				)
				( attribute "CDS_LOCATION" "R8G14"
					( Origin gPackager )
				)
				( attribute "CDS_SEC" "1"
					( Origin gPackager )
				)
				( attribute "LOCATION" "R8G14"
					( Origin gFrontEnd )
				)
				( attribute "MATERIAL" "CHIP"
					( Origin gFrontEnd )
				)
				( attribute "PACK_TYPE" "0402"
					( Origin gFrontEnd )
				)
				( attribute "PART_NUMBER" "G21497-005"
					( Origin gFrontEnd )
				)
				( attribute "PHYS_PAGE" "189"
					( Origin gFrontEnd )
				)
				( attribute "ROOM" "BMC_DEBUG_HEADER"
					( Origin gFrontEnd )
				)
				( attribute "ROT" "0"
					( Origin gFrontEnd )
				)
				( attribute "SEC" "1"
					( Origin gFrontEnd )
				)
				( attribute "SEC_TYPE" "0402"
					( Origin gFrontEnd )
				)
				( attribute "TOLERANCE" "5%"
					( Origin gFrontEnd )
				)
				( attribute "VALUE" "0.0"
					( Origin gFrontEnd )
				)
				( attribute "VER" "1"
					( Origin gFrontEnd )
				)
				( attribute "WATTAGE" "1/16W"
					( Origin gFrontEnd )
				)
				( attribute "XY" "(-1900,3250)"
					( Origin gFrontEnd )
				)
				( attribute "CHIPS_PART_NAME" "RES"
					( Origin gPackager )
				)
				( attribute "CDS_PART_NAME" "RES_0402-0.0,5%,1/16W,CHIP,G21A"
					( Origin gPackager )
				)
				( objectStatus "R8G14" )
				( pin "a"
					( attribute "PN" "1"
						( Origin gPackager )
					)
					( objectStatus "R8G14.1" )
				)
				( pin "b"
					( attribute "PN" "2"
						( Origin gPackager )
					)
					( objectStatus "R8G14.2" )
				)
			)
			( gate "@baseboard_fab2_lib.baseboard_fab2(sch_1):page189_i21"
				( attribute "BOM_COST" "DEBUG"
					( Origin gFrontEnd )
				)
				( attribute "CDS_LIB" "mstr_discrete"
					( Origin gPackager )
				)
				( attribute "CDS_LOCATION" "R8G12"
					( Origin gPackager )
				)
				( attribute "CDS_SEC" "1"
					( Origin gPackager )
				)
				( attribute "LOCATION" "R8G12"
					( Origin gFrontEnd )
				)
				( attribute "MATERIAL" "EMPTY"
					( Origin gFrontEnd )
				)
				( attribute "PACK_TYPE" "0402"
					( Origin gFrontEnd )
				)
				( attribute "PART_NUMBER" "G21497-005"
					( Origin gFrontEnd )
				)
				( attribute "PHYS_PAGE" "189"
					( Origin gFrontEnd )
				)
				( attribute "ROOM" "BMC_DEBUG_HEADER"
					( Origin gFrontEnd )
				)
				( attribute "ROT" "0"
					( Origin gFrontEnd )
				)
				( attribute "SEC" "1"
					( Origin gFrontEnd )
				)
				( attribute "SEC_TYPE" "0402"
					( Origin gFrontEnd )
				)
				( attribute "TOLERANCE" "5%"
					( Origin gFrontEnd )
				)
				( attribute "VALUE" "0.0"
					( Origin gFrontEnd )
				)
				( attribute "VER" "1"
					( Origin gFrontEnd )
				)
				( attribute "WATTAGE" "1/16W"
					( Origin gFrontEnd )
				)
				( attribute "XY" "(-1900,3575)"
					( Origin gFrontEnd )
				)
				( attribute "CHIPS_PART_NAME" "RES"
					( Origin gPackager )
				)
				( attribute "CDS_PART_NAME" "RES_0402-0.0,5%,1/16W,EMPTY,G2A"
					( Origin gPackager )
				)
				( objectStatus "R8G12" )
				( pin "a"
					( attribute "PN" "1"
						( Origin gPackager )
					)
					( objectStatus "R8G12.1" )
				)
				( pin "b"
					( attribute "PN" "2"
						( Origin gPackager )
					)
					( objectStatus "R8G12.2" )
				)
			)
			( gate "@baseboard_fab2_lib.baseboard_fab2(sch_1):page189_i22"
				( attribute "BOM_COST" "DEBUG"
					( Origin gFrontEnd )
				)
				( attribute "CDS_LIB" "mstr_discrete"
					( Origin gPackager )
				)
				( attribute "CDS_LOCATION" "R8G16"
					( Origin gPackager )
				)
				( attribute "CDS_SEC" "1"
					( Origin gPackager )
				)
				( attribute "LOCATION" "R8G16"
					( Origin gFrontEnd )
				)
				( attribute "MATERIAL" "EMPTY"
					( Origin gFrontEnd )
				)
				( attribute "PACK_TYPE" "0402"
					( Origin gFrontEnd )
				)
				( attribute "PART_NUMBER" "G21497-005"
					( Origin gFrontEnd )
				)
				( attribute "PHYS_PAGE" "189"
					( Origin gFrontEnd )
				)
				( attribute "ROOM" "BMC_DEBUG_HEADER"
					( Origin gFrontEnd )
				)
				( attribute "ROT" "0"
					( Origin gFrontEnd )
				)
				( attribute "SEC" "1"
					( Origin gFrontEnd )
				)
				( attribute "SEC_TYPE" "0402"
					( Origin gFrontEnd )
				)
				( attribute "TOLERANCE" "5%"
					( Origin gFrontEnd )
				)
				( attribute "VALUE" "0.0"
					( Origin gFrontEnd )
				)
				( attribute "VER" "1"
					( Origin gFrontEnd )
				)
				( attribute "WATTAGE" "1/16W"
					( Origin gFrontEnd )
				)
				( attribute "XY" "(-1900,2700)"
					( Origin gFrontEnd )
				)
				( attribute "CHIPS_PART_NAME" "RES"
					( Origin gPackager )
				)
				( attribute "CDS_PART_NAME" "RES_0402-0.0,5%,1/16W,EMPTY,G2A"
					( Origin gPackager )
				)
				( objectStatus "R8G16" )
				( pin "a"
					( attribute "PN" "1"
						( Origin gPackager )
					)
					( objectStatus "R8G16.1" )
				)
				( pin "b"
					( attribute "PN" "2"
						( Origin gPackager )
					)
					( objectStatus "R8G16.2" )
				)
			)
			( gate "@baseboard_fab2_lib.baseboard_fab2(sch_1):page189_i23"
				( attribute "BOM_COST" "DEBUG"
					( Origin gFrontEnd )
				)
				( attribute "CDS_LIB" "mstr_discrete"
					( Origin gPackager )
				)
				( attribute "CDS_LOCATION" "R8G13"
					( Origin gPackager )
				)
				( attribute "CDS_SEC" "1"
					( Origin gPackager )
				)
				( attribute "LOCATION" "R8G13"
					( Origin gFrontEnd )
				)
				( attribute "MATERIAL" "CHIP"
					( Origin gFrontEnd )
				)
				( attribute "PACK_TYPE" "0402"
					( Origin gFrontEnd )
				)
				( attribute "PART_NUMBER" "G21497-005"
					( Origin gFrontEnd )
				)
				( attribute "PHYS_PAGE" "189"
					( Origin gFrontEnd )
				)
				( attribute "ROOM" "BMC_DEBUG_HEADER"
					( Origin gFrontEnd )
				)
				( attribute "ROT" "0"
					( Origin gFrontEnd )
				)
				( attribute "SEC" "1"
					( Origin gFrontEnd )
				)
				( attribute "SEC_TYPE" "0402"
					( Origin gFrontEnd )
				)
				( attribute "TOLERANCE" "5%"
					( Origin gFrontEnd )
				)
				( attribute "VALUE" "0.0"
					( Origin gFrontEnd )
				)
				( attribute "VER" "1"
					( Origin gFrontEnd )
				)
				( attribute "WATTAGE" "1/16W"
					( Origin gFrontEnd )
				)
				( attribute "XY" "(-1900,3075)"
					( Origin gFrontEnd )
				)
				( attribute "CHIPS_PART_NAME" "RES"
					( Origin gPackager )
				)
				( attribute "CDS_PART_NAME" "RES_0402-0.0,5%,1/16W,CHIP,G21A"
					( Origin gPackager )
				)
				( objectStatus "R8G13" )
				( pin "a"
					( attribute "PN" "1"
						( Origin gPackager )
					)
					( objectStatus "R8G13.1" )
				)
				( pin "b"
					( attribute "PN" "2"
						( Origin gPackager )
					)
					( objectStatus "R8G13.2" )
				)
			)
			( gate "@baseboard_fab2_lib.baseboard_fab2(sch_1):page189_i24"
				( attribute "BOM_COST" "DEBUG"
					( Origin gFrontEnd )
				)
				( attribute "CDS_LIB" "mstr_discrete"
					( Origin gPackager )
				)
				( attribute "CDS_LOCATION" "R8G15"
					( Origin gPackager )
				)
				( attribute "CDS_SEC" "1"
					( Origin gPackager )
				)
				( attribute "LOCATION" "R8G15"
					( Origin gFrontEnd )
				)
				( attribute "MATERIAL" "EMPTY"
					( Origin gFrontEnd )
				)
				( attribute "PACK_TYPE" "0402"
					( Origin gFrontEnd )
				)
				( attribute "PART_NUMBER" "G21497-005"
					( Origin gFrontEnd )
				)
				( attribute "PHYS_PAGE" "189"
					( Origin gFrontEnd )
				)
				( attribute "ROOM" "BMC_DEBUG_HEADER"
					( Origin gFrontEnd )
				)
				( attribute "ROT" "0"
					( Origin gFrontEnd )
				)
				( attribute "SEC" "1"
					( Origin gFrontEnd )
				)
				( attribute "SEC_TYPE" "0402"
					( Origin gFrontEnd )
				)
				( attribute "TOLERANCE" "5%"
					( Origin gFrontEnd )
				)
				( attribute "VALUE" "0.0"
					( Origin gFrontEnd )
				)
				( attribute "VER" "1"
					( Origin gFrontEnd )
				)
				( attribute "WATTAGE" "1/16W"
					( Origin gFrontEnd )
				)
				( attribute "XY" "(-1900,2875)"
					( Origin gFrontEnd )
				)
				( attribute "CHIPS_PART_NAME" "RES"
					( Origin gPackager )
				)
				( attribute "CDS_PART_NAME" "RES_0402-0.0,5%,1/16W,EMPTY,G2A"
					( Origin gPackager )
				)
				( objectStatus "R8G15" )
				( pin "a"
					( attribute "PN" "1"
						( Origin gPackager )
					)
					( objectStatus "R8G15.1" )
				)
				( pin "b"
					( attribute "PN" "2"
						( Origin gPackager )
					)
					( objectStatus "R8G15.2" )
				)
			)
			( gate "@baseboard_fab2_lib.baseboard_fab2(sch_1):page189_i25"
				( attribute "BOM_COST" "DEBUG"
					( Origin gFrontEnd )
				)
				( attribute "CDS_LIB" "mstr_discrete"
					( Origin gPackager )
				)
				( attribute "CDS_LOCATION" "R8G17"
					( Origin gPackager )
				)
				( attribute "CDS_SEC" "1"
					( Origin gPackager )
				)
				( attribute "LOCATION" "R8G17"
					( Origin gFrontEnd )
				)
				( attribute "MATERIAL" "CHIP"
					( Origin gFrontEnd )
				)
				( attribute "PACK_TYPE" "0402"
					( Origin gFrontEnd )
				)
				( attribute "PART_NUMBER" "G21497-005"
					( Origin gFrontEnd )
				)
				( attribute "PHYS_PAGE" "189"
					( Origin gFrontEnd )
				)
				( attribute "ROOM" "BMC_DEBUG_HEADER"
					( Origin gFrontEnd )
				)
				( attribute "ROT" "0"
					( Origin gFrontEnd )
				)
				( attribute "SEC" "1"
					( Origin gFrontEnd )
				)
				( attribute "SEC_TYPE" "0402"
					( Origin gFrontEnd )
				)
				( attribute "TOLERANCE" "5%"
					( Origin gFrontEnd )
				)
				( attribute "VALUE" "0.0"
					( Origin gFrontEnd )
				)
				( attribute "VER" "1"
					( Origin gFrontEnd )
				)
				( attribute "WATTAGE" "1/16W"
					( Origin gFrontEnd )
				)
				( attribute "XY" "(-1900,2525)"
					( Origin gFrontEnd )
				)
				( attribute "CHIPS_PART_NAME" "RES"
					( Origin gPackager )
				)
				( attribute "CDS_PART_NAME" "RES_0402-0.0,5%,1/16W,CHIP,G21A"
					( Origin gPackager )
				)
				( objectStatus "R8G17" )
				( pin "a"
					( attribute "PN" "1"
						( Origin gPackager )
					)
					( objectStatus "R8G17.1" )
				)
				( pin "b"
					( attribute "PN" "2"
						( Origin gPackager )
					)
					( objectStatus "R8G17.2" )
				)
			)
			( gate "@baseboard_fab2_lib.baseboard_fab2(sch_1):page189_i26"
				( attribute "BOM_COST" "DEBUG"
					( Origin gFrontEnd )
				)
				( attribute "CDS_LIB" "mstr_discrete"
					( Origin gPackager )
				)
				( attribute "CDS_LOCATION" "R8G18"
					( Origin gPackager )
				)
				( attribute "CDS_SEC" "1"
					( Origin gPackager )
				)
				( attribute "LOCATION" "R8G18"
					( Origin gFrontEnd )
				)
				( attribute "MATERIAL" "CHIP"
					( Origin gFrontEnd )
				)
				( attribute "PACK_TYPE" "0402"
					( Origin gFrontEnd )
				)
				( attribute "PART_NUMBER" "G21497-005"
					( Origin gFrontEnd )
				)
				( attribute "PHYS_PAGE" "189"
					( Origin gFrontEnd )
				)
				( attribute "ROOM" "BMC_DEBUG_HEADER"
					( Origin gFrontEnd )
				)
				( attribute "ROT" "0"
					( Origin gFrontEnd )
				)
				( attribute "SEC" "1"
					( Origin gFrontEnd )
				)
				( attribute "SEC_TYPE" "0402"
					( Origin gFrontEnd )
				)
				( attribute "TOLERANCE" "5%"
					( Origin gFrontEnd )
				)
				( attribute "VALUE" "0.0"
					( Origin gFrontEnd )
				)
				( attribute "VER" "1"
					( Origin gFrontEnd )
				)
				( attribute "WATTAGE" "1/16W"
					( Origin gFrontEnd )
				)
				( attribute "XY" "(-1900,2350)"
					( Origin gFrontEnd )
				)
				( attribute "CHIPS_PART_NAME" "RES"
					( Origin gPackager )
				)
				( attribute "CDS_PART_NAME" "RES_0402-0.0,5%,1/16W,CHIP,G21A"
					( Origin gPackager )
				)
				( objectStatus "R8G18" )
				( pin "a"
					( attribute "PN" "1"
						( Origin gPackager )
					)
					( objectStatus "R8G18.1" )
				)
				( pin "b"
					( attribute "PN" "2"
						( Origin gPackager )
					)
					( objectStatus "R8G18.2" )
				)
			)
			( gate "@baseboard_fab2_lib.baseboard_fab2(sch_1):page189_i27"
				( attribute "BOM_COST" "DEBUG"
					( Origin gFrontEnd )
				)
				( attribute "CDS_LIB" "mstr_discrete"
					( Origin gPackager )
				)
				( attribute "CDS_LOCATION" "R7G16"
					( Origin gPackager )
				)
				( attribute "CDS_SEC" "1"
					( Origin gPackager )
				)
				( attribute "LOCATION" "R7G16"
					( Origin gFrontEnd )
				)
				( attribute "MATERIAL" "EMPTY"
					( Origin gFrontEnd )
				)
				( attribute "PACK_TYPE" "0402"
					( Origin gFrontEnd )
				)
				( attribute "PART_NUMBER" "G21497-005"
					( Origin gFrontEnd )
				)
				( attribute "PHYS_PAGE" "189"
					( Origin gFrontEnd )
				)
				( attribute "ROOM" "BMC_DEBUG_HEADER"
					( Origin gFrontEnd )
				)
				( attribute "ROT" "0"
					( Origin gFrontEnd )
				)
				( attribute "SEC" "1"
					( Origin gFrontEnd )
				)
				( attribute "SEC_TYPE" "0402"
					( Origin gFrontEnd )
				)
				( attribute "TOLERANCE" "5%"
					( Origin gFrontEnd )
				)
				( attribute "VALUE" "0.0"
					( Origin gFrontEnd )
				)
				( attribute "VER" "1"
					( Origin gFrontEnd )
				)
				( attribute "WATTAGE" "1/16W"
					( Origin gFrontEnd )
				)
				( attribute "XY" "(-1900,2150)"
					( Origin gFrontEnd )
				)
				( attribute "CHIPS_PART_NAME" "RES"
					( Origin gPackager )
				)
				( attribute "CDS_PART_NAME" "RES_0402-0.0,5%,1/16W,EMPTY,G2A"
					( Origin gPackager )
				)
				( objectStatus "R7G16" )
				( pin "a"
					( attribute "PN" "1"
						( Origin gPackager )
					)
					( objectStatus "R7G16.1" )
				)
				( pin "b"
					( attribute "PN" "2"
						( Origin gPackager )
					)
					( objectStatus "R7G16.2" )
				)
			)
			( gate "@baseboard_fab2_lib.baseboard_fab2(sch_1):page189_i36"
				( attribute "BOM_COST" "DEBUG"
					( Origin gFrontEnd )
				)
				( attribute "CDS_LIB" "mstr_discrete"
					( Origin gPackager )
				)
				( attribute "CDS_LOCATION" "R7G15"
					( Origin gPackager )
				)
				( attribute "CDS_SEC" "1"
					( Origin gPackager )
				)
				( attribute "LOCATION" "R7G15"
					( Origin gFrontEnd )
				)
				( attribute "MATERIAL" "EMPTY"
					( Origin gFrontEnd )
				)
				( attribute "PACK_TYPE" "0402"
					( Origin gFrontEnd )
				)
				( attribute "PART_NUMBER" "G21497-005"
					( Origin gFrontEnd )
				)
				( attribute "PHYS_PAGE" "189"
					( Origin gFrontEnd )
				)
				( attribute "ROOM" "BMC_DEBUG_HEADER"
					( Origin gFrontEnd )
				)
				( attribute "ROT" "0"
					( Origin gFrontEnd )
				)
				( attribute "SEC" "1"
					( Origin gFrontEnd )
				)
				( attribute "SEC_TYPE" "0402"
					( Origin gFrontEnd )
				)
				( attribute "TOLERANCE" "5%"
					( Origin gFrontEnd )
				)
				( attribute "VALUE" "0.0"
					( Origin gFrontEnd )
				)
				( attribute "VER" "1"
					( Origin gFrontEnd )
				)
				( attribute "WATTAGE" "1/16W"
					( Origin gFrontEnd )
				)
				( attribute "XY" "(-1900,1975)"
					( Origin gFrontEnd )
				)
				( attribute "CHIPS_PART_NAME" "RES"
					( Origin gPackager )
				)
				( attribute "CDS_PART_NAME" "RES_0402-0.0,5%,1/16W,EMPTY,G2A"
					( Origin gPackager )
				)
				( objectStatus "R7G15" )
				( pin "a"
					( attribute "PN" "1"
						( Origin gPackager )
					)
					( objectStatus "R7G15.1" )
				)
				( pin "b"
					( attribute "PN" "2"
						( Origin gPackager )
					)
					( objectStatus "R7G15.2" )
				)
			)
			( gate "@baseboard_fab2_lib.baseboard_fab2(sch_1):page189_i37"
				( attribute "BOM_COST" "DEBUG"
					( Origin gFrontEnd )
				)
				( attribute "CDS_LIB" "mstr_discrete"
					( Origin gPackager )
				)
				( attribute "CDS_LOCATION" "R7G17"
					( Origin gPackager )
				)
				( attribute "CDS_SEC" "1"
					( Origin gPackager )
				)
				( attribute "LOCATION" "R7G17"
					( Origin gFrontEnd )
				)
				( attribute "MATERIAL" "CHIP"
					( Origin gFrontEnd )
				)
				( attribute "PACK_TYPE" "0402"
					( Origin gFrontEnd )
				)
				( attribute "PART_NUMBER" "G21497-005"
					( Origin gFrontEnd )
				)
				( attribute "PHYS_PAGE" "189"
					( Origin gFrontEnd )
				)
				( attribute "ROOM" "BMC_DEBUG_HEADER"
					( Origin gFrontEnd )
				)
				( attribute "ROT" "0"
					( Origin gFrontEnd )
				)
				( attribute "SEC" "1"
					( Origin gFrontEnd )
				)
				( attribute "SEC_TYPE" "0402"
					( Origin gFrontEnd )
				)
				( attribute "TOLERANCE" "5%"
					( Origin gFrontEnd )
				)
				( attribute "VALUE" "0.0"
					( Origin gFrontEnd )
				)
				( attribute "VER" "1"
					( Origin gFrontEnd )
				)
				( attribute "WATTAGE" "1/16W"
					( Origin gFrontEnd )
				)
				( attribute "XY" "(-1900,1800)"
					( Origin gFrontEnd )
				)
				( attribute "CHIPS_PART_NAME" "RES"
					( Origin gPackager )
				)
				( attribute "CDS_PART_NAME" "RES_0402-0.0,5%,1/16W,CHIP,G21A"
					( Origin gPackager )
				)
				( objectStatus "R7G17" )
				( pin "a"
					( attribute "PN" "1"
						( Origin gPackager )
					)
					( objectStatus "R7G17.1" )
				)
				( pin "b"
					( attribute "PN" "2"
						( Origin gPackager )
					)
					( objectStatus "R7G17.2" )
				)
			)
			( gate "@baseboard_fab2_lib.baseboard_fab2(sch_1):page189_i38"
				( attribute "BOM_COST" "DEBUG"
					( Origin gFrontEnd )
				)
				( attribute "CDS_LIB" "mstr_discrete"
					( Origin gPackager )
				)
				( attribute "CDS_LOCATION" "R7G14"
					( Origin gPackager )
				)
				( attribute "CDS_SEC" "1"
					( Origin gPackager )
				)
				( attribute "LOCATION" "R7G14"
					( Origin gFrontEnd )
				)
				( attribute "MATERIAL" "CHIP"
					( Origin gFrontEnd )
				)
				( attribute "PACK_TYPE" "0402"
					( Origin gFrontEnd )
				)
				( attribute "PART_NUMBER" "G21497-005"
					( Origin gFrontEnd )
				)
				( attribute "PHYS_PAGE" "189"
					( Origin gFrontEnd )
				)
				( attribute "ROOM" "BMC_DEBUG_HEADER"
					( Origin gFrontEnd )
				)
				( attribute "ROT" "0"
					( Origin gFrontEnd )
				)
				( attribute "SEC" "1"
					( Origin gFrontEnd )
				)
				( attribute "SEC_TYPE" "0402"
					( Origin gFrontEnd )
				)
				( attribute "TOLERANCE" "5%"
					( Origin gFrontEnd )
				)
				( attribute "VALUE" "0.0"
					( Origin gFrontEnd )
				)
				( attribute "VER" "1"
					( Origin gFrontEnd )
				)
				( attribute "WATTAGE" "1/16W"
					( Origin gFrontEnd )
				)
				( attribute "XY" "(-1900,1625)"
					( Origin gFrontEnd )
				)
				( attribute "CHIPS_PART_NAME" "RES"
					( Origin gPackager )
				)
				( attribute "CDS_PART_NAME" "RES_0402-0.0,5%,1/16W,CHIP,G21A"
					( Origin gPackager )
				)
				( objectStatus "R7G14" )
				( pin "a"
					( attribute "PN" "1"
						( Origin gPackager )
					)
					( objectStatus "R7G14.1" )
				)
				( pin "b"
					( attribute "PN" "2"
						( Origin gPackager )
					)
					( objectStatus "R7G14.2" )
				)
			)
			( gate "@baseboard_fab2_lib.baseboard_fab2(sch_1):page189_i44"
				( attribute "CDS_LIB" "mstr_discrete"
					( Origin gPackager )
				)
				( attribute "CDS_LOCATION" "R3R15"
					( Origin gPackager )
				)
				( attribute "CDS_SEC" "1"
					( Origin gPackager )
				)
				( attribute "LOCATION" "R3R15"
					( Origin gFrontEnd )
				)
				( attribute "MATERIAL" "CHIP"
					( Origin gFrontEnd )
				)
				( attribute "PACK_TYPE" "0402"
					( Origin gFrontEnd )
				)
				( attribute "PART_NUMBER" "G21796-026"
					( Origin gFrontEnd )
				)
				( attribute "PHYS_PAGE" "189"
					( Origin gFrontEnd )
				)
				( attribute "ROOM" "BMC_DEBUG_HEADER"
					( Origin gFrontEnd )
				)
				( attribute "ROT" "0"
					( Origin gFrontEnd )
				)
				( attribute "SEC" "1"
					( Origin gFrontEnd )
				)
				( attribute "SEC_TYPE" "0402"
					( Origin gFrontEnd )
				)
				( attribute "TOLERANCE" "1%"
					( Origin gFrontEnd )
				)
				( attribute "VALUE" "1.00K"
					( Origin gFrontEnd )
				)
				( attribute "VER" "2"
					( Origin gFrontEnd )
				)
				( attribute "WATTAGE" "1/16W"
					( Origin gFrontEnd )
				)
				( attribute "XY" "(-175,1925)"
					( Origin gFrontEnd )
				)
				( attribute "CHIPS_PART_NAME" "RES"
					( Origin gPackager )
				)
				( attribute "CDS_PART_NAME" "RES_0402-1.00K,1%,1/16W,CHIP,GA"
					( Origin gPackager )
				)
				( objectStatus "R3R15" )
				( pin "a"
					( attribute "PN" "1"
						( Origin gPackager )
					)
					( objectStatus "R3R15.1" )
				)
				( pin "b"
					( attribute "PN" "2"
						( Origin gPackager )
					)
					( objectStatus "R3R15.2" )
				)
			)
			( gate "@baseboard_fab2_lib.baseboard_fab2(sch_1):page189_i45"
				( attribute "CDS_LIB" "mstr_discrete"
					( Origin gPackager )
				)
				( attribute "CDS_LOCATION" "R3R11"
					( Origin gPackager )
				)
				( attribute "CDS_SEC" "1"
					( Origin gPackager )
				)
				( attribute "LOCATION" "R3R11"
					( Origin gFrontEnd )
				)
				( attribute "MATERIAL" "EMPTY"
					( Origin gFrontEnd )
				)
				( attribute "PACK_TYPE" "0402"
					( Origin gFrontEnd )
				)
				( attribute "PART_NUMBER" "G21796-016"
					( Origin gFrontEnd )
				)
				( attribute "PHYS_PAGE" "189"
					( Origin gFrontEnd )
				)
				( attribute "ROOM" "BMC_DEBUG_HEADER"
					( Origin gFrontEnd )
				)
				( attribute "ROT" "0"
					( Origin gFrontEnd )
				)
				( attribute "SEC" "1"
					( Origin gFrontEnd )
				)
				( attribute "SEC_TYPE" "0402"
					( Origin gFrontEnd )
				)
				( attribute "TOLERANCE" "1%"
					( Origin gFrontEnd )
				)
				( attribute "VALUE" "10.0K"
					( Origin gFrontEnd )
				)
				( attribute "VER" "2"
					( Origin gFrontEnd )
				)
				( attribute "WATTAGE" "1/16W"
					( Origin gFrontEnd )
				)
				( attribute "XY" "(-175,1525)"
					( Origin gFrontEnd )
				)
				( attribute "CHIPS_PART_NAME" "RES"
					( Origin gPackager )
				)
				( attribute "CDS_PART_NAME" "RES_0402-10.0K,1%,1/16W,EMPTY,A"
					( Origin gPackager )
				)
				( objectStatus "R3R11" )
				( pin "a"
					( attribute "PN" "1"
						( Origin gPackager )
					)
					( objectStatus "R3R11.1" )
				)
				( pin "b"
					( attribute "PN" "2"
						( Origin gPackager )
					)
					( objectStatus "R3R11.2" )
				)
			)
			( gate "@baseboard_fab2_lib.baseboard_fab2(sch_1):page189_i47"
				( attribute "BOM_COST" "DEBUG"
					( Origin gFrontEnd )
				)
				( attribute "CDS_LIB" "mstr_conn"
					( Origin gPackager )
				)
				( attribute "CDS_LOCATION" "J7G2"
					( Origin gPackager )
				)
				( attribute "CDS_SEC" "1"
					( Origin gPackager )
				)
				( attribute "LOCATION" "J7G2"
					( Origin gFrontEnd )
				)
				( attribute "MATERIAL" "CONN"
					( Origin gFrontEnd )
				)
				( attribute "PACK_TYPE" "PIP"
					( Origin gFrontEnd )
				)
				( attribute "PART_NUMBER" "C77962-004"
					( Origin gFrontEnd )
				)
				( attribute "PHYS_PAGE" "189"
					( Origin gFrontEnd )
				)
				( attribute "ROOM" "BMC_DEBUG_HEADER"
					( Origin gFrontEnd )
				)
				( attribute "ROT" "2"
					( Origin gFrontEnd )
				)
				( attribute "SEC" "1"
					( Origin gFrontEnd )
				)
				( attribute "SEC_TYPE" "PIP"
					( Origin gFrontEnd )
				)
				( attribute "VER" "1"
					( Origin gFrontEnd )
				)
				( attribute "XY" "(3475,3625)"
					( Origin gFrontEnd )
				)
				( attribute "CHIPS_PART_NAME" "CONN8_C77962004"
					( Origin gPackager )
				)
				( attribute "CDS_PART_NAME" "CONN8_C77962004_PIP-CONN,C7796A"
					( Origin gPackager )
				)
				( objectStatus "J7G2" )
				( pin "io1"
					( attribute "PN" "1"
						( Origin gPackager )
					)
					( objectStatus "J7G2.1" )
				)
				( pin "io2"
					( attribute "PN" "2"
						( Origin gPackager )
					)
					( objectStatus "J7G2.2" )
				)
				( pin "io3"
					( attribute "PN" "3"
						( Origin gPackager )
					)
					( objectStatus "J7G2.3" )
				)
				( pin "io4"
					( attribute "PN" "4"
						( Origin gPackager )
					)
					( objectStatus "J7G2.4" )
				)
				( pin "io5"
					( attribute "PN" "5"
						( Origin gPackager )
					)
					( objectStatus "J7G2.5" )
				)
				( pin "io6"
					( attribute "PN" "6"
						( Origin gPackager )
					)
					( objectStatus "J7G2.6" )
				)
				( pin "io7"
					( attribute "PN" "7"
						( Origin gPackager )
					)
					( objectStatus "J7G2.7" )
				)
				( pin "io8"
					( attribute "PN" "8"
						( Origin gPackager )
					)
					( objectStatus "J7G2.8" )
				)
			)
			( gate "@baseboard_fab2_lib.baseboard_fab2(sch_1):page189_i49"
				( attribute "BOM_COST" "DEBUG"
					( Origin gFrontEnd )
				)
				( attribute "CDS_LIB" "mstr_discrete"
					( Origin gPackager )
				)
				( attribute "CDS_LOCATION" "CR3U1"
					( Origin gPackager )
				)
				( attribute "CDS_SEC" "1"
					( Origin gPackager )
				)
				( attribute "LOCATION" "CR3U1"
					( Origin gFrontEnd )
				)
				( attribute "MATERIAL" "IC"
					( Origin gFrontEnd )
				)
				( attribute "PACK_TYPE" "SMLF"
					( Origin gFrontEnd )
				)
				( attribute "PART_NUMBER" "D55839-001"
					( Origin gFrontEnd )
				)
				( attribute "PHYS_PAGE" "189"
					( Origin gFrontEnd )
				)
				( attribute "ROOM" "BMC_DEBUG_HEADER"
					( Origin gFrontEnd )
				)
				( attribute "ROT" "0"
					( Origin gFrontEnd )
				)
				( attribute "SEC" "1"
					( Origin gFrontEnd )
				)
				( attribute "SEC_TYPE" "SMLF"
					( Origin gFrontEnd )
				)
				( attribute "VALUE" "1N5819HW"
					( Origin gFrontEnd )
				)
				( attribute "VER" "1"
					( Origin gFrontEnd )
				)
				( attribute "XY" "(2800,4050)"
					( Origin gFrontEnd )
				)
				( attribute "CHIPS_PART_NAME" "DIODE"
					( Origin gPackager )
				)
				( attribute "CDS_PART_NAME" "DIODE_SMLF-1N5819HW,IC,D55839-A"
					( Origin gPackager )
				)
				( objectStatus "CR3U1" )
				( pin "a"
					( attribute "PN" "2"
						( Origin gPackager )
					)
					( objectStatus "CR3U1.2" )
				)
				( pin "c"
					( attribute "PN" "1"
						( Origin gPackager )
					)
					( objectStatus "CR3U1.1" )
				)
			)
			( gate "@baseboard_fab2_lib.baseboard_fab2(sch_1):page189_i50"
				( attribute "CDS_LIB" "mstr_discrete"
					( Origin gPackager )
				)
				( attribute "CDS_LOCATION" "R8G20"
					( Origin gPackager )
				)
				( attribute "CDS_SEC" "1"
					( Origin gPackager )
				)
				( attribute "LOCATION" "R8G20"
					( Origin gFrontEnd )
				)
				( attribute "MATERIAL" "CHIP"
					( Origin gFrontEnd )
				)
				( attribute "PACK_TYPE" "0402"
					( Origin gFrontEnd )
				)
				( attribute "PART_NUMBER" "G21796-016"
					( Origin gFrontEnd )
				)
				( attribute "PHYS_PAGE" "189"
					( Origin gFrontEnd )
				)
				( attribute "ROOM" "BMC_DEBUG_HEADER"
					( Origin gFrontEnd )
				)
				( attribute "ROT" "0"
					( Origin gFrontEnd )
				)
				( attribute "SEC" "1"
					( Origin gPackager )
				)
				( attribute "TOLERANCE" "1%"
					( Origin gFrontEnd )
				)
				( attribute "VALUE" "10.0K"
					( Origin gFrontEnd )
				)
				( attribute "VER" "2"
					( Origin gFrontEnd )
				)
				( attribute "WATTAGE" "1/16W"
					( Origin gFrontEnd )
				)
				( attribute "XY" "(2325,3975)"
					( Origin gFrontEnd )
				)
				( attribute "CHIPS_PART_NAME" "RES"
					( Origin gPackager )
				)
				( attribute "CDS_PART_NAME" "RES_0402-10.0K,1%,1/16W,CHIP,GA"
					( Origin gPackager )
				)
				( objectStatus "R8G20" )
				( pin "a"
					( attribute "PN" "1"
						( Origin gPackager )
					)
					( objectStatus "R8G20.1" )
				)
				( pin "b"
					( attribute "PN" "2"
						( Origin gPackager )
					)
					( objectStatus "R8G20.2" )
				)
			)
			( gate "@baseboard_fab2_lib.baseboard_fab2(sch_1):page189_i51"
				( attribute "CDS_LIB" "mstr_discrete"
					( Origin gPackager )
				)
				( attribute "CDS_LOCATION" "R7G23"
					( Origin gPackager )
				)
				( attribute "CDS_SEC" "1"
					( Origin gPackager )
				)
				( attribute "LOCATION" "R7G23"
					( Origin gFrontEnd )
				)
				( attribute "MATERIAL" "CHIP"
					( Origin gFrontEnd )
				)
				( attribute "PACK_TYPE" "0402"
					( Origin gFrontEnd )
				)
				( attribute "PART_NUMBER" "G21796-016"
					( Origin gFrontEnd )
				)
				( attribute "PHYS_PAGE" "189"
					( Origin gFrontEnd )
				)
				( attribute "ROOM" "BMC_DEBUG_HEADER"
					( Origin gFrontEnd )
				)
				( attribute "ROT" "0"
					( Origin gFrontEnd )
				)
				( attribute "SEC" "1"
					( Origin gPackager )
				)
				( attribute "TOLERANCE" "1%"
					( Origin gFrontEnd )
				)
				( attribute "VALUE" "10.0K"
					( Origin gFrontEnd )
				)
				( attribute "VER" "2"
					( Origin gFrontEnd )
				)
				( attribute "WATTAGE" "1/16W"
					( Origin gFrontEnd )
				)
				( attribute "XY" "(2025,3975)"
					( Origin gFrontEnd )
				)
				( attribute "CHIPS_PART_NAME" "RES"
					( Origin gPackager )
				)
				( attribute "CDS_PART_NAME" "RES_0402-10.0K,1%,1/16W,CHIP,GA"
					( Origin gPackager )
				)
				( objectStatus "R7G23" )
				( pin "a"
					( attribute "PN" "1"
						( Origin gPackager )
					)
					( objectStatus "R7G23.1" )
				)
				( pin "b"
					( attribute "PN" "2"
						( Origin gPackager )
					)
					( objectStatus "R7G23.2" )
				)
			)
			( gate "@baseboard_fab2_lib.baseboard_fab2(sch_1):page189_i53"
				( attribute "CDS_LIB" "mstr_discrete"
					( Origin gPackager )
				)
				( attribute "CDS_LOCATION" "R7G22"
					( Origin gPackager )
				)
				( attribute "CDS_SEC" "1"
					( Origin gPackager )
				)
				( attribute "LOCATION" "R7G22"
					( Origin gFrontEnd )
				)
				( attribute "MATERIAL" "CHIP"
					( Origin gFrontEnd )
				)
				( attribute "PACK_TYPE" "0402"
					( Origin gFrontEnd )
				)
				( attribute "PART_NUMBER" "G21796-016"
					( Origin gFrontEnd )
				)
				( attribute "PHYS_PAGE" "189"
					( Origin gFrontEnd )
				)
				( attribute "ROOM" "BMC_DEBUG_HEADER"
					( Origin gFrontEnd )
				)
				( attribute "ROT" "0"
					( Origin gFrontEnd )
				)
				( attribute "SEC" "1"
					( Origin gPackager )
				)
				( attribute "TOLERANCE" "1%"
					( Origin gFrontEnd )
				)
				( attribute "VALUE" "10.0K"
					( Origin gFrontEnd )
				)
				( attribute "VER" "2"
					( Origin gFrontEnd )
				)
				( attribute "WATTAGE" "1/16W"
					( Origin gFrontEnd )
				)
				( attribute "XY" "(1675,3975)"
					( Origin gFrontEnd )
				)
				( attribute "CHIPS_PART_NAME" "RES"
					( Origin gPackager )
				)
				( attribute "CDS_PART_NAME" "RES_0402-10.0K,1%,1/16W,CHIP,GA"
					( Origin gPackager )
				)
				( objectStatus "R7G22" )
				( pin "a"
					( attribute "PN" "1"
						( Origin gPackager )
					)
					( objectStatus "R7G22.1" )
				)
				( pin "b"
					( attribute "PN" "2"
						( Origin gPackager )
					)
					( objectStatus "R7G22.2" )
				)
			)
			( gate "@baseboard_fab2_lib.baseboard_fab2(sch_1):page189_i56"
				( attribute "CDS_LIB" "mstr_discrete"
					( Origin gPackager )
				)
				( attribute "CDS_LOCATION" "R8G23"
					( Origin gPackager )
				)
				( attribute "CDS_SEC" "1"
					( Origin gPackager )
				)
				( attribute "LOCATION" "R8G23"
					( Origin gFrontEnd )
				)
				( attribute "MATERIAL" "CHIP"
					( Origin gFrontEnd )
				)
				( attribute "PACK_TYPE" "0402"
					( Origin gFrontEnd )
				)
				( attribute "PART_NUMBER" "G21796-072"
					( Origin gFrontEnd )
				)
				( attribute "PHYS_PAGE" "189"
					( Origin gFrontEnd )
				)
				( attribute "ROOM" "BMC_DEBUG_HEADER"
					( Origin gFrontEnd )
				)
				( attribute "ROT" "0"
					( Origin gFrontEnd )
				)
				( attribute "SEC" "1"
					( Origin gFrontEnd )
				)
				( attribute "SEC_TYPE" "0402"
					( Origin gFrontEnd )
				)
				( attribute "TOLERANCE" "1%"
					( Origin gFrontEnd )
				)
				( attribute "VALUE" "4.75K"
					( Origin gFrontEnd )
				)
				( attribute "VER" "2"
					( Origin gFrontEnd )
				)
				( attribute "WATTAGE" "1/16W"
					( Origin gFrontEnd )
				)
				( attribute "XY" "(2325,3225)"
					( Origin gFrontEnd )
				)
				( attribute "CHIPS_PART_NAME" "RES"
					( Origin gPackager )
				)
				( attribute "CDS_PART_NAME" "RES_0402-4.75K,1%,1/16W,CHIP,GA"
					( Origin gPackager )
				)
				( objectStatus "R8G23" )
				( pin "a"
					( attribute "PN" "1"
						( Origin gPackager )
					)
					( objectStatus "R8G23.1" )
				)
				( pin "b"
					( attribute "PN" "2"
						( Origin gPackager )
					)
					( objectStatus "R8G23.2" )
				)
			)
			( gate "@baseboard_fab2_lib.baseboard_fab2(sch_1):page189_i63"
				( attribute "BOM_COST" "DEBUG"
					( Origin gFrontEnd )
				)
				( attribute "CDS_LIB" "mstr_discrete"
					( Origin gPackager )
				)
				( attribute "CDS_LOCATION" "R7G21"
					( Origin gPackager )
				)
				( attribute "CDS_SEC" "1"
					( Origin gPackager )
				)
				( attribute "LOCATION" "R7G21"
					( Origin gFrontEnd )
				)
				( attribute "MATERIAL" "CHIP"
					( Origin gFrontEnd )
				)
				( attribute "PACK_TYPE" "0402"
					( Origin gFrontEnd )
				)
				( attribute "PART_NUMBER" "G21497-005"
					( Origin gFrontEnd )
				)
				( attribute "PHYS_PAGE" "189"
					( Origin gFrontEnd )
				)
				( attribute "ROOM" "BMC_DEBUG_HEADER"
					( Origin gFrontEnd )
				)
				( attribute "ROT" "0"
					( Origin gFrontEnd )
				)
				( attribute "SEC" "1"
					( Origin gFrontEnd )
				)
				( attribute "SEC_TYPE" "0402"
					( Origin gFrontEnd )
				)
				( attribute "TOLERANCE" "5%"
					( Origin gFrontEnd )
				)
				( attribute "VALUE" "0.0"
					( Origin gFrontEnd )
				)
				( attribute "VER" "1"
					( Origin gFrontEnd )
				)
				( attribute "WATTAGE" "1/16W"
					( Origin gFrontEnd )
				)
				( attribute "XY" "(900,3725)"
					( Origin gFrontEnd )
				)
				( attribute "CHIPS_PART_NAME" "RES"
					( Origin gPackager )
				)
				( attribute "CDS_PART_NAME" "RES_0402-0.0,5%,1/16W,CHIP,G21A"
					( Origin gPackager )
				)
				( objectStatus "R7G21" )
				( pin "a"
					( attribute "PN" "1"
						( Origin gPackager )
					)
					( objectStatus "R7G21.1" )
				)
				( pin "b"
					( attribute "PN" "2"
						( Origin gPackager )
					)
					( objectStatus "R7G21.2" )
				)
			)
			( gate "@baseboard_fab2_lib.baseboard_fab2(sch_1):page189_i64"
				( attribute "BOM_COST" "DEBUG"
					( Origin gFrontEnd )
				)
				( attribute "CDS_LIB" "mstr_discrete"
					( Origin gPackager )
				)
				( attribute "CDS_LOCATION" "R8G19"
					( Origin gPackager )
				)
				( attribute "CDS_SEC" "1"
					( Origin gPackager )
				)
				( attribute "LOCATION" "R8G19"
					( Origin gFrontEnd )
				)
				( attribute "MATERIAL" "CHIP"
					( Origin gFrontEnd )
				)
				( attribute "PACK_TYPE" "0402"
					( Origin gFrontEnd )
				)
				( attribute "PART_NUMBER" "G21497-005"
					( Origin gFrontEnd )
				)
				( attribute "PHYS_PAGE" "189"
					( Origin gFrontEnd )
				)
				( attribute "ROOM" "BMC_DEBUG_HEADER"
					( Origin gFrontEnd )
				)
				( attribute "ROT" "0"
					( Origin gFrontEnd )
				)
				( attribute "SEC" "1"
					( Origin gFrontEnd )
				)
				( attribute "SEC_TYPE" "0402"
					( Origin gFrontEnd )
				)
				( attribute "TOLERANCE" "5%"
					( Origin gFrontEnd )
				)
				( attribute "VALUE" "0.0"
					( Origin gFrontEnd )
				)
				( attribute "VER" "1"
					( Origin gFrontEnd )
				)
				( attribute "WATTAGE" "1/16W"
					( Origin gFrontEnd )
				)
				( attribute "XY" "(1375,3675)"
					( Origin gFrontEnd )
				)
				( attribute "CHIPS_PART_NAME" "RES"
					( Origin gPackager )
				)
				( attribute "CDS_PART_NAME" "RES_0402-0.0,5%,1/16W,CHIP,G21A"
					( Origin gPackager )
				)
				( objectStatus "R8G19" )
				( pin "a"
					( attribute "PN" "1"
						( Origin gPackager )
					)
					( objectStatus "R8G19.1" )
				)
				( pin "b"
					( attribute "PN" "2"
						( Origin gPackager )
					)
					( objectStatus "R8G19.2" )
				)
			)
			( gate "@baseboard_fab2_lib.baseboard_fab2(sch_1):page189_i65"
				( attribute "BOM_COST" "DEBUG"
					( Origin gFrontEnd )
				)
				( attribute "CDS_LIB" "mstr_discrete"
					( Origin gPackager )
				)
				( attribute "CDS_LOCATION" "R8G21"
					( Origin gPackager )
				)
				( attribute "CDS_SEC" "1"
					( Origin gPackager )
				)
				( attribute "LOCATION" "R8G21"
					( Origin gFrontEnd )
				)
				( attribute "MATERIAL" "CHIP"
					( Origin gFrontEnd )
				)
				( attribute "PACK_TYPE" "0402"
					( Origin gFrontEnd )
				)
				( attribute "PART_NUMBER" "G21497-005"
					( Origin gFrontEnd )
				)
				( attribute "PHYS_PAGE" "189"
					( Origin gFrontEnd )
				)
				( attribute "ROOM" "BMC_DEBUG_HEADER"
					( Origin gFrontEnd )
				)
				( attribute "ROT" "0"
					( Origin gFrontEnd )
				)
				( attribute "SEC" "1"
					( Origin gFrontEnd )
				)
				( attribute "SEC_TYPE" "0402"
					( Origin gFrontEnd )
				)
				( attribute "TOLERANCE" "5%"
					( Origin gFrontEnd )
				)
				( attribute "VALUE" "0.0"
					( Origin gFrontEnd )
				)
				( attribute "VER" "1"
					( Origin gFrontEnd )
				)
				( attribute "WATTAGE" "1/16W"
					( Origin gFrontEnd )
				)
				( attribute "XY" "(975,3525)"
					( Origin gFrontEnd )
				)
				( attribute "CHIPS_PART_NAME" "RES"
					( Origin gPackager )
				)
				( attribute "CDS_PART_NAME" "RES_0402-0.0,5%,1/16W,CHIP,G21A"
					( Origin gPackager )
				)
				( objectStatus "R8G21" )
				( pin "a"
					( attribute "PN" "1"
						( Origin gPackager )
					)
					( objectStatus "R8G21.1" )
				)
				( pin "b"
					( attribute "PN" "2"
						( Origin gPackager )
					)
					( objectStatus "R8G21.2" )
				)
			)
			( gate "@baseboard_fab2_lib.baseboard_fab2(sch_1):page189_i66"
				( attribute "BOM_COST" "DEBUG"
					( Origin gFrontEnd )
				)
				( attribute "CDS_LIB" "mstr_discrete"
					( Origin gPackager )
				)
				( attribute "CDS_LOCATION" "R8G22"
					( Origin gPackager )
				)
				( attribute "CDS_SEC" "1"
					( Origin gPackager )
				)
				( attribute "LOCATION" "R8G22"
					( Origin gFrontEnd )
				)
				( attribute "MATERIAL" "CHIP"
					( Origin gFrontEnd )
				)
				( attribute "PACK_TYPE" "0402"
					( Origin gFrontEnd )
				)
				( attribute "PART_NUMBER" "G21497-005"
					( Origin gFrontEnd )
				)
				( attribute "PHYS_PAGE" "189"
					( Origin gFrontEnd )
				)
				( attribute "ROOM" "BMC_DEBUG_HEADER"
					( Origin gFrontEnd )
				)
				( attribute "ROT" "0"
					( Origin gFrontEnd )
				)
				( attribute "SEC" "1"
					( Origin gFrontEnd )
				)
				( attribute "SEC_TYPE" "0402"
					( Origin gFrontEnd )
				)
				( attribute "TOLERANCE" "5%"
					( Origin gFrontEnd )
				)
				( attribute "VALUE" "0.0"
					( Origin gFrontEnd )
				)
				( attribute "VER" "1"
					( Origin gFrontEnd )
				)
				( attribute "WATTAGE" "1/16W"
					( Origin gFrontEnd )
				)
				( attribute "XY" "(1600,3425)"
					( Origin gFrontEnd )
				)
				( attribute "CHIPS_PART_NAME" "RES"
					( Origin gPackager )
				)
				( attribute "CDS_PART_NAME" "RES_0402-0.0,5%,1/16W,CHIP,G21A"
					( Origin gPackager )
				)
				( objectStatus "R8G22" )
				( pin "a"
					( attribute "PN" "1"
						( Origin gPackager )
					)
					( objectStatus "R8G22.1" )
				)
				( pin "b"
					( attribute "PN" "2"
						( Origin gPackager )
					)
					( objectStatus "R8G22.2" )
				)
			)
			( gate "@baseboard_fab2_lib.baseboard_fab2(sch_1):page190_i116"
				( attribute "BOM_COST" "CPLD"
					( Origin gFrontEnd )
				)
				( attribute "CDS_LIB" "mstr_discrete"
					( Origin gPackager )
				)
				( attribute "CDS_LOCATION" "R3P34"
					( Origin gPackager )
				)
				( attribute "CDS_SEC" "1"
					( Origin gPackager )
				)
				( attribute "LOCATION" "R3P34"
					( Origin gFrontEnd )
				)
				( attribute "MATERIAL" "CHIP"
					( Origin gFrontEnd )
				)
				( attribute "PACK_TYPE" "0402"
					( Origin gFrontEnd )
				)
				( attribute "PART_NUMBER" "G21497-005"
					( Origin gFrontEnd )
				)
				( attribute "PHYS_PAGE" "190"
					( Origin gFrontEnd )
				)
				( attribute "ROOM" "CPLD"
					( Origin gFrontEnd )
				)
				( attribute "ROT" "0"
					( Origin gFrontEnd )
				)
				( attribute "SEC" "1"
					( Origin gFrontEnd )
				)
				( attribute "SEC_TYPE" "0402"
					( Origin gFrontEnd )
				)
				( attribute "TOLERANCE" "5%"
					( Origin gFrontEnd )
				)
				( attribute "VALUE" "0.0"
					( Origin gFrontEnd )
				)
				( attribute "VER" "1"
					( Origin gFrontEnd )
				)
				( attribute "WATTAGE" "1/16W"
					( Origin gFrontEnd )
				)
				( attribute "XY" "(-4150,5200)"
					( Origin gFrontEnd )
				)
				( attribute "CHIPS_PART_NAME" "RES"
					( Origin gPackager )
				)
				( attribute "CDS_PART_NAME" "RES_0402-0.0,5%,1/16W,CHIP,G21A"
					( Origin gPackager )
				)
				( objectStatus "R3P34" )
				( pin "a"
					( attribute "PN" "1"
						( Origin gPackager )
					)
					( objectStatus "R3P34.1" )
				)
				( pin "b"
					( attribute "PN" "2"
						( Origin gPackager )
					)
					( objectStatus "R3P34.2" )
				)
			)
			( gate "@baseboard_fab2_lib.baseboard_fab2(sch_1):page190_i117"
				( attribute "BOM_COST" "CPLD"
					( Origin gFrontEnd )
				)
				( attribute "CDS_LIB" "mstr_discrete"
					( Origin gPackager )
				)
				( attribute "CDS_LOCATION" "R3P35"
					( Origin gPackager )
				)
				( attribute "CDS_SEC" "1"
					( Origin gPackager )
				)
				( attribute "LOCATION" "R3P35"
					( Origin gFrontEnd )
				)
				( attribute "MATERIAL" "CHIP"
					( Origin gFrontEnd )
				)
				( attribute "PACK_TYPE" "0402"
					( Origin gFrontEnd )
				)
				( attribute "PART_NUMBER" "G21497-005"
					( Origin gFrontEnd )
				)
				( attribute "PHYS_PAGE" "190"
					( Origin gFrontEnd )
				)
				( attribute "ROOM" "CPLD"
					( Origin gFrontEnd )
				)
				( attribute "ROT" "0"
					( Origin gFrontEnd )
				)
				( attribute "SEC" "1"
					( Origin gFrontEnd )
				)
				( attribute "SEC_TYPE" "0402"
					( Origin gFrontEnd )
				)
				( attribute "TOLERANCE" "5%"
					( Origin gFrontEnd )
				)
				( attribute "VALUE" "0.0"
					( Origin gFrontEnd )
				)
				( attribute "VER" "1"
					( Origin gFrontEnd )
				)
				( attribute "WATTAGE" "1/16W"
					( Origin gFrontEnd )
				)
				( attribute "XY" "(-4150,5000)"
					( Origin gFrontEnd )
				)
				( attribute "CHIPS_PART_NAME" "RES"
					( Origin gPackager )
				)
				( attribute "CDS_PART_NAME" "RES_0402-0.0,5%,1/16W,CHIP,G21A"
					( Origin gPackager )
				)
				( objectStatus "R3P35" )
				( pin "a"
					( attribute "PN" "1"
						( Origin gPackager )
					)
					( objectStatus "R3P35.1" )
				)
				( pin "b"
					( attribute "PN" "2"
						( Origin gPackager )
					)
					( objectStatus "R3P35.2" )
				)
			)
			( gate "@baseboard_fab2_lib.baseboard_fab2(sch_1):page190_i179"
				( attribute "BOM_COST" "CPLD"
					( Origin gFrontEnd )
				)
				( attribute "CDS_LIB" "mstr_memory"
					( Origin gPackager )
				)
				( attribute "CDS_LMAN_SYM_OUTLINE" "-550,1750,550,-1750"
					( Origin gPackager )
				)
				( attribute "CDS_LOCATION" "U8D7"
					( Origin gPackager )
				)
				( attribute "LOCATION" "U8D7"
					( Origin gFrontEnd )
				)
				( attribute "MATERIAL" "IC"
					( Origin gFrontEnd )
				)
				( attribute "PACK_TYPE" "256BGA"
					( Origin gFrontEnd )
				)
				( attribute "PART_NUMBER" "H63395-001"
					( Origin gFrontEnd )
				)
				( attribute "PHYS_PAGE" "190"
					( Origin gFrontEnd )
				)
				( attribute "ROOM" "CPLD"
					( Origin gFrontEnd )
				)
				( attribute "ROT" "0"
					( Origin gFrontEnd )
				)
				( attribute "SEC" "1"
					( Origin gFrontEnd )
				)
				( attribute "SEC_TYPE" "256BGA"
					( Origin gFrontEnd )
				)
				( attribute "VER" "4"
					( Origin gFrontEnd )
				)
				( attribute "XY" "(-1950,2950)"
					( Origin gFrontEnd )
				)
				( attribute "CHIPS_PART_NAME" "LCMXO2_A"
					( Origin gPackager )
				)
				( attribute "CDS_PART_NAME" "LCMXO2_A_256BGA-IC,H63395-001"
					( Origin gPackager )
				)
				( attribute "CDS_SEC" "1"
					( Origin gPackager )
				)
				( objectStatus "U8D7" )
				( pin "pb3a"
					( attribute "PN" "P4"
						( Origin gPackager )
					)
					( objectStatus "U8D7.P4" )
				)
				( pin "pb3b"
					( attribute "PN" "T4"
						( Origin gPackager )
					)
					( objectStatus "U8D7.T4" )
				)
				( pin "pb3c"
					( attribute "PN" "T2"
						( Origin gPackager )
					)
					( objectStatus "U8D7.T2" )
				)
				( pin "pb3d"
					( attribute "PN" "R3"
						( Origin gPackager )
					)
					( objectStatus "U8D7.R3" )
				)
				( pin "pb5a_csspin"
					( attribute "PN" "R5"
						( Origin gPackager )
					)
					( objectStatus "U8D7.R5" )
				)
				( pin "pb5b"
					( attribute "PN" "P5"
						( Origin gPackager )
					)
					( objectStatus "U8D7.P5" )
				)
				( pin "pb6a"
					( attribute "PN" "T5"
						( Origin gPackager )
					)
					( objectStatus "U8D7.T5" )
				)
				( pin "pb6b"
					( attribute "PN" "R6"
						( Origin gPackager )
					)
					( objectStatus "U8D7.R6" )
				)
				( pin "pb6c"
					( attribute "PN" "T3"
						( Origin gPackager )
					)
					( objectStatus "U8D7.T3" )
				)
				( pin "pb6d"
					( attribute "PN" "R4"
						( Origin gPackager )
					)
					( objectStatus "U8D7.R4" )
				)
				( pin "pb8a_mclk_cclk"
					( attribute "PN" "P6"
						( Origin gPackager )
					)
					( objectStatus "U8D7.P6" )
				)
				( pin "pb8b_so_spiso"
					( attribute "PN" "T6"
						( Origin gPackager )
					)
					( objectStatus "U8D7.T6" )
				)
				( pin "pb8c"
					( attribute "PN" "N6"
						( Origin gPackager )
					)
					( objectStatus "U8D7.N6" )
				)
				( pin "pb8d"
					( attribute "PN" "L7"
						( Origin gPackager )
					)
					( objectStatus "U8D7.L7" )
				)
				( pin "pb9a"
					( attribute "PN" "R7"
						( Origin gPackager )
					)
					( objectStatus "U8D7.R7" )
				)
				( pin "pb9b"
					( attribute "PN" "P7"
						( Origin gPackager )
					)
					( objectStatus "U8D7.P7" )
				)
				( pin "pb9c"
					( attribute "PN" "M7"
						( Origin gPackager )
					)
					( objectStatus "U8D7.M7" )
				)
				( pin "pb9d"
					( attribute "PN" "N7"
						( Origin gPackager )
					)
					( objectStatus "U8D7.N7" )
				)
				( pin "pb11a_pclkt2_0"
					( attribute "PN" "T7"
						( Origin gPackager )
					)
					( objectStatus "U8D7.T7" )
				)
				( pin "pb11b_pclkc2_0"
					( attribute "PN" "R8"
						( Origin gPackager )
					)
					( objectStatus "U8D7.R8" )
				)
				( pin "pb11c"
					( attribute "PN" "M6"
						( Origin gPackager )
					)
					( objectStatus "U8D7.M6" )
				)
				( pin "pb11d"
					( attribute "PN" "L8"
						( Origin gPackager )
					)
					( objectStatus "U8D7.L8" )
				)
				( pin "pb12a"
					( attribute "PN" "P8"
						( Origin gPackager )
					)
					( objectStatus "U8D7.P8" )
				)
				( pin "pb12b"
					( attribute "PN" "T8"
						( Origin gPackager )
					)
					( objectStatus "U8D7.T8" )
				)
				( pin "pb12c"
					( attribute "PN" "N8"
						( Origin gPackager )
					)
					( objectStatus "U8D7.N8" )
				)
				( pin "pb12d"
					( attribute "PN" "L9"
						( Origin gPackager )
					)
					( objectStatus "U8D7.L9" )
				)
				( pin "pb16a_pclkt2_1"
					( attribute "PN" "T9"
						( Origin gPackager )
					)
					( objectStatus "U8D7.T9" )
				)
				( pin "pb16b_pclkc2_1"
					( attribute "PN" "P9"
						( Origin gPackager )
					)
					( objectStatus "U8D7.P9" )
				)
				( pin "pb16c"
					( attribute "PN" "M8"
						( Origin gPackager )
					)
					( objectStatus "U8D7.M8" )
				)
				( pin "pb16d"
					( attribute "PN" "N9"
						( Origin gPackager )
					)
					( objectStatus "U8D7.N9" )
				)
				( pin "pb18a"
					( attribute "PN" "R9"
						( Origin gPackager )
					)
					( objectStatus "U8D7.R9" )
				)
				( pin "pb18b"
					( attribute "PN" "T10"
						( Origin gPackager )
					)
					( objectStatus "U8D7.T10" )
				)
				( pin "pb18c"
					( attribute "PN" "M9"
						( Origin gPackager )
					)
					( objectStatus "U8D7.M9" )
				)
				( pin "pb18d"
					( attribute "PN" "L10"
						( Origin gPackager )
					)
					( objectStatus "U8D7.L10" )
				)
				( pin "pb19a"
					( attribute "PN" "P10"
						( Origin gPackager )
					)
					( objectStatus "U8D7.P10" )
				)
				( pin "pb19b"
					( attribute "PN" "R10"
						( Origin gPackager )
					)
					( objectStatus "U8D7.R10" )
				)
				( pin "pb19c"
					( attribute "PN" "N10"
						( Origin gPackager )
					)
					( objectStatus "U8D7.N10" )
				)
				( pin "pb19d"
					( attribute "PN" "M11"
						( Origin gPackager )
					)
					( objectStatus "U8D7.M11" )
				)
				( pin "pb21a"
					( attribute "PN" "T11"
						( Origin gPackager )
					)
					( objectStatus "U8D7.T11" )
				)
				( pin "pb21b"
					( attribute "PN" "P11"
						( Origin gPackager )
					)
					( objectStatus "U8D7.P11" )
				)
				( pin "pb21c"
					( attribute "PN" "M10"
						( Origin gPackager )
					)
					( objectStatus "U8D7.M10" )
				)
				( pin "pb21d"
					( attribute "PN" "N11"
						( Origin gPackager )
					)
					( objectStatus "U8D7.N11" )
				)
				( pin "pb22a"
					( attribute "PN" "R11"
						( Origin gPackager )
					)
					( objectStatus "U8D7.R11" )
				)
				( pin "pb22b"
					( attribute "PN" "T12"
						( Origin gPackager )
					)
					( objectStatus "U8D7.T12" )
				)
				( pin "pb22c"
					( attribute "PN" "R13"
						( Origin gPackager )
					)
					( objectStatus "U8D7.R13" )
				)
				( pin "pb22d"
					( attribute "PN" "T14"
						( Origin gPackager )
					)
					( objectStatus "U8D7.T14" )
				)
				( pin "pb24a"
					( attribute "PN" "P12"
						( Origin gPackager )
					)
					( objectStatus "U8D7.P12" )
				)
				( pin "pb24b"
					( attribute "PN" "T13"
						( Origin gPackager )
					)
					( objectStatus "U8D7.T13" )
				)
				( pin "pb25a_sn"
					( attribute "PN" "R12"
						( Origin gPackager )
					)
					( objectStatus "U8D7.R12" )
				)
				( pin "pb25b_si_sispi"
					( attribute "PN" "P13"
						( Origin gPackager )
					)
					( objectStatus "U8D7.P13" )
				)
				( pin "pb25c"
					( attribute "PN" "T15"
						( Origin gPackager )
					)
					( objectStatus "U8D7.T15" )
				)
				( pin "pb25d"
					( attribute "PN" "R14"
						( Origin gPackager )
					)
					( objectStatus "U8D7.R14" )
				)
				( pin "pl1a_l_gpllt_fb"
					( attribute "PN" "D3"
						( Origin gPackager )
					)
					( objectStatus "U8D7.D3" )
				)
				( pin "pl1b_l_gpllc_fb"
					( attribute "PN" "D1"
						( Origin gPackager )
					)
					( objectStatus "U8D7.D1" )
				)
				( pin "pl1c"
					( attribute "PN" "B1"
						( Origin gPackager )
					)
					( objectStatus "U8D7.B1" )
				)
				( pin "pl1d"
					( attribute "PN" "C2"
						( Origin gPackager )
					)
					( objectStatus "U8D7.C2" )
				)
				( pin "pl2a_l_gpllt_in"
					( attribute "PN" "E2"
						( Origin gPackager )
					)
					( objectStatus "U8D7.E2" )
				)
				( pin "pl2b_l_gpllc_in"
					( attribute "PN" "E3"
						( Origin gPackager )
					)
					( objectStatus "U8D7.E3" )
				)
				( pin "pl2c"
					( attribute "PN" "C1"
						( Origin gPackager )
					)
					( objectStatus "U8D7.C1" )
				)
				( pin "pl2d"
					( attribute "PN" "D2"
						( Origin gPackager )
					)
					( objectStatus "U8D7.D2" )
				)
				( pin "pl3a_pclkt5_0"
					( attribute "PN" "E1"
						( Origin gPackager )
					)
					( objectStatus "U8D7.E1" )
				)
				( pin "pl3b_pclkc5_0"
					( attribute "PN" "F2"
						( Origin gPackager )
					)
					( objectStatus "U8D7.F2" )
				)
				( pin "pl3c"
					( attribute "PN" "F4"
						( Origin gPackager )
					)
					( objectStatus "U8D7.F4" )
				)
				( pin "pl3d"
					( attribute "PN" "G6"
						( Origin gPackager )
					)
					( objectStatus "U8D7.G6" )
				)
				( pin "pl4a"
					( attribute "PN" "F3"
						( Origin gPackager )
					)
					( objectStatus "U8D7.F3" )
				)
				( pin "pl4b"
					( attribute "PN" "F1"
						( Origin gPackager )
					)
					( objectStatus "U8D7.F1" )
				)
				( pin "pl4c"
					( attribute "PN" "G5"
						( Origin gPackager )
					)
					( objectStatus "U8D7.G5" )
				)
				( pin "pl4d"
					( attribute "PN" "G4"
						( Origin gPackager )
					)
					( objectStatus "U8D7.G4" )
				)
				( pin "pl5a"
					( attribute "PN" "G2"
						( Origin gPackager )
					)
					( objectStatus "U8D7.G2" )
				)
				( pin "pl5b"
					( attribute "PN" "G3"
						( Origin gPackager )
					)
					( objectStatus "U8D7.G3" )
				)
				( pin "pl5c"
					( attribute "PN" "F5"
						( Origin gPackager )
					)
					( objectStatus "U8D7.F5" )
				)
				( pin "pl5d"
					( attribute "PN" "H6"
						( Origin gPackager )
					)
					( objectStatus "U8D7.H6" )
				)
				( pin "pl6a"
					( attribute "PN" "G1"
						( Origin gPackager )
					)
					( objectStatus "U8D7.G1" )
				)
				( pin "pl6b"
					( attribute "PN" "H2"
						( Origin gPackager )
					)
					( objectStatus "U8D7.H2" )
				)
				( pin "pl6c"
					( attribute "PN" "H4"
						( Origin gPackager )
					)
					( objectStatus "U8D7.H4" )
				)
				( pin "pl6d"
					( attribute "PN" "J6"
						( Origin gPackager )
					)
					( objectStatus "U8D7.J6" )
				)
				( pin "pl7a"
					( attribute "PN" "H3"
						( Origin gPackager )
					)
					( objectStatus "U8D7.H3" )
				)
				( pin "pl7b"
					( attribute "PN" "H1"
						( Origin gPackager )
					)
					( objectStatus "U8D7.H1" )
				)
				( pin "pl7c_pclkt4_0"
					( attribute "PN" "J1"
						( Origin gPackager )
					)
					( objectStatus "U8D7.J1" )
				)
				( pin "pl7d_pclkc4_0"
					( attribute "PN" "J3"
						( Origin gPackager )
					)
					( objectStatus "U8D7.J3" )
				)
				( pin "pl9a"
					( attribute "PN" "J2"
						( Origin gPackager )
					)
					( objectStatus "U8D7.J2" )
				)
				( pin "pl9b"
					( attribute "PN" "K1"
						( Origin gPackager )
					)
					( objectStatus "U8D7.K1" )
				)
				( pin "pl9c"
					( attribute "PN" "H5"
						( Origin gPackager )
					)
					( objectStatus "U8D7.H5" )
				)
				( pin "pl9d"
					( attribute "PN" "J4"
						( Origin gPackager )
					)
					( objectStatus "U8D7.J4" )
				)
				( pin "pl10a"
					( attribute "PN" "K3"
						( Origin gPackager )
					)
					( objectStatus "U8D7.K3" )
				)
				( pin "pl10b"
					( attribute "PN" "K2"
						( Origin gPackager )
					)
					( objectStatus "U8D7.K2" )
				)
				( pin "pl10c"
					( attribute "PN" "J5"
						( Origin gPackager )
					)
					( objectStatus "U8D7.J5" )
				)
				( pin "pl10d"
					( attribute "PN" "K6"
						( Origin gPackager )
					)
					( objectStatus "U8D7.K6" )
				)
				( pin "pl11a"
					( attribute "PN" "L1"
						( Origin gPackager )
					)
					( objectStatus "U8D7.L1" )
				)
				( pin "pl11b"
					( attribute "PN" "L3"
						( Origin gPackager )
					)
					( objectStatus "U8D7.L3" )
				)
				( pin "pl11c"
					( attribute "PN" "K4"
						( Origin gPackager )
					)
					( objectStatus "U8D7.K4" )
				)
				( pin "pl11d"
					( attribute "PN" "L5"
						( Origin gPackager )
					)
					( objectStatus "U8D7.L5" )
				)
				( pin "pl12a_pclkt3_0"
					( attribute "PN" "L2"
						( Origin gPackager )
					)
					( objectStatus "U8D7.L2" )
				)
				( pin "pl12b_pclkc3_0"
					( attribute "PN" "M1"
						( Origin gPackager )
					)
					( objectStatus "U8D7.M1" )
				)
				( pin "pl12c"
					( attribute "PN" "K5"
						( Origin gPackager )
					)
					( objectStatus "U8D7.K5" )
				)
				( pin "pl12d"
					( attribute "PN" "L4"
						( Origin gPackager )
					)
					( objectStatus "U8D7.L4" )
				)
				( pin "pl13a"
					( attribute "PN" "M3"
						( Origin gPackager )
					)
					( objectStatus "U8D7.M3" )
				)
				( pin "pl13b"
					( attribute "PN" "N1"
						( Origin gPackager )
					)
					( objectStatus "U8D7.N1" )
				)
				( pin "pl13c"
					( attribute "PN" "N2"
						( Origin gPackager )
					)
					( objectStatus "U8D7.N2" )
				)
				( pin "pl13d"
					( attribute "PN" "P1"
						( Origin gPackager )
					)
					( objectStatus "U8D7.P1" )
				)
				( pin "pl14a"
					( attribute "PN" "M2"
						( Origin gPackager )
					)
					( objectStatus "U8D7.M2" )
				)
				( pin "pl14b"
					( attribute "PN" "N3"
						( Origin gPackager )
					)
					( objectStatus "U8D7.N3" )
				)
				( pin "pl14c"
					( attribute "PN" "R1"
						( Origin gPackager )
					)
					( objectStatus "U8D7.R1" )
				)
				( pin "pl14d"
					( attribute "PN" "P2"
						( Origin gPackager )
					)
					( objectStatus "U8D7.P2" )
				)
			)
			( gate "@baseboard_fab2_lib.baseboard_fab2(sch_1):page190_i338"
				( attribute "BOM_COST" "CPLD"
					( Origin gFrontEnd )
				)
				( attribute "CDS_LIB" "mstr_discrete"
					( Origin gPackager )
				)
				( attribute "CDS_LOCATION" "R2R2"
					( Origin gPackager )
				)
				( attribute "CDS_SEC" "1"
					( Origin gPackager )
				)
				( attribute "LOCATION" "R2R2"
					( Origin gFrontEnd )
				)
				( attribute "MATERIAL" "CHIP"
					( Origin gFrontEnd )
				)
				( attribute "PACK_TYPE" "0402"
					( Origin gFrontEnd )
				)
				( attribute "PART_NUMBER" "G21796-074"
					( Origin gFrontEnd )
				)
				( attribute "PHYS_PAGE" "190"
					( Origin gFrontEnd )
				)
				( attribute "ROOM" "CPLD"
					( Origin gFrontEnd )
				)
				( attribute "ROT" "0"
					( Origin gFrontEnd )
				)
				( attribute "SEC" "1"
					( Origin gPackager )
				)
				( attribute "TOLERANCE" "1%"
					( Origin gFrontEnd )
				)
				( attribute "VALUE" "33.2"
					( Origin gFrontEnd )
				)
				( attribute "VER" "1"
					( Origin gFrontEnd )
				)
				( attribute "WATTAGE" "1/16W"
					( Origin gFrontEnd )
				)
				( attribute "XY" "(-1350,5200)"
					( Origin gFrontEnd )
				)
				( attribute "CHIPS_PART_NAME" "RES"
					( Origin gPackager )
				)
				( attribute "CDS_PART_NAME" "RES_0402-33.2,1%,1/16W,CHIP,G2A"
					( Origin gPackager )
				)
				( objectStatus "R2R2" )
				( pin "a"
					( attribute "PN" "1"
						( Origin gPackager )
					)
					( objectStatus "R2R2.1" )
				)
				( pin "b"
					( attribute "PN" "2"
						( Origin gPackager )
					)
					( objectStatus "R2R2.2" )
				)
			)
			( gate "@baseboard_fab2_lib.baseboard_fab2(sch_1):page191_i59"
				( attribute "BOM_COST" "CPLD"
					( Origin gFrontEnd )
				)
				( attribute "CDS_LIB" "mstr_memory"
					( Origin gPackager )
				)
				( attribute "CDS_LMAN_SYM_OUTLINE" "-550,1700,550,-1700"
					( Origin gPackager )
				)
				( attribute "CDS_LOCATION" "U8D7"
					( Origin gPackager )
				)
				( attribute "LOCATION" "U8D7"
					( Origin gFrontEnd )
				)
				( attribute "MATERIAL" "IC"
					( Origin gFrontEnd )
				)
				( attribute "PACK_TYPE" "256BGA"
					( Origin gFrontEnd )
				)
				( attribute "PART_NUMBER" "H63395-001"
					( Origin gFrontEnd )
				)
				( attribute "PHYS_PAGE" "191"
					( Origin gFrontEnd )
				)
				( attribute "ROOM" "CPLD"
					( Origin gFrontEnd )
				)
				( attribute "ROT" "0"
					( Origin gFrontEnd )
				)
				( attribute "SEC" "2"
					( Origin gFrontEnd )
				)
				( attribute "SEC_TYPE" "256BGA"
					( Origin gFrontEnd )
				)
				( attribute "VER" "5"
					( Origin gFrontEnd )
				)
				( attribute "XY" "(-4475,2725)"
					( Origin gFrontEnd )
				)
				( attribute "CHIPS_PART_NAME" "LCMXO2_A"
					( Origin gPackager )
				)
				( attribute "CDS_PART_NAME" "LCMXO2_A_256BGA-IC,H63395-001"
					( Origin gPackager )
				)
				( attribute "CDS_SEC" "2"
					( Origin gPackager )
				)
				( objectStatus "U8D7" )
				( pin "pr1a"
					( attribute "PN" "D14"
						( Origin gPackager )
					)
					( objectStatus "U8D7.D14" )
				)
				( pin "pr1b"
					( attribute "PN" "E15"
						( Origin gPackager )
					)
					( objectStatus "U8D7.E15" )
				)
				( pin "pr1c"
					( attribute "PN" "C15"
						( Origin gPackager )
					)
					( objectStatus "U8D7.C15" )
				)
				( pin "pr1d"
					( attribute "PN" "B16"
						( Origin gPackager )
					)
					( objectStatus "U8D7.B16" )
				)
				( pin "pr2a"
					( attribute "PN" "D16"
						( Origin gPackager )
					)
					( objectStatus "U8D7.D16" )
				)
				( pin "pr2b"
					( attribute "PN" "E14"
						( Origin gPackager )
					)
					( objectStatus "U8D7.E14" )
				)
				( pin "pr2c"
					( attribute "PN" "C16"
						( Origin gPackager )
					)
					( objectStatus "U8D7.C16" )
				)
				( pin "pr2d"
					( attribute "PN" "D15"
						( Origin gPackager )
					)
					( objectStatus "U8D7.D15" )
				)
				( pin "pr3a"
					( attribute "PN" "E16"
						( Origin gPackager )
					)
					( objectStatus "U8D7.E16" )
				)
				( pin "pr3b"
					( attribute "PN" "F15"
						( Origin gPackager )
					)
					( objectStatus "U8D7.F15" )
				)
				( pin "pr3c"
					( attribute "PN" "F13"
						( Origin gPackager )
					)
					( objectStatus "U8D7.F13" )
				)
				( pin "pr3d"
					( attribute "PN" "G12"
						( Origin gPackager )
					)
					( objectStatus "U8D7.G12" )
				)
				( pin "pr4a"
					( attribute "PN" "F14"
						( Origin gPackager )
					)
					( objectStatus "U8D7.F14" )
				)
				( pin "pr4b"
					( attribute "PN" "F16"
						( Origin gPackager )
					)
					( objectStatus "U8D7.F16" )
				)
				( pin "pr4c"
					( attribute "PN" "F12"
						( Origin gPackager )
					)
					( objectStatus "U8D7.F12" )
				)
				( pin "pr4d"
					( attribute "PN" "G13"
						( Origin gPackager )
					)
					( objectStatus "U8D7.G13" )
				)
				( pin "pr5a"
					( attribute "PN" "G15"
						( Origin gPackager )
					)
					( objectStatus "U8D7.G15" )
				)
				( pin "pr5b"
					( attribute "PN" "G14"
						( Origin gPackager )
					)
					( objectStatus "U8D7.G14" )
				)
				( pin "pr5c"
					( attribute "PN" "G11"
						( Origin gPackager )
					)
					( objectStatus "U8D7.G11" )
				)
				( pin "pr5d"
					( attribute "PN" "H12"
						( Origin gPackager )
					)
					( objectStatus "U8D7.H12" )
				)
				( pin "pr6a"
					( attribute "PN" "G16"
						( Origin gPackager )
					)
					( objectStatus "U8D7.G16" )
				)
				( pin "pr6b"
					( attribute "PN" "H15"
						( Origin gPackager )
					)
					( objectStatus "U8D7.H15" )
				)
				( pin "pr6c"
					( attribute "PN" "H13"
						( Origin gPackager )
					)
					( objectStatus "U8D7.H13" )
				)
				( pin "pr6d"
					( attribute "PN" "J12"
						( Origin gPackager )
					)
					( objectStatus "U8D7.J12" )
				)
				( pin "pr7a_pclkt1_0"
					( attribute "PN" "H14"
						( Origin gPackager )
					)
					( objectStatus "U8D7.H14" )
				)
				( pin "pr7b_pclkc1_0"
					( attribute "PN" "H16"
						( Origin gPackager )
					)
					( objectStatus "U8D7.H16" )
				)
				( pin "pr7c"
					( attribute "PN" "J16"
						( Origin gPackager )
					)
					( objectStatus "U8D7.J16" )
				)
				( pin "pr7d"
					( attribute "PN" "J14"
						( Origin gPackager )
					)
					( objectStatus "U8D7.J14" )
				)
				( pin "pr9a"
					( attribute "PN" "J15"
						( Origin gPackager )
					)
					( objectStatus "U8D7.J15" )
				)
				( pin "pr9b"
					( attribute "PN" "K16"
						( Origin gPackager )
					)
					( objectStatus "U8D7.K16" )
				)
				( pin "pr9c"
					( attribute "PN" "H11"
						( Origin gPackager )
					)
					( objectStatus "U8D7.H11" )
				)
				( pin "pr9d"
					( attribute "PN" "J13"
						( Origin gPackager )
					)
					( objectStatus "U8D7.J13" )
				)
				( pin "pr10a"
					( attribute "PN" "K14"
						( Origin gPackager )
					)
					( objectStatus "U8D7.K14" )
				)
				( pin "pr10b"
					( attribute "PN" "K15"
						( Origin gPackager )
					)
					( objectStatus "U8D7.K15" )
				)
				( pin "pr10c"
					( attribute "PN" "J11"
						( Origin gPackager )
					)
					( objectStatus "U8D7.J11" )
				)
				( pin "pr10d"
					( attribute "PN" "L12"
						( Origin gPackager )
					)
					( objectStatus "U8D7.L12" )
				)
				( pin "pr11a"
					( attribute "PN" "L16"
						( Origin gPackager )
					)
					( objectStatus "U8D7.L16" )
				)
				( pin "pr11b"
					( attribute "PN" "L14"
						( Origin gPackager )
					)
					( objectStatus "U8D7.L14" )
				)
				( pin "pr11c"
					( attribute "PN" "K13"
						( Origin gPackager )
					)
					( objectStatus "U8D7.K13" )
				)
				( pin "pr11d"
					( attribute "PN" "K12"
						( Origin gPackager )
					)
					( objectStatus "U8D7.K12" )
				)
				( pin "pr12a"
					( attribute "PN" "L15"
						( Origin gPackager )
					)
					( objectStatus "U8D7.L15" )
				)
				( pin "pr12b"
					( attribute "PN" "M16"
						( Origin gPackager )
					)
					( objectStatus "U8D7.M16" )
				)
				( pin "pr12c"
					( attribute "PN" "K11"
						( Origin gPackager )
					)
					( objectStatus "U8D7.K11" )
				)
				( pin "pr12d"
					( attribute "PN" "L13"
						( Origin gPackager )
					)
					( objectStatus "U8D7.L13" )
				)
				( pin "pr13a"
					( attribute "PN" "M14"
						( Origin gPackager )
					)
					( objectStatus "U8D7.M14" )
				)
				( pin "pr13b"
					( attribute "PN" "M15"
						( Origin gPackager )
					)
					( objectStatus "U8D7.M15" )
				)
				( pin "pr13c"
					( attribute "PN" "N15"
						( Origin gPackager )
					)
					( objectStatus "U8D7.N15" )
				)
				( pin "pr13d"
					( attribute "PN" "P16"
						( Origin gPackager )
					)
					( objectStatus "U8D7.P16" )
				)
				( pin "pr14a"
					( attribute "PN" "N16"
						( Origin gPackager )
					)
					( objectStatus "U8D7.N16" )
				)
				( pin "pr14b"
					( attribute "PN" "N14"
						( Origin gPackager )
					)
					( objectStatus "U8D7.N14" )
				)
				( pin "pr14c"
					( attribute "PN" "P15"
						( Origin gPackager )
					)
					( objectStatus "U8D7.P15" )
				)
				( pin "pr14d"
					( attribute "PN" "R16"
						( Origin gPackager )
					)
					( objectStatus "U8D7.R16" )
				)
				( pin "pt9a"
					( attribute "PN" "C4"
						( Origin gPackager )
					)
					( objectStatus "U8D7.C4" )
				)
				( pin "pt9b"
					( attribute "PN" "B5"
						( Origin gPackager )
					)
					( objectStatus "U8D7.B5" )
				)
				( pin "pt9c"
					( attribute "PN" "B3"
						( Origin gPackager )
					)
					( objectStatus "U8D7.B3" )
				)
				( pin "pt10a"
					( attribute "PN" "A4"
						( Origin gPackager )
					)
					( objectStatus "U8D7.A4" )
				)
				( pin "pt10b"
					( attribute "PN" "C5"
						( Origin gPackager )
					)
					( objectStatus "U8D7.C5" )
				)
				( pin "pt11a"
					( attribute "PN" "A5"
						( Origin gPackager )
					)
					( objectStatus "U8D7.A5" )
				)
				( pin "pt11b"
					( attribute "PN" "B6"
						( Origin gPackager )
					)
					( objectStatus "U8D7.B6" )
				)
				( pin "pt11c"
					( attribute "PN" "A3"
						( Origin gPackager )
					)
					( objectStatus "U8D7.A3" )
				)
				( pin "pt11d"
					( attribute "PN" "B4"
						( Origin gPackager )
					)
					( objectStatus "U8D7.B4" )
				)
				( pin "pt12a"
					( attribute "PN" "D6"
						( Origin gPackager )
					)
					( objectStatus "U8D7.D6" )
				)
				( pin "pt12b"
					( attribute "PN" "E7"
						( Origin gPackager )
					)
					( objectStatus "U8D7.E7" )
				)
				( pin "pt12c_tdo"
					( attribute "PN" "C6"
						( Origin gPackager )
					)
					( objectStatus "U8D7.C6" )
				)
				( pin "pt12d_tdi"
					( attribute "PN" "A6"
						( Origin gPackager )
					)
					( objectStatus "U8D7.A6" )
				)
				( pin "pt13a"
					( attribute "PN" "B7"
						( Origin gPackager )
					)
					( objectStatus "U8D7.B7" )
				)
				( pin "pt13b"
					( attribute "PN" "C7"
						( Origin gPackager )
					)
					( objectStatus "U8D7.C7" )
				)
				( pin "pt13c"
					( attribute "PN" "E6"
						( Origin gPackager )
					)
					( objectStatus "U8D7.E6" )
				)
				( pin "pt13d"
					( attribute "PN" "D7"
						( Origin gPackager )
					)
					( objectStatus "U8D7.D7" )
				)
				( pin "pt16a"
					( attribute "PN" "F7"
						( Origin gPackager )
					)
					( objectStatus "U8D7.F7" )
				)
				( pin "pt16b"
					( attribute "PN" "E8"
						( Origin gPackager )
					)
					( objectStatus "U8D7.E8" )
				)
				( pin "pt16c_tck"
					( attribute "PN" "A7"
						( Origin gPackager )
					)
					( objectStatus "U8D7.A7" )
				)
				( pin "pt16d_tms"
					( attribute "PN" "B8"
						( Origin gPackager )
					)
					( objectStatus "U8D7.B8" )
				)
				( pin "pt17a_pclkt0_1"
					( attribute "PN" "C8"
						( Origin gPackager )
					)
					( objectStatus "U8D7.C8" )
				)
				( pin "pt17b_pclkc0_1"
					( attribute "PN" "A8"
						( Origin gPackager )
					)
					( objectStatus "U8D7.A8" )
				)
				( pin "pt17c"
					( attribute "PN" "D8"
						( Origin gPackager )
					)
					( objectStatus "U8D7.D8" )
				)
				( pin "pt17d"
					( attribute "PN" "E9"
						( Origin gPackager )
					)
					( objectStatus "U8D7.E9" )
				)
				( pin "pt18a"
					( attribute "PN" "F8"
						( Origin gPackager )
					)
					( objectStatus "U8D7.F8" )
				)
				( pin "pt18b"
					( attribute "PN" "D9"
						( Origin gPackager )
					)
					( objectStatus "U8D7.D9" )
				)
				( pin "pt18c_scl_pclkt0_0"
					( attribute "PN" "A9"
						( Origin gPackager )
					)
					( objectStatus "U8D7.A9" )
				)
				( pin "pt18d_sda_pclkc0_0"
					( attribute "PN" "C9"
						( Origin gPackager )
					)
					( objectStatus "U8D7.C9" )
				)
				( pin "pt19a"
					( attribute "PN" "B9"
						( Origin gPackager )
					)
					( objectStatus "U8D7.B9" )
				)
				( pin "pt19b"
					( attribute "PN" "A10"
						( Origin gPackager )
					)
					( objectStatus "U8D7.A10" )
				)
				( pin "pt19c"
					( attribute "PN" "F9"
						( Origin gPackager )
					)
					( objectStatus "U8D7.F9" )
				)
				( pin "pt19d"
					( attribute "PN" "E11"
						( Origin gPackager )
					)
					( objectStatus "U8D7.E11" )
				)
				( pin "pt20a"
					( attribute "PN" "D10"
						( Origin gPackager )
					)
					( objectStatus "U8D7.D10" )
				)
				( pin "pt20b"
					( attribute "PN" "E10"
						( Origin gPackager )
					)
					( objectStatus "U8D7.E10" )
				)
				( pin "pt20c_jtagenb"
					( attribute "PN" "C10"
						( Origin gPackager )
					)
					( objectStatus "U8D7.C10" )
				)
				( pin "pt20d_programn"
					( attribute "PN" "B10"
						( Origin gPackager )
					)
					( objectStatus "U8D7.B10" )
				)
				( pin "pt21a"
					( attribute "PN" "A11"
						( Origin gPackager )
					)
					( objectStatus "U8D7.A11" )
				)
				( pin "pt21b"
					( attribute "PN" "C11"
						( Origin gPackager )
					)
					( objectStatus "U8D7.C11" )
				)
				( pin "pt21c"
					( attribute "PN" "F10"
						( Origin gPackager )
					)
					( objectStatus "U8D7.F10" )
				)
				( pin "pt21d"
					( attribute "PN" "D11"
						( Origin gPackager )
					)
					( objectStatus "U8D7.D11" )
				)
				( pin "pt22a"
					( attribute "PN" "B11"
						( Origin gPackager )
					)
					( objectStatus "U8D7.B11" )
				)
				( pin "pt22b"
					( attribute "PN" "A12"
						( Origin gPackager )
					)
					( objectStatus "U8D7.A12" )
				)
				( pin "pt22c"
					( attribute "PN" "B13"
						( Origin gPackager )
					)
					( objectStatus "U8D7.B13" )
				)
				( pin "pt22d"
					( attribute "PN" "A14"
						( Origin gPackager )
					)
					( objectStatus "U8D7.A14" )
				)
				( pin "pt23a"
					( attribute "PN" "C12"
						( Origin gPackager )
					)
					( objectStatus "U8D7.C12" )
				)
				( pin "pt23b"
					( attribute "PN" "B12"
						( Origin gPackager )
					)
					( objectStatus "U8D7.B12" )
				)
				( pin "pt24a"
					( attribute "PN" "B14"
						( Origin gPackager )
					)
					( objectStatus "U8D7.B14" )
				)
				( pin "pt24b"
					( attribute "PN" "A15"
						( Origin gPackager )
					)
					( objectStatus "U8D7.A15" )
				)
				( pin "pt24c_initn"
					( attribute "PN" "A13"
						( Origin gPackager )
					)
					( objectStatus "U8D7.A13" )
				)
				( pin "pt24d_done"
					( attribute "PN" "C13"
						( Origin gPackager )
					)
					( objectStatus "U8D7.C13" )
				)
			)
			( gate "@baseboard_fab2_lib.baseboard_fab2(sch_1):page191_i166"
				( attribute "CDS_LIB" "mstr_discrete"
					( Origin gPackager )
				)
				( attribute "CDS_LOCATION" "R2R6"
					( Origin gPackager )
				)
				( attribute "LOCATION" "R2R6"
					( Origin gFrontEnd )
				)
				( attribute "MATERIAL" "CHIP"
					( Origin gFrontEnd )
				)
				( attribute "PACK_TYPE" "0402"
					( Origin gFrontEnd )
				)
				( attribute "PART_NUMBER" "G21497-048"
					( Origin gFrontEnd )
				)
				( attribute "PHYS_PAGE" "191"
					( Origin gFrontEnd )
				)
				( attribute "ROOM" "CPLD"
					( Origin gFrontEnd )
				)
				( attribute "ROT" "0"
					( Origin gFrontEnd )
				)
				( attribute "SEC" "1"
					( Origin gFrontEnd )
				)
				( attribute "SEC_TYPE" "0402"
					( Origin gFrontEnd )
				)
				( attribute "TOLERANCE" "5.0%"
					( Origin gFrontEnd )
				)
				( attribute "VALUE" "51"
					( Origin gFrontEnd )
				)
				( attribute "VER" "1"
					( Origin gFrontEnd )
				)
				( attribute "WATTAGE" "1/16W"
					( Origin gFrontEnd )
				)
				( attribute "XY" "(-1425,2675)"
					( Origin gFrontEnd )
				)
				( attribute "CHIPS_PART_NAME" "RES"
					( Origin gPackager )
				)
				( attribute "CDS_PART_NAME" "RES_0402-51,5.0%,1/16W,CHIP,G2A"
					( Origin gPackager )
				)
				( attribute "CDS_SEC" "1"
					( Origin gPackager )
				)
				( objectStatus "R2R6" )
				( pin "a"
					( attribute "PN" "1"
						( Origin gPackager )
					)
					( objectStatus "R2R6.1" )
				)
				( pin "b"
					( attribute "PN" "2"
						( Origin gPackager )
					)
					( objectStatus "R2R6.2" )
				)
			)
			( gate "@baseboard_fab2_lib.baseboard_fab2(sch_1):page191_i172"
				( attribute "BOM_COST" "CPLD"
					( Origin gFrontEnd )
				)
				( attribute "CDS_LIB" "mstr_discrete"
					( Origin gPackager )
				)
				( attribute "CDS_LOCATION" "R2R7"
					( Origin gPackager )
				)
				( attribute "LOCATION" "R2R7"
					( Origin gFrontEnd )
				)
				( attribute "MATERIAL" "CHIP"
					( Origin gFrontEnd )
				)
				( attribute "PACK_TYPE" "0402"
					( Origin gFrontEnd )
				)
				( attribute "PART_NUMBER" "G21796-072"
					( Origin gFrontEnd )
				)
				( attribute "PHYS_PAGE" "191"
					( Origin gFrontEnd )
				)
				( attribute "ROOM" "CPLD"
					( Origin gFrontEnd )
				)
				( attribute "ROT" "2"
					( Origin gFrontEnd )
				)
				( attribute "SEC" "1"
					( Origin gFrontEnd )
				)
				( attribute "SEC_TYPE" "0402"
					( Origin gFrontEnd )
				)
				( attribute "SIGNAL_MODEL" "DEFAULT_RESISTOR_47000OHM_2_1"
					( Origin gFrontEnd )
				)
				( attribute "TOLERANCE" "1%"
					( Origin gFrontEnd )
				)
				( attribute "VALUE" "4.75K"
					( Origin gFrontEnd )
				)
				( attribute "VER" "2"
					( Origin gFrontEnd )
				)
				( attribute "WATTAGE" "1/16W"
					( Origin gFrontEnd )
				)
				( attribute "XY" "(-1375,3550)"
					( Origin gFrontEnd )
				)
				( attribute "CHIPS_PART_NAME" "RES"
					( Origin gPackager )
				)
				( attribute "CDS_PART_NAME" "RES_0402-4.75K,1%,1/16W,CHIP,GA"
					( Origin gPackager )
				)
				( attribute "CDS_SEC" "1"
					( Origin gPackager )
				)
				( objectStatus "R2R7" )
				( pin "a"
					( attribute "PN" "1"
						( Origin gPackager )
					)
					( objectStatus "R2R7.1" )
				)
				( pin "b"
					( attribute "PN" "2"
						( Origin gPackager )
					)
					( objectStatus "R2R7.2" )
				)
			)
			( gate "@baseboard_fab2_lib.baseboard_fab2(sch_1):page191_i184"
				( attribute "BOM_COST" "CPLD"
					( Origin gFrontEnd )
				)
				( attribute "CDS_LIB" "mstr_discrete"
					( Origin gPackager )
				)
				( attribute "CDS_LOCATION" "R2R4"
					( Origin gPackager )
				)
				( attribute "CDS_SEC" "1"
					( Origin gPackager )
				)
				( attribute "LOCATION" "R2R4"
					( Origin gFrontEnd )
				)
				( attribute "MATERIAL" "CHIP"
					( Origin gFrontEnd )
				)
				( attribute "PACK_TYPE" "0402"
					( Origin gFrontEnd )
				)
				( attribute "PART_NUMBER" "G21497-005"
					( Origin gFrontEnd )
				)
				( attribute "PHYS_PAGE" "191"
					( Origin gFrontEnd )
				)
				( attribute "ROOM" "CPLD"
					( Origin gFrontEnd )
				)
				( attribute "ROT" "0"
					( Origin gFrontEnd )
				)
				( attribute "SEC" "1"
					( Origin gPackager )
				)
				( attribute "TOLERANCE" "5%"
					( Origin gFrontEnd )
				)
				( attribute "VALUE" "0.0"
					( Origin gFrontEnd )
				)
				( attribute "VER" "1"
					( Origin gFrontEnd )
				)
				( attribute "WATTAGE" "1/16W"
					( Origin gFrontEnd )
				)
				( attribute "XY" "(-3200,4325)"
					( Origin gFrontEnd )
				)
				( attribute "CHIPS_PART_NAME" "RES"
					( Origin gPackager )
				)
				( attribute "CDS_PART_NAME" "RES_0402-0.0,5%,1/16W,CHIP,G21A"
					( Origin gPackager )
				)
				( objectStatus "R2R4" )
				( pin "a"
					( attribute "PN" "1"
						( Origin gPackager )
					)
					( objectStatus "R2R4.1" )
				)
				( pin "b"
					( attribute "PN" "2"
						( Origin gPackager )
					)
					( objectStatus "R2R4.2" )
				)
			)
			( gate "@baseboard_fab2_lib.baseboard_fab2(sch_1):page191_i193"
				( attribute "CDS_LIB" "mstr_discrete"
					( Origin gPackager )
				)
				( attribute "CDS_LOCATION" "R7D42"
					( Origin gPackager )
				)
				( attribute "CDS_SEC" "1"
					( Origin gPackager )
				)
				( attribute "LOCATION" "R7D42"
					( Origin gFrontEnd )
				)
				( attribute "MATERIAL" "CHIP"
					( Origin gFrontEnd )
				)
				( attribute "PACK_TYPE" "0402"
					( Origin gFrontEnd )
				)
				( attribute "PART_NUMBER" "G21796-072"
					( Origin gFrontEnd )
				)
				( attribute "PHYS_PAGE" "191"
					( Origin gFrontEnd )
				)
				( attribute "ROOM" "CPLD"
					( Origin gFrontEnd )
				)
				( attribute "ROT" "0"
					( Origin gFrontEnd )
				)
				( attribute "SEC" "1"
					( Origin gFrontEnd )
				)
				( attribute "SEC_TYPE" "0402"
					( Origin gFrontEnd )
				)
				( attribute "TOLERANCE" "1%"
					( Origin gFrontEnd )
				)
				( attribute "VALUE" "4.75K"
					( Origin gFrontEnd )
				)
				( attribute "VER" "2"
					( Origin gFrontEnd )
				)
				( attribute "WATTAGE" "1/16W"
					( Origin gFrontEnd )
				)
				( attribute "XY" "(-7225,2675)"
					( Origin gFrontEnd )
				)
				( attribute "CHIPS_PART_NAME" "RES"
					( Origin gPackager )
				)
				( attribute "CDS_PART_NAME" "RES_0402-4.75K,1%,1/16W,CHIP,GA"
					( Origin gPackager )
				)
				( objectStatus "R7D42" )
				( pin "a"
					( attribute "PN" "1"
						( Origin gPackager )
					)
					( objectStatus "R7D42.1" )
				)
				( pin "b"
					( attribute "PN" "2"
						( Origin gPackager )
					)
					( objectStatus "R7D42.2" )
				)
			)
			( gate "@baseboard_fab2_lib.baseboard_fab2(sch_1):page192_i1"
				( attribute "BOM_COST" "CPLD"
					( Origin gFrontEnd )
				)
				( attribute "CDS_LIB" "dev_discrete"
					( Origin gPackager )
				)
				( attribute "CDS_LOCATION" "C2P8"
					( Origin gPackager )
				)
				( attribute "CDS_SEC" "1"
					( Origin gPackager )
				)
				( attribute "LOCATION" "C2P8"
					( Origin gFrontEnd )
				)
				( attribute "MATERIAL" "X7R"
					( Origin gFrontEnd )
				)
				( attribute "PACK_TYPE" "0402V"
					( Origin gFrontEnd )
				)
				( attribute "PART_NUMBER" "A36096-045"
					( Origin gFrontEnd )
				)
				( attribute "PHYS_PAGE" "192"
					( Origin gFrontEnd )
				)
				( attribute "ROOM" "CPLD"
					( Origin gFrontEnd )
				)
				( attribute "ROT" "0"
					( Origin gFrontEnd )
				)
				( attribute "SEC" "1"
					( Origin gPackager )
				)
				( attribute "SIGNAL_MODEL" "DEFAULT_CAPACITOR_10000pF_2_1"
					( Origin gFrontEnd )
				)
				( attribute "TOLERANCE" "10%"
					( Origin gFrontEnd )
				)
				( attribute "VALUE" "0.01UF"
					( Origin gFrontEnd )
				)
				( attribute "VER" "1"
					( Origin gFrontEnd )
				)
				( attribute "VOLTAGE" "25V"
					( Units "uVoltage" "V" 1.000000)
					( Origin gFrontEnd )
				)
				( attribute "XY" "(-1225,1975)"
					( Origin gFrontEnd )
				)
				( attribute "CHIPS_PART_NAME" "CAP_A"
					( Origin gPackager )
				)
				( attribute "CDS_PART_NAME" "CAP_A_0402V-0.01UF,25V,10%,X7RA"
					( Origin gPackager )
				)
				( objectStatus "C2P8" )
				( pin "a"
					( attribute "PN" "1"
						( Origin gPackager )
					)
					( objectStatus "C2P8.1" )
				)
				( pin "b"
					( attribute "PN" "2"
						( Origin gPackager )
					)
					( objectStatus "C2P8.2" )
				)
			)
			( gate "@baseboard_fab2_lib.baseboard_fab2(sch_1):page192_i3"
				( attribute "BOM_COST" "CPLD"
					( Origin gFrontEnd )
				)
				( attribute "CDS_LIB" "dev_discrete"
					( Origin gPackager )
				)
				( attribute "CDS_LOCATION" "C2P5"
					( Origin gPackager )
				)
				( attribute "CDS_SEC" "1"
					( Origin gPackager )
				)
				( attribute "LOCATION" "C2P5"
					( Origin gFrontEnd )
				)
				( attribute "MATERIAL" "X7R"
					( Origin gFrontEnd )
				)
				( attribute "PACK_TYPE" "0402V"
					( Origin gFrontEnd )
				)
				( attribute "PART_NUMBER" "A36096-030"
					( Origin gFrontEnd )
				)
				( attribute "PHYS_PAGE" "192"
					( Origin gFrontEnd )
				)
				( attribute "ROOM" "CPLD"
					( Origin gFrontEnd )
				)
				( attribute "ROT" "0"
					( Origin gFrontEnd )
				)
				( attribute "SEC" "1"
					( Origin gPackager )
				)
				( attribute "SIGNAL_MODEL" "DEFAULT_CAPACITOR_100000pF_2_1"
					( Origin gFrontEnd )
				)
				( attribute "TOLERANCE" "10%"
					( Origin gFrontEnd )
				)
				( attribute "VALUE" "0.1UF"
					( Origin gFrontEnd )
				)
				( attribute "VER" "1"
					( Origin gFrontEnd )
				)
				( attribute "VOLTAGE" "16V"
					( Units "uVoltage" "V" 1.000000)
					( Origin gFrontEnd )
				)
				( attribute "XY" "(-1700,1975)"
					( Origin gFrontEnd )
				)
				( attribute "CHIPS_PART_NAME" "CAP_A"
					( Origin gPackager )
				)
				( attribute "CDS_PART_NAME" "CAP_A_0402V-0.1UF,16V,10%,X7R,A"
					( Origin gPackager )
				)
				( objectStatus "C2P5" )
				( pin "a"
					( attribute "PN" "1"
						( Origin gPackager )
					)
					( objectStatus "C2P5.1" )
				)
				( pin "b"
					( attribute "PN" "2"
						( Origin gPackager )
					)
					( objectStatus "C2P5.2" )
				)
			)
			( gate "@baseboard_fab2_lib.baseboard_fab2(sch_1):page192_i4"
				( attribute "BOM_COST" "CPLD"
					( Origin gFrontEnd )
				)
				( attribute "CDS_LIB" "dev_discrete"
					( Origin gPackager )
				)
				( attribute "CDS_LOCATION" "C3R1"
					( Origin gPackager )
				)
				( attribute "CDS_SEC" "1"
					( Origin gPackager )
				)
				( attribute "LOCATION" "C3R1"
					( Origin gFrontEnd )
				)
				( attribute "MATERIAL" "X7R"
					( Origin gFrontEnd )
				)
				( attribute "PACK_TYPE" "0402V"
					( Origin gFrontEnd )
				)
				( attribute "PART_NUMBER" "A36096-030"
					( Origin gFrontEnd )
				)
				( attribute "PHYS_PAGE" "192"
					( Origin gFrontEnd )
				)
				( attribute "ROOM" "CPLD"
					( Origin gFrontEnd )
				)
				( attribute "ROT" "0"
					( Origin gFrontEnd )
				)
				( attribute "SEC" "1"
					( Origin gPackager )
				)
				( attribute "SIGNAL_MODEL" "DEFAULT_CAPACITOR_100000pF_2_1"
					( Origin gFrontEnd )
				)
				( attribute "TOLERANCE" "10%"
					( Origin gFrontEnd )
				)
				( attribute "VALUE" "0.1UF"
					( Origin gFrontEnd )
				)
				( attribute "VER" "1"
					( Origin gFrontEnd )
				)
				( attribute "VOLTAGE" "16V"
					( Units "uVoltage" "V" 1.000000)
					( Origin gFrontEnd )
				)
				( attribute "XY" "(-2175,1975)"
					( Origin gFrontEnd )
				)
				( attribute "CHIPS_PART_NAME" "CAP_A"
					( Origin gPackager )
				)
				( attribute "CDS_PART_NAME" "CAP_A_0402V-0.1UF,16V,10%,X7R,A"
					( Origin gPackager )
				)
				( objectStatus "C3R1" )
				( pin "a"
					( attribute "PN" "1"
						( Origin gPackager )
					)
					( objectStatus "C3R1.1" )
				)
				( pin "b"
					( attribute "PN" "2"
						( Origin gPackager )
					)
					( objectStatus "C3R1.2" )
				)
			)
			( gate "@baseboard_fab2_lib.baseboard_fab2(sch_1):page192_i6"
				( attribute "BOM_COST" "CPLD"
					( Origin gFrontEnd )
				)
				( attribute "CDS_LIB" "dev_discrete"
					( Origin gPackager )
				)
				( attribute "CDS_LOCATION" "C3P43"
					( Origin gPackager )
				)
				( attribute "CDS_SEC" "1"
					( Origin gPackager )
				)
				( attribute "LOCATION" "C3P43"
					( Origin gFrontEnd )
				)
				( attribute "MATERIAL" "X7R"
					( Origin gFrontEnd )
				)
				( attribute "PACK_TYPE" "0402V"
					( Origin gFrontEnd )
				)
				( attribute "PART_NUMBER" "A36096-030"
					( Origin gFrontEnd )
				)
				( attribute "PHYS_PAGE" "192"
					( Origin gFrontEnd )
				)
				( attribute "ROOM" "CPLD"
					( Origin gFrontEnd )
				)
				( attribute "ROT" "0"
					( Origin gFrontEnd )
				)
				( attribute "SEC" "1"
					( Origin gPackager )
				)
				( attribute "SIGNAL_MODEL" "DEFAULT_CAPACITOR_100000pF_2_1"
					( Origin gFrontEnd )
				)
				( attribute "TOLERANCE" "10%"
					( Origin gFrontEnd )
				)
				( attribute "VALUE" "0.1UF"
					( Origin gFrontEnd )
				)
				( attribute "VER" "1"
					( Origin gFrontEnd )
				)
				( attribute "VOLTAGE" "16V"
					( Units "uVoltage" "V" 1.000000)
					( Origin gFrontEnd )
				)
				( attribute "XY" "(-2650,1975)"
					( Origin gFrontEnd )
				)
				( attribute "CHIPS_PART_NAME" "CAP_A"
					( Origin gPackager )
				)
				( attribute "CDS_PART_NAME" "CAP_A_0402V-0.1UF,16V,10%,X7R,A"
					( Origin gPackager )
				)
				( objectStatus "C3P43" )
				( pin "a"
					( attribute "PN" "1"
						( Origin gPackager )
					)
					( objectStatus "C3P43.1" )
				)
				( pin "b"
					( attribute "PN" "2"
						( Origin gPackager )
					)
					( objectStatus "C3P43.2" )
				)
			)
			( gate "@baseboard_fab2_lib.baseboard_fab2(sch_1):page192_i7"
				( attribute "BOM_COST" "CPLD"
					( Origin gFrontEnd )
				)
				( attribute "CDS_LIB" "dev_discrete"
					( Origin gPackager )
				)
				( attribute "CDS_LOCATION" "C3R3"
					( Origin gPackager )
				)
				( attribute "CDS_SEC" "1"
					( Origin gPackager )
				)
				( attribute "LOCATION" "C3R3"
					( Origin gFrontEnd )
				)
				( attribute "MATERIAL" "X7R"
					( Origin gFrontEnd )
				)
				( attribute "PACK_TYPE" "0402V"
					( Origin gFrontEnd )
				)
				( attribute "PART_NUMBER" "A36096-030"
					( Origin gFrontEnd )
				)
				( attribute "PHYS_PAGE" "192"
					( Origin gFrontEnd )
				)
				( attribute "ROOM" "CPLD"
					( Origin gFrontEnd )
				)
				( attribute "ROT" "0"
					( Origin gFrontEnd )
				)
				( attribute "SEC" "1"
					( Origin gPackager )
				)
				( attribute "SIGNAL_MODEL" "DEFAULT_CAPACITOR_100000pF_2_1"
					( Origin gFrontEnd )
				)
				( attribute "TOLERANCE" "10%"
					( Origin gFrontEnd )
				)
				( attribute "VALUE" "0.1UF"
					( Origin gFrontEnd )
				)
				( attribute "VER" "1"
					( Origin gFrontEnd )
				)
				( attribute "VOLTAGE" "16V"
					( Units "uVoltage" "V" 1.000000)
					( Origin gFrontEnd )
				)
				( attribute "XY" "(-3125,1975)"
					( Origin gFrontEnd )
				)
				( attribute "CHIPS_PART_NAME" "CAP_A"
					( Origin gPackager )
				)
				( attribute "CDS_PART_NAME" "CAP_A_0402V-0.1UF,16V,10%,X7R,A"
					( Origin gPackager )
				)
				( objectStatus "C3R3" )
				( pin "a"
					( attribute "PN" "1"
						( Origin gPackager )
					)
					( objectStatus "C3R3.1" )
				)
				( pin "b"
					( attribute "PN" "2"
						( Origin gPackager )
					)
					( objectStatus "C3R3.2" )
				)
			)
			( gate "@baseboard_fab2_lib.baseboard_fab2(sch_1):page192_i8"
				( attribute "BOM_COST" "CPLD"
					( Origin gFrontEnd )
				)
				( attribute "CDS_LIB" "dev_discrete"
					( Origin gPackager )
				)
				( attribute "CDS_LOCATION" "C2R1"
					( Origin gPackager )
				)
				( attribute "CDS_SEC" "1"
					( Origin gPackager )
				)
				( attribute "LOCATION" "C2R1"
					( Origin gFrontEnd )
				)
				( attribute "MATERIAL" "X7R"
					( Origin gFrontEnd )
				)
				( attribute "PACK_TYPE" "0402V"
					( Origin gFrontEnd )
				)
				( attribute "PART_NUMBER" "A36096-030"
					( Origin gFrontEnd )
				)
				( attribute "PHYS_PAGE" "192"
					( Origin gFrontEnd )
				)
				( attribute "ROOM" "CPLD"
					( Origin gFrontEnd )
				)
				( attribute "ROT" "0"
					( Origin gFrontEnd )
				)
				( attribute "SEC" "1"
					( Origin gPackager )
				)
				( attribute "SIGNAL_MODEL" "DEFAULT_CAPACITOR_100000pF_2_1"
					( Origin gFrontEnd )
				)
				( attribute "TOLERANCE" "10%"
					( Origin gFrontEnd )
				)
				( attribute "VALUE" "0.1UF"
					( Origin gFrontEnd )
				)
				( attribute "VER" "1"
					( Origin gFrontEnd )
				)
				( attribute "VOLTAGE" "16V"
					( Units "uVoltage" "V" 1.000000)
					( Origin gFrontEnd )
				)
				( attribute "XY" "(-3150,1300)"
					( Origin gFrontEnd )
				)
				( attribute "CHIPS_PART_NAME" "CAP_A"
					( Origin gPackager )
				)
				( attribute "CDS_PART_NAME" "CAP_A_0402V-0.1UF,16V,10%,X7R,A"
					( Origin gPackager )
				)
				( objectStatus "C2R1" )
				( pin "a"
					( attribute "PN" "1"
						( Origin gPackager )
					)
					( objectStatus "C2R1.1" )
				)
				( pin "b"
					( attribute "PN" "2"
						( Origin gPackager )
					)
					( objectStatus "C2R1.2" )
				)
			)
			( gate "@baseboard_fab2_lib.baseboard_fab2(sch_1):page192_i9"
				( attribute "BOM_COST" "CPLD"
					( Origin gFrontEnd )
				)
				( attribute "CDS_LIB" "dev_discrete"
					( Origin gPackager )
				)
				( attribute "CDS_LOCATION" "C2P2"
					( Origin gPackager )
				)
				( attribute "CDS_SEC" "1"
					( Origin gPackager )
				)
				( attribute "LOCATION" "C2P2"
					( Origin gFrontEnd )
				)
				( attribute "MATERIAL" "X7R"
					( Origin gFrontEnd )
				)
				( attribute "PACK_TYPE" "0402V"
					( Origin gFrontEnd )
				)
				( attribute "PART_NUMBER" "A36096-030"
					( Origin gFrontEnd )
				)
				( attribute "PHYS_PAGE" "192"
					( Origin gFrontEnd )
				)
				( attribute "ROOM" "CPLD"
					( Origin gFrontEnd )
				)
				( attribute "ROT" "0"
					( Origin gFrontEnd )
				)
				( attribute "SEC" "1"
					( Origin gPackager )
				)
				( attribute "SIGNAL_MODEL" "DEFAULT_CAPACITOR_100000pF_2_1"
					( Origin gFrontEnd )
				)
				( attribute "TOLERANCE" "10%"
					( Origin gFrontEnd )
				)
				( attribute "VALUE" "0.1UF"
					( Origin gFrontEnd )
				)
				( attribute "VER" "1"
					( Origin gFrontEnd )
				)
				( attribute "VOLTAGE" "16V"
					( Units "uVoltage" "V" 1.000000)
					( Origin gFrontEnd )
				)
				( attribute "XY" "(-3600,1975)"
					( Origin gFrontEnd )
				)
				( attribute "CHIPS_PART_NAME" "CAP_A"
					( Origin gPackager )
				)
				( attribute "CDS_PART_NAME" "CAP_A_0402V-0.1UF,16V,10%,X7R,A"
					( Origin gPackager )
				)
				( objectStatus "C2P2" )
				( pin "a"
					( attribute "PN" "1"
						( Origin gPackager )
					)
					( objectStatus "C2P2.1" )
				)
				( pin "b"
					( attribute "PN" "2"
						( Origin gPackager )
					)
					( objectStatus "C2P2.2" )
				)
			)
			( gate "@baseboard_fab2_lib.baseboard_fab2(sch_1):page192_i10"
				( attribute "BOM_COST" "CPLD"
					( Origin gFrontEnd )
				)
				( attribute "CDS_LIB" "dev_discrete"
					( Origin gPackager )
				)
				( attribute "CDS_LOCATION" "C3R2"
					( Origin gPackager )
				)
				( attribute "CDS_SEC" "1"
					( Origin gPackager )
				)
				( attribute "LOCATION" "C3R2"
					( Origin gFrontEnd )
				)
				( attribute "MATERIAL" "X7R"
					( Origin gFrontEnd )
				)
				( attribute "PACK_TYPE" "0402V"
					( Origin gFrontEnd )
				)
				( attribute "PART_NUMBER" "A36096-030"
					( Origin gFrontEnd )
				)
				( attribute "PHYS_PAGE" "192"
					( Origin gFrontEnd )
				)
				( attribute "ROOM" "CPLD"
					( Origin gFrontEnd )
				)
				( attribute "ROT" "0"
					( Origin gFrontEnd )
				)
				( attribute "SEC" "1"
					( Origin gPackager )
				)
				( attribute "SIGNAL_MODEL" "DEFAULT_CAPACITOR_100000pF_2_1"
					( Origin gFrontEnd )
				)
				( attribute "TOLERANCE" "10%"
					( Origin gFrontEnd )
				)
				( attribute "VALUE" "0.1UF"
					( Origin gFrontEnd )
				)
				( attribute "VER" "1"
					( Origin gFrontEnd )
				)
				( attribute "VOLTAGE" "16V"
					( Units "uVoltage" "V" 1.000000)
					( Origin gFrontEnd )
				)
				( attribute "XY" "(-4075,1975)"
					( Origin gFrontEnd )
				)
				( attribute "CHIPS_PART_NAME" "CAP_A"
					( Origin gPackager )
				)
				( attribute "CDS_PART_NAME" "CAP_A_0402V-0.1UF,16V,10%,X7R,A"
					( Origin gPackager )
				)
				( objectStatus "C3R2" )
				( pin "a"
					( attribute "PN" "1"
						( Origin gPackager )
					)
					( objectStatus "C3R2.1" )
				)
				( pin "b"
					( attribute "PN" "2"
						( Origin gPackager )
					)
					( objectStatus "C3R2.2" )
				)
			)
			( gate "@baseboard_fab2_lib.baseboard_fab2(sch_1):page192_i11"
				( attribute "BOM_COST" "CPLD"
					( Origin gFrontEnd )
				)
				( attribute "CDS_LIB" "dev_discrete"
					( Origin gPackager )
				)
				( attribute "CDS_LOCATION" "C3P51"
					( Origin gPackager )
				)
				( attribute "CDS_SEC" "1"
					( Origin gPackager )
				)
				( attribute "LOCATION" "C3P51"
					( Origin gFrontEnd )
				)
				( attribute "MATERIAL" "X7R"
					( Origin gFrontEnd )
				)
				( attribute "PACK_TYPE" "0402V"
					( Origin gFrontEnd )
				)
				( attribute "PART_NUMBER" "A36096-030"
					( Origin gFrontEnd )
				)
				( attribute "PHYS_PAGE" "192"
					( Origin gFrontEnd )
				)
				( attribute "ROOM" "CPLD"
					( Origin gFrontEnd )
				)
				( attribute "ROT" "0"
					( Origin gFrontEnd )
				)
				( attribute "SEC" "1"
					( Origin gPackager )
				)
				( attribute "SIGNAL_MODEL" "DEFAULT_CAPACITOR_100000pF_2_1"
					( Origin gFrontEnd )
				)
				( attribute "TOLERANCE" "10%"
					( Origin gFrontEnd )
				)
				( attribute "VALUE" "0.1UF"
					( Origin gFrontEnd )
				)
				( attribute "VER" "1"
					( Origin gFrontEnd )
				)
				( attribute "VOLTAGE" "16V"
					( Units "uVoltage" "V" 1.000000)
					( Origin gFrontEnd )
				)
				( attribute "XY" "(-3700,1300)"
					( Origin gFrontEnd )
				)
				( attribute "CHIPS_PART_NAME" "CAP_A"
					( Origin gPackager )
				)
				( attribute "CDS_PART_NAME" "CAP_A_0402V-0.1UF,16V,10%,X7R,A"
					( Origin gPackager )
				)
				( objectStatus "C3P51" )
				( pin "a"
					( attribute "PN" "1"
						( Origin gPackager )
					)
					( objectStatus "C3P51.1" )
				)
				( pin "b"
					( attribute "PN" "2"
						( Origin gPackager )
					)
					( objectStatus "C3P51.2" )
				)
			)
			( gate "@baseboard_fab2_lib.baseboard_fab2(sch_1):page192_i12"
				( attribute "BOM_COST" "CPLD"
					( Origin gFrontEnd )
				)
				( attribute "CDS_LIB" "dev_discrete"
					( Origin gPackager )
				)
				( attribute "CDS_LOCATION" "C3P47"
					( Origin gPackager )
				)
				( attribute "CDS_SEC" "1"
					( Origin gPackager )
				)
				( attribute "LOCATION" "C3P47"
					( Origin gFrontEnd )
				)
				( attribute "MATERIAL" "X7R"
					( Origin gFrontEnd )
				)
				( attribute "PACK_TYPE" "0402V"
					( Origin gFrontEnd )
				)
				( attribute "PART_NUMBER" "A36096-030"
					( Origin gFrontEnd )
				)
				( attribute "PHYS_PAGE" "192"
					( Origin gFrontEnd )
				)
				( attribute "ROOM" "CPLD"
					( Origin gFrontEnd )
				)
				( attribute "ROT" "0"
					( Origin gFrontEnd )
				)
				( attribute "SEC" "1"
					( Origin gPackager )
				)
				( attribute "SIGNAL_MODEL" "DEFAULT_CAPACITOR_100000pF_2_1"
					( Origin gFrontEnd )
				)
				( attribute "TOLERANCE" "10%"
					( Origin gFrontEnd )
				)
				( attribute "VALUE" "0.1UF"
					( Origin gFrontEnd )
				)
				( attribute "VER" "1"
					( Origin gFrontEnd )
				)
				( attribute "VOLTAGE" "16V"
					( Units "uVoltage" "V" 1.000000)
					( Origin gFrontEnd )
				)
				( attribute "XY" "(-4200,1300)"
					( Origin gFrontEnd )
				)
				( attribute "CHIPS_PART_NAME" "CAP_A"
					( Origin gPackager )
				)
				( attribute "CDS_PART_NAME" "CAP_A_0402V-0.1UF,16V,10%,X7R,A"
					( Origin gPackager )
				)
				( objectStatus "C3P47" )
				( pin "a"
					( attribute "PN" "1"
						( Origin gPackager )
					)
					( objectStatus "C3P47.1" )
				)
				( pin "b"
					( attribute "PN" "2"
						( Origin gPackager )
					)
					( objectStatus "C3P47.2" )
				)
			)
			( gate "@baseboard_fab2_lib.baseboard_fab2(sch_1):page192_i14"
				( attribute "BOM_COST" "CPLD"
					( Origin gFrontEnd )
				)
				( attribute "CDS_LIB" "mstr_memory"
					( Origin gPackager )
				)
				( attribute "CDS_LMAN_SYM_OUTLINE" "-400,750,400,-750"
					( Origin gPackager )
				)
				( attribute "CDS_LOCATION" "U8D7"
					( Origin gPackager )
				)
				( attribute "LOCATION" "U8D7"
					( Origin gFrontEnd )
				)
				( attribute "MATERIAL" "IC"
					( Origin gFrontEnd )
				)
				( attribute "PACK_TYPE" "256BGA"
					( Origin gFrontEnd )
				)
				( attribute "PART_NUMBER" "H63395-001"
					( Origin gFrontEnd )
				)
				( attribute "PHYS_PAGE" "192"
					( Origin gFrontEnd )
				)
				( attribute "ROOM" "CPLD"
					( Origin gFrontEnd )
				)
				( attribute "ROT" "0"
					( Origin gFrontEnd )
				)
				( attribute "SEC" "3"
					( Origin gFrontEnd )
				)
				( attribute "SEC_TYPE" "256BGA"
					( Origin gFrontEnd )
				)
				( attribute "VER" "6"
					( Origin gFrontEnd )
				)
				( attribute "XY" "(-1850,3900)"
					( Origin gFrontEnd )
				)
				( attribute "CHIPS_PART_NAME" "LCMXO2_A"
					( Origin gPackager )
				)
				( attribute "CDS_PART_NAME" "LCMXO2_A_256BGA-IC,H63395-001"
					( Origin gPackager )
				)
				( attribute "CDS_SEC" "3"
					( Origin gPackager )
				)
				( objectStatus "U8D7" )
				( pin "gnd(0)"
					( attribute "PN" "B2"
						( Origin gPackager )
					)
					( objectStatus "U8D7.B2" )
				)
				( pin "gnd(1)"
					( attribute "PN" "B15"
						( Origin gPackager )
					)
					( objectStatus "U8D7.B15" )
				)
				( pin "gnd(2)"
					( attribute "PN" "C3"
						( Origin gPackager )
					)
					( objectStatus "U8D7.C3" )
				)
				( pin "gnd(3)"
					( attribute "PN" "C14"
						( Origin gPackager )
					)
					( objectStatus "U8D7.C14" )
				)
				( pin "gnd(4)"
					( attribute "PN" "D4"
						( Origin gPackager )
					)
					( objectStatus "U8D7.D4" )
				)
				( pin "gnd(5)"
					( attribute "PN" "D13"
						( Origin gPackager )
					)
					( objectStatus "U8D7.D13" )
				)
				( pin "gnd(6)"
					( attribute "PN" "E5"
						( Origin gPackager )
					)
					( objectStatus "U8D7.E5" )
				)
				( pin "gnd(7)"
					( attribute "PN" "E12"
						( Origin gPackager )
					)
					( objectStatus "U8D7.E12" )
				)
				( pin "gnd(8)"
					( attribute "PN" "F6"
						( Origin gPackager )
					)
					( objectStatus "U8D7.F6" )
				)
				( pin "gnd(9)"
					( attribute "PN" "F11"
						( Origin gPackager )
					)
					( objectStatus "U8D7.F11" )
				)
				( pin "gnd(10)"
					( attribute "PN" "H8"
						( Origin gPackager )
					)
					( objectStatus "U8D7.H8" )
				)
				( pin "gnd(11)"
					( attribute "PN" "H9"
						( Origin gPackager )
					)
					( objectStatus "U8D7.H9" )
				)
				( pin "gnd(12)"
					( attribute "PN" "J8"
						( Origin gPackager )
					)
					( objectStatus "U8D7.J8" )
				)
				( pin "gnd(13)"
					( attribute "PN" "J9"
						( Origin gPackager )
					)
					( objectStatus "U8D7.J9" )
				)
				( pin "gnd(14)"
					( attribute "PN" "L6"
						( Origin gPackager )
					)
					( objectStatus "U8D7.L6" )
				)
				( pin "gnd(15)"
					( attribute "PN" "L11"
						( Origin gPackager )
					)
					( objectStatus "U8D7.L11" )
				)
				( pin "gnd(16)"
					( attribute "PN" "M5"
						( Origin gPackager )
					)
					( objectStatus "U8D7.M5" )
				)
				( pin "gnd(17)"
					( attribute "PN" "M12"
						( Origin gPackager )
					)
					( objectStatus "U8D7.M12" )
				)
				( pin "gnd(18)"
					( attribute "PN" "N4"
						( Origin gPackager )
					)
					( objectStatus "U8D7.N4" )
				)
				( pin "gnd(19)"
					( attribute "PN" "N13"
						( Origin gPackager )
					)
					( objectStatus "U8D7.N13" )
				)
				( pin "gnd(20)"
					( attribute "PN" "P3"
						( Origin gPackager )
					)
					( objectStatus "U8D7.P3" )
				)
				( pin "gnd(21)"
					( attribute "PN" "P14"
						( Origin gPackager )
					)
					( objectStatus "U8D7.P14" )
				)
				( pin "gnd(22)"
					( attribute "PN" "R2"
						( Origin gPackager )
					)
					( objectStatus "U8D7.R2" )
				)
				( pin "gnd(23)"
					( attribute "PN" "R15"
						( Origin gPackager )
					)
					( objectStatus "U8D7.R15" )
				)
				( pin "nc(0)"
					( attribute "PN" "A2"
						( Origin gPackager )
					)
					( objectStatus "U8D7.A2" )
				)
				( pin "vcc(0)"
					( attribute "PN" "A1"
						( Origin gPackager )
					)
					( objectStatus "U8D7.A1" )
				)
				( pin "vcc(1)"
					( attribute "PN" "A16"
						( Origin gPackager )
					)
					( objectStatus "U8D7.A16" )
				)
				( pin "vcc(2)"
					( attribute "PN" "T1"
						( Origin gPackager )
					)
					( objectStatus "U8D7.T1" )
				)
				( pin "vcc(3)"
					( attribute "PN" "T16"
						( Origin gPackager )
					)
					( objectStatus "U8D7.T16" )
				)
				( pin "vcc(4)"
					( attribute "PN" "G7"
						( Origin gPackager )
					)
					( objectStatus "U8D7.G7" )
				)
				( pin "vcc(5)"
					( attribute "PN" "G10"
						( Origin gPackager )
					)
					( objectStatus "U8D7.G10" )
				)
				( pin "vcc(6)"
					( attribute "PN" "K7"
						( Origin gPackager )
					)
					( objectStatus "U8D7.K7" )
				)
				( pin "vcc(7)"
					( attribute "PN" "K10"
						( Origin gPackager )
					)
					( objectStatus "U8D7.K10" )
				)
				( pin "vccio0(0)"
					( attribute "PN" "G8"
						( Origin gPackager )
					)
					( objectStatus "U8D7.G8" )
				)
				( pin "vccio0(1)"
					( attribute "PN" "D12"
						( Origin gPackager )
					)
					( objectStatus "U8D7.D12" )
				)
				( pin "vccio0(2)"
					( attribute "PN" "G9"
						( Origin gPackager )
					)
					( objectStatus "U8D7.G9" )
				)
				( pin "vccio0(3)"
					( attribute "PN" "D5"
						( Origin gPackager )
					)
					( objectStatus "U8D7.D5" )
				)
				( pin "vccio1(0)"
					( attribute "PN" "E13"
						( Origin gPackager )
					)
					( objectStatus "U8D7.E13" )
				)
				( pin "vccio1(1)"
					( attribute "PN" "H10"
						( Origin gPackager )
					)
					( objectStatus "U8D7.H10" )
				)
				( pin "vccio1(2)"
					( attribute "PN" "J10"
						( Origin gPackager )
					)
					( objectStatus "U8D7.J10" )
				)
				( pin "vccio1(3)"
					( attribute "PN" "M13"
						( Origin gPackager )
					)
					( objectStatus "U8D7.M13" )
				)
				( pin "vccio2(0)"
					( attribute "PN" "K9"
						( Origin gPackager )
					)
					( objectStatus "U8D7.K9" )
				)
				( pin "vccio2(1)"
					( attribute "PN" "N12"
						( Origin gPackager )
					)
					( objectStatus "U8D7.N12" )
				)
				( pin "vccio2(2)"
					( attribute "PN" "K8"
						( Origin gPackager )
					)
					( objectStatus "U8D7.K8" )
				)
				( pin "vccio2(3)"
					( attribute "PN" "N5"
						( Origin gPackager )
					)
					( objectStatus "U8D7.N5" )
				)
				( pin "vccio3(0)"
					( attribute "PN" "M4"
						( Origin gPackager )
					)
					( objectStatus "U8D7.M4" )
				)
				( pin "vccio4(0)"
					( attribute "PN" "J7"
						( Origin gPackager )
					)
					( objectStatus "U8D7.J7" )
				)
				( pin "vccio4(1)"
					( attribute "PN" "H7"
						( Origin gPackager )
					)
					( objectStatus "U8D7.H7" )
				)
				( pin "vccio5(0)"
					( attribute "PN" "E4"
						( Origin gPackager )
					)
					( objectStatus "U8D7.E4" )
				)
			)
			( gate "@baseboard_fab2_lib.baseboard_fab2(sch_1):page192_i15"
				( attribute "BOM_COST" "CPLD"
					( Origin gFrontEnd )
				)
				( attribute "CDS_LIB" "dev_discrete"
					( Origin gPackager )
				)
				( attribute "CDS_LOCATION" "C2R5"
					( Origin gPackager )
				)
				( attribute "CDS_SEC" "1"
					( Origin gPackager )
				)
				( attribute "LOCATION" "C2R5"
					( Origin gFrontEnd )
				)
				( attribute "MATERIAL" "X7R"
					( Origin gFrontEnd )
				)
				( attribute "PACK_TYPE" "0402V"
					( Origin gFrontEnd )
				)
				( attribute "PART_NUMBER" "A36096-030"
					( Origin gFrontEnd )
				)
				( attribute "PHYS_PAGE" "192"
					( Origin gFrontEnd )
				)
				( attribute "ROOM" "CPLD"
					( Origin gFrontEnd )
				)
				( attribute "ROT" "0"
					( Origin gFrontEnd )
				)
				( attribute "SEC" "1"
					( Origin gPackager )
				)
				( attribute "SIGNAL_MODEL" "DEFAULT_CAPACITOR_100000pF_2_1"
					( Origin gFrontEnd )
				)
				( attribute "TOLERANCE" "10%"
					( Origin gFrontEnd )
				)
				( attribute "VALUE" "0.1UF"
					( Origin gFrontEnd )
				)
				( attribute "VER" "1"
					( Origin gFrontEnd )
				)
				( attribute "VOLTAGE" "16V"
					( Units "uVoltage" "V" 1.000000)
					( Origin gFrontEnd )
				)
				( attribute "XY" "(-4550,1975)"
					( Origin gFrontEnd )
				)
				( attribute "CHIPS_PART_NAME" "CAP_A"
					( Origin gPackager )
				)
				( attribute "CDS_PART_NAME" "CAP_A_0402V-0.1UF,16V,10%,X7R,A"
					( Origin gPackager )
				)
				( objectStatus "C2R5" )
				( pin "a"
					( attribute "PN" "1"
						( Origin gPackager )
					)
					( objectStatus "C2R5.1" )
				)
				( pin "b"
					( attribute "PN" "2"
						( Origin gPackager )
					)
					( objectStatus "C2R5.2" )
				)
			)
			( gate "@baseboard_fab2_lib.baseboard_fab2(sch_1):page192_i16"
				( attribute "BOM_COST" "CPLD"
					( Origin gFrontEnd )
				)
				( attribute "CDS_LIB" "dev_discrete"
					( Origin gPackager )
				)
				( attribute "CDS_LOCATION" "C2P4"
					( Origin gPackager )
				)
				( attribute "CDS_SEC" "1"
					( Origin gPackager )
				)
				( attribute "LOCATION" "C2P4"
					( Origin gFrontEnd )
				)
				( attribute "MATERIAL" "X7R"
					( Origin gFrontEnd )
				)
				( attribute "PACK_TYPE" "0402V"
					( Origin gFrontEnd )
				)
				( attribute "PART_NUMBER" "A36096-030"
					( Origin gFrontEnd )
				)
				( attribute "PHYS_PAGE" "192"
					( Origin gFrontEnd )
				)
				( attribute "ROOM" "CPLD"
					( Origin gFrontEnd )
				)
				( attribute "ROT" "0"
					( Origin gFrontEnd )
				)
				( attribute "SEC" "1"
					( Origin gPackager )
				)
				( attribute "SIGNAL_MODEL" "DEFAULT_CAPACITOR_100000pF_2_1"
					( Origin gFrontEnd )
				)
				( attribute "TOLERANCE" "10%"
					( Origin gFrontEnd )
				)
				( attribute "VALUE" "0.1UF"
					( Origin gFrontEnd )
				)
				( attribute "VER" "1"
					( Origin gFrontEnd )
				)
				( attribute "VOLTAGE" "16V"
					( Units "uVoltage" "V" 1.000000)
					( Origin gFrontEnd )
				)
				( attribute "XY" "(-5025,1975)"
					( Origin gFrontEnd )
				)
				( attribute "CHIPS_PART_NAME" "CAP_A"
					( Origin gPackager )
				)
				( attribute "CDS_PART_NAME" "CAP_A_0402V-0.1UF,16V,10%,X7R,A"
					( Origin gPackager )
				)
				( objectStatus "C2P4" )
				( pin "a"
					( attribute "PN" "1"
						( Origin gPackager )
					)
					( objectStatus "C2P4.1" )
				)
				( pin "b"
					( attribute "PN" "2"
						( Origin gPackager )
					)
					( objectStatus "C2P4.2" )
				)
			)
			( gate "@baseboard_fab2_lib.baseboard_fab2(sch_1):page192_i17"
				( attribute "BOM_COST" "CPLD"
					( Origin gFrontEnd )
				)
				( attribute "CDS_LIB" "dev_discrete"
					( Origin gPackager )
				)
				( attribute "CDS_LOCATION" "C3P52"
					( Origin gPackager )
				)
				( attribute "CDS_SEC" "1"
					( Origin gPackager )
				)
				( attribute "LOCATION" "C3P52"
					( Origin gFrontEnd )
				)
				( attribute "MATERIAL" "X7R"
					( Origin gFrontEnd )
				)
				( attribute "PACK_TYPE" "0402V"
					( Origin gFrontEnd )
				)
				( attribute "PART_NUMBER" "A36096-030"
					( Origin gFrontEnd )
				)
				( attribute "PHYS_PAGE" "192"
					( Origin gFrontEnd )
				)
				( attribute "ROOM" "CPLD"
					( Origin gFrontEnd )
				)
				( attribute "ROT" "0"
					( Origin gFrontEnd )
				)
				( attribute "SEC" "1"
					( Origin gPackager )
				)
				( attribute "SIGNAL_MODEL" "DEFAULT_CAPACITOR_100000pF_2_1"
					( Origin gFrontEnd )
				)
				( attribute "TOLERANCE" "10%"
					( Origin gFrontEnd )
				)
				( attribute "VALUE" "0.1UF"
					( Origin gFrontEnd )
				)
				( attribute "VER" "1"
					( Origin gFrontEnd )
				)
				( attribute "VOLTAGE" "16V"
					( Units "uVoltage" "V" 1.000000)
					( Origin gFrontEnd )
				)
				( attribute "XY" "(-4725,1300)"
					( Origin gFrontEnd )
				)
				( attribute "CHIPS_PART_NAME" "CAP_A"
					( Origin gPackager )
				)
				( attribute "CDS_PART_NAME" "CAP_A_0402V-0.1UF,16V,10%,X7R,A"
					( Origin gPackager )
				)
				( objectStatus "C3P52" )
				( pin "a"
					( attribute "PN" "1"
						( Origin gPackager )
					)
					( objectStatus "C3P52.1" )
				)
				( pin "b"
					( attribute "PN" "2"
						( Origin gPackager )
					)
					( objectStatus "C3P52.2" )
				)
			)
			( gate "@baseboard_fab2_lib.baseboard_fab2(sch_1):page192_i18"
				( attribute "BOM_COST" "CPLD"
					( Origin gFrontEnd )
				)
				( attribute "CDS_LIB" "dev_discrete"
					( Origin gPackager )
				)
				( attribute "CDS_LOCATION" "C2P6"
					( Origin gPackager )
				)
				( attribute "CDS_SEC" "1"
					( Origin gPackager )
				)
				( attribute "LOCATION" "C2P6"
					( Origin gFrontEnd )
				)
				( attribute "MATERIAL" "X7R"
					( Origin gFrontEnd )
				)
				( attribute "PACK_TYPE" "0402V"
					( Origin gFrontEnd )
				)
				( attribute "PART_NUMBER" "A36096-030"
					( Origin gFrontEnd )
				)
				( attribute "PHYS_PAGE" "192"
					( Origin gFrontEnd )
				)
				( attribute "ROOM" "CPLD"
					( Origin gFrontEnd )
				)
				( attribute "ROT" "0"
					( Origin gFrontEnd )
				)
				( attribute "SEC" "1"
					( Origin gPackager )
				)
				( attribute "SIGNAL_MODEL" "DEFAULT_CAPACITOR_100000pF_2_1"
					( Origin gFrontEnd )
				)
				( attribute "TOLERANCE" "10%"
					( Origin gFrontEnd )
				)
				( attribute "VALUE" "0.1UF"
					( Origin gFrontEnd )
				)
				( attribute "VER" "1"
					( Origin gFrontEnd )
				)
				( attribute "VOLTAGE" "16V"
					( Units "uVoltage" "V" 1.000000)
					( Origin gFrontEnd )
				)
				( attribute "XY" "(-5225,1300)"
					( Origin gFrontEnd )
				)
				( attribute "CHIPS_PART_NAME" "CAP_A"
					( Origin gPackager )
				)
				( attribute "CDS_PART_NAME" "CAP_A_0402V-0.1UF,16V,10%,X7R,A"
					( Origin gPackager )
				)
				( objectStatus "C2P6" )
				( pin "a"
					( attribute "PN" "1"
						( Origin gPackager )
					)
					( objectStatus "C2P6.1" )
				)
				( pin "b"
					( attribute "PN" "2"
						( Origin gPackager )
					)
					( objectStatus "C2P6.2" )
				)
			)
			( gate "@baseboard_fab2_lib.baseboard_fab2(sch_1):page192_i19"
				( attribute "BOM_COST" "CPLD"
					( Origin gFrontEnd )
				)
				( attribute "CDS_LIB" "dev_discrete"
					( Origin gPackager )
				)
				( attribute "CDS_LOCATION" "C2R3"
					( Origin gPackager )
				)
				( attribute "CDS_SEC" "1"
					( Origin gPackager )
				)
				( attribute "LOCATION" "C2R3"
					( Origin gFrontEnd )
				)
				( attribute "MATERIAL" "X7R"
					( Origin gFrontEnd )
				)
				( attribute "PACK_TYPE" "0402V"
					( Origin gFrontEnd )
				)
				( attribute "PART_NUMBER" "A36096-030"
					( Origin gFrontEnd )
				)
				( attribute "PHYS_PAGE" "192"
					( Origin gFrontEnd )
				)
				( attribute "ROOM" "CPLD"
					( Origin gFrontEnd )
				)
				( attribute "ROT" "0"
					( Origin gFrontEnd )
				)
				( attribute "SEC" "1"
					( Origin gPackager )
				)
				( attribute "SIGNAL_MODEL" "DEFAULT_CAPACITOR_100000pF_2_1"
					( Origin gFrontEnd )
				)
				( attribute "TOLERANCE" "10%"
					( Origin gFrontEnd )
				)
				( attribute "VALUE" "0.1UF"
					( Origin gFrontEnd )
				)
				( attribute "VER" "1"
					( Origin gFrontEnd )
				)
				( attribute "VOLTAGE" "16V"
					( Units "uVoltage" "V" 1.000000)
					( Origin gFrontEnd )
				)
				( attribute "XY" "(-5500,1975)"
					( Origin gFrontEnd )
				)
				( attribute "CHIPS_PART_NAME" "CAP_A"
					( Origin gPackager )
				)
				( attribute "CDS_PART_NAME" "CAP_A_0402V-0.1UF,16V,10%,X7R,A"
					( Origin gPackager )
				)
				( objectStatus "C2R3" )
				( pin "a"
					( attribute "PN" "1"
						( Origin gPackager )
					)
					( objectStatus "C2R3.1" )
				)
				( pin "b"
					( attribute "PN" "2"
						( Origin gPackager )
					)
					( objectStatus "C2R3.2" )
				)
			)
			( gate "@baseboard_fab2_lib.baseboard_fab2(sch_1):page192_i20"
				( attribute "BOM_COST" "CPLD"
					( Origin gFrontEnd )
				)
				( attribute "CDS_LIB" "dev_discrete"
					( Origin gPackager )
				)
				( attribute "CDS_LOCATION" "C2P7"
					( Origin gPackager )
				)
				( attribute "CDS_SEC" "1"
					( Origin gPackager )
				)
				( attribute "LOCATION" "C2P7"
					( Origin gFrontEnd )
				)
				( attribute "MATERIAL" "X7R"
					( Origin gFrontEnd )
				)
				( attribute "PACK_TYPE" "0402V"
					( Origin gFrontEnd )
				)
				( attribute "PART_NUMBER" "A36096-030"
					( Origin gFrontEnd )
				)
				( attribute "PHYS_PAGE" "192"
					( Origin gFrontEnd )
				)
				( attribute "ROOM" "CPLD"
					( Origin gFrontEnd )
				)
				( attribute "ROT" "0"
					( Origin gFrontEnd )
				)
				( attribute "SEC" "1"
					( Origin gPackager )
				)
				( attribute "SIGNAL_MODEL" "DEFAULT_CAPACITOR_100000pF_2_1"
					( Origin gFrontEnd )
				)
				( attribute "TOLERANCE" "10%"
					( Origin gFrontEnd )
				)
				( attribute "VALUE" "0.1UF"
					( Origin gFrontEnd )
				)
				( attribute "VER" "1"
					( Origin gFrontEnd )
				)
				( attribute "VOLTAGE" "16V"
					( Units "uVoltage" "V" 1.000000)
					( Origin gFrontEnd )
				)
				( attribute "XY" "(-5975,1975)"
					( Origin gFrontEnd )
				)
				( attribute "CHIPS_PART_NAME" "CAP_A"
					( Origin gPackager )
				)
				( attribute "CDS_PART_NAME" "CAP_A_0402V-0.1UF,16V,10%,X7R,A"
					( Origin gPackager )
				)
				( objectStatus "C2P7" )
				( pin "a"
					( attribute "PN" "1"
						( Origin gPackager )
					)
					( objectStatus "C2P7.1" )
				)
				( pin "b"
					( attribute "PN" "2"
						( Origin gPackager )
					)
					( objectStatus "C2P7.2" )
				)
			)
			( gate "@baseboard_fab2_lib.baseboard_fab2(sch_1):page192_i21"
				( attribute "BOM_COST" "CPLD"
					( Origin gFrontEnd )
				)
				( attribute "CDS_LIB" "dev_discrete"
					( Origin gPackager )
				)
				( attribute "CDS_LOCATION" "C2R4"
					( Origin gPackager )
				)
				( attribute "CDS_SEC" "1"
					( Origin gPackager )
				)
				( attribute "LOCATION" "C2R4"
					( Origin gFrontEnd )
				)
				( attribute "MATERIAL" "X7R"
					( Origin gFrontEnd )
				)
				( attribute "PACK_TYPE" "0402V"
					( Origin gFrontEnd )
				)
				( attribute "PART_NUMBER" "A36096-030"
					( Origin gFrontEnd )
				)
				( attribute "PHYS_PAGE" "192"
					( Origin gFrontEnd )
				)
				( attribute "ROOM" "CPLD"
					( Origin gFrontEnd )
				)
				( attribute "ROT" "0"
					( Origin gFrontEnd )
				)
				( attribute "SEC" "1"
					( Origin gPackager )
				)
				( attribute "SIGNAL_MODEL" "DEFAULT_CAPACITOR_100000pF_2_1"
					( Origin gFrontEnd )
				)
				( attribute "TOLERANCE" "10%"
					( Origin gFrontEnd )
				)
				( attribute "VALUE" "0.1UF"
					( Origin gFrontEnd )
				)
				( attribute "VER" "1"
					( Origin gFrontEnd )
				)
				( attribute "VOLTAGE" "16V"
					( Units "uVoltage" "V" 1.000000)
					( Origin gFrontEnd )
				)
				( attribute "XY" "(-5700,1300)"
					( Origin gFrontEnd )
				)
				( attribute "CHIPS_PART_NAME" "CAP_A"
					( Origin gPackager )
				)
				( attribute "CDS_PART_NAME" "CAP_A_0402V-0.1UF,16V,10%,X7R,A"
					( Origin gPackager )
				)
				( objectStatus "C2R4" )
				( pin "a"
					( attribute "PN" "1"
						( Origin gPackager )
					)
					( objectStatus "C2R4.1" )
				)
				( pin "b"
					( attribute "PN" "2"
						( Origin gPackager )
					)
					( objectStatus "C2R4.2" )
				)
			)
			( gate "@baseboard_fab2_lib.baseboard_fab2(sch_1):page192_i22"
				( attribute "BOM_COST" "CPLD"
					( Origin gFrontEnd )
				)
				( attribute "CDS_LIB" "dev_discrete"
					( Origin gPackager )
				)
				( attribute "CDS_LOCATION" "C2P3"
					( Origin gPackager )
				)
				( attribute "CDS_SEC" "1"
					( Origin gPackager )
				)
				( attribute "LOCATION" "C2P3"
					( Origin gFrontEnd )
				)
				( attribute "MATERIAL" "X7R"
					( Origin gFrontEnd )
				)
				( attribute "PACK_TYPE" "0402V"
					( Origin gFrontEnd )
				)
				( attribute "PART_NUMBER" "A36096-030"
					( Origin gFrontEnd )
				)
				( attribute "PHYS_PAGE" "192"
					( Origin gFrontEnd )
				)
				( attribute "ROOM" "CPLD"
					( Origin gFrontEnd )
				)
				( attribute "ROT" "0"
					( Origin gFrontEnd )
				)
				( attribute "SEC" "1"
					( Origin gPackager )
				)
				( attribute "SIGNAL_MODEL" "DEFAULT_CAPACITOR_100000pF_2_1"
					( Origin gFrontEnd )
				)
				( attribute "TOLERANCE" "10%"
					( Origin gFrontEnd )
				)
				( attribute "VALUE" "0.1UF"
					( Origin gFrontEnd )
				)
				( attribute "VER" "1"
					( Origin gFrontEnd )
				)
				( attribute "VOLTAGE" "16V"
					( Units "uVoltage" "V" 1.000000)
					( Origin gFrontEnd )
				)
				( attribute "XY" "(-6250,1300)"
					( Origin gFrontEnd )
				)
				( attribute "CHIPS_PART_NAME" "CAP_A"
					( Origin gPackager )
				)
				( attribute "CDS_PART_NAME" "CAP_A_0402V-0.1UF,16V,10%,X7R,A"
					( Origin gPackager )
				)
				( objectStatus "C2P3" )
				( pin "a"
					( attribute "PN" "1"
						( Origin gPackager )
					)
					( objectStatus "C2P3.1" )
				)
				( pin "b"
					( attribute "PN" "2"
						( Origin gPackager )
					)
					( objectStatus "C2P3.2" )
				)
			)
			( gate "@baseboard_fab2_lib.baseboard_fab2(sch_1):page192_i23"
				( attribute "BOM_COST" "CPLD"
					( Origin gFrontEnd )
				)
				( attribute "CDS_LIB" "dev_discrete"
					( Origin gPackager )
				)
				( attribute "CDS_LOCATION" "C3P44"
					( Origin gPackager )
				)
				( attribute "CDS_SEC" "1"
					( Origin gPackager )
				)
				( attribute "LOCATION" "C3P44"
					( Origin gFrontEnd )
				)
				( attribute "MATERIAL" "X7R"
					( Origin gFrontEnd )
				)
				( attribute "PACK_TYPE" "0402V"
					( Origin gFrontEnd )
				)
				( attribute "PART_NUMBER" "A36096-030"
					( Origin gFrontEnd )
				)
				( attribute "PHYS_PAGE" "192"
					( Origin gFrontEnd )
				)
				( attribute "ROOM" "CPLD"
					( Origin gFrontEnd )
				)
				( attribute "ROT" "0"
					( Origin gFrontEnd )
				)
				( attribute "SEC" "1"
					( Origin gPackager )
				)
				( attribute "SIGNAL_MODEL" "DEFAULT_CAPACITOR_100000pF_2_1"
					( Origin gFrontEnd )
				)
				( attribute "TOLERANCE" "10%"
					( Origin gFrontEnd )
				)
				( attribute "VALUE" "0.1UF"
					( Origin gFrontEnd )
				)
				( attribute "VER" "1"
					( Origin gFrontEnd )
				)
				( attribute "VOLTAGE" "16V"
					( Units "uVoltage" "V" 1.000000)
					( Origin gFrontEnd )
				)
				( attribute "XY" "(-6450,1975)"
					( Origin gFrontEnd )
				)
				( attribute "CHIPS_PART_NAME" "CAP_A"
					( Origin gPackager )
				)
				( attribute "CDS_PART_NAME" "CAP_A_0402V-0.1UF,16V,10%,X7R,A"
					( Origin gPackager )
				)
				( objectStatus "C3P44" )
				( pin "a"
					( attribute "PN" "1"
						( Origin gPackager )
					)
					( objectStatus "C3P44.1" )
				)
				( pin "b"
					( attribute "PN" "2"
						( Origin gPackager )
					)
					( objectStatus "C3P44.2" )
				)
			)
			( gate "@baseboard_fab2_lib.baseboard_fab2(sch_1):page192_i25"
				( attribute "BOM_COST" "CPLD"
					( Origin gFrontEnd )
				)
				( attribute "CDS_LIB" "dev_discrete"
					( Origin gPackager )
				)
				( attribute "CDS_LOCATION" "C3P48"
					( Origin gPackager )
				)
				( attribute "CDS_SEC" "1"
					( Origin gPackager )
				)
				( attribute "LOCATION" "C3P48"
					( Origin gFrontEnd )
				)
				( attribute "MATERIAL" "X7R"
					( Origin gFrontEnd )
				)
				( attribute "PACK_TYPE" "0402V"
					( Origin gFrontEnd )
				)
				( attribute "PART_NUMBER" "A36096-030"
					( Origin gFrontEnd )
				)
				( attribute "PHYS_PAGE" "192"
					( Origin gFrontEnd )
				)
				( attribute "ROOM" "CPLD"
					( Origin gFrontEnd )
				)
				( attribute "ROT" "0"
					( Origin gFrontEnd )
				)
				( attribute "SEC" "1"
					( Origin gFrontEnd )
				)
				( attribute "SEC_TYPE" "0402V"
					( Origin gFrontEnd )
				)
				( attribute "SIGNAL_MODEL" "DEFAULT_CAPACITOR_100000pF_2_1"
					( Origin gFrontEnd )
				)
				( attribute "TOLERANCE" "10%"
					( Origin gFrontEnd )
				)
				( attribute "VALUE" "0.1UF"
					( Origin gFrontEnd )
				)
				( attribute "VER" "1"
					( Origin gFrontEnd )
				)
				( attribute "VOLTAGE" "16V"
					( Units "uVoltage" "V" 1.000000)
					( Origin gFrontEnd )
				)
				( attribute "XY" "(-6925,1975)"
					( Origin gFrontEnd )
				)
				( attribute "CHIPS_PART_NAME" "CAP_A"
					( Origin gPackager )
				)
				( attribute "CDS_PART_NAME" "CAP_A_0402V-0.1UF,16V,10%,X7R,A"
					( Origin gPackager )
				)
				( objectStatus "C3P48" )
				( pin "a"
					( attribute "PN" "1"
						( Origin gPackager )
					)
					( objectStatus "C3P48.1" )
				)
				( pin "b"
					( attribute "PN" "2"
						( Origin gPackager )
					)
					( objectStatus "C3P48.2" )
				)
			)
			( gate "@baseboard_fab2_lib.baseboard_fab2(sch_1):page192_i28"
				( attribute "BOM_COST" "CPLD"
					( Origin gFrontEnd )
				)
				( attribute "CDS_LIB" "dev_discrete"
					( Origin gPackager )
				)
				( attribute "CDS_LOCATION" "C2R2"
					( Origin gPackager )
				)
				( attribute "CDS_SEC" "1"
					( Origin gPackager )
				)
				( attribute "LOCATION" "C2R2"
					( Origin gFrontEnd )
				)
				( attribute "MATERIAL" "X7R"
					( Origin gFrontEnd )
				)
				( attribute "PACK_TYPE" "0402V"
					( Origin gFrontEnd )
				)
				( attribute "PART_NUMBER" "A36096-030"
					( Origin gFrontEnd )
				)
				( attribute "PHYS_PAGE" "192"
					( Origin gFrontEnd )
				)
				( attribute "ROOM" "CPLD"
					( Origin gFrontEnd )
				)
				( attribute "ROT" "0"
					( Origin gFrontEnd )
				)
				( attribute "SEC" "1"
					( Origin gPackager )
				)
				( attribute "SIGNAL_MODEL" "DEFAULT_CAPACITOR_100000pF_2_1"
					( Origin gFrontEnd )
				)
				( attribute "TOLERANCE" "10%"
					( Origin gFrontEnd )
				)
				( attribute "VALUE" "0.1UF"
					( Origin gFrontEnd )
				)
				( attribute "VER" "1"
					( Origin gFrontEnd )
				)
				( attribute "VOLTAGE" "16V"
					( Units "uVoltage" "V" 1.000000)
					( Origin gFrontEnd )
				)
				( attribute "XY" "(-6850,1300)"
					( Origin gFrontEnd )
				)
				( attribute "CHIPS_PART_NAME" "CAP_A"
					( Origin gPackager )
				)
				( attribute "CDS_PART_NAME" "CAP_A_0402V-0.1UF,16V,10%,X7R,A"
					( Origin gPackager )
				)
				( objectStatus "C2R2" )
				( pin "a"
					( attribute "PN" "1"
						( Origin gPackager )
					)
					( objectStatus "C2R2.1" )
				)
				( pin "b"
					( attribute "PN" "2"
						( Origin gPackager )
					)
					( objectStatus "C2R2.2" )
				)
			)
			( gate "@baseboard_fab2_lib.baseboard_fab2(sch_1):page192_i33"
				( attribute "BOM_COST" "CPLD"
					( Origin gFrontEnd )
				)
				( attribute "CDS_LIB" "mstr_discrete"
					( Origin gPackager )
				)
				( attribute "CDS_LOCATION" "R7E6"
					( Origin gPackager )
				)
				( attribute "CDS_SEC" "1"
					( Origin gPackager )
				)
				( attribute "LOCATION" "R7E6"
					( Origin gFrontEnd )
				)
				( attribute "MATERIAL" "CHIP"
					( Origin gFrontEnd )
				)
				( attribute "PACK_TYPE" "0402"
					( Origin gFrontEnd )
				)
				( attribute "PART_NUMBER" "G21796-016"
					( Origin gFrontEnd )
				)
				( attribute "PHYS_PAGE" "192"
					( Origin gFrontEnd )
				)
				( attribute "ROOM" "CPLD"
					( Origin gFrontEnd )
				)
				( attribute "ROT" "0"
					( Origin gFrontEnd )
				)
				( attribute "SEC" "1"
					( Origin gPackager )
				)
				( attribute "TOLERANCE" "1%"
					( Origin gFrontEnd )
				)
				( attribute "VALUE" "10.0K"
					( Origin gFrontEnd )
				)
				( attribute "VER" "2"
					( Origin gFrontEnd )
				)
				( attribute "WATTAGE" "1/16W"
					( Origin gFrontEnd )
				)
				( attribute "XY" "(-6150,4400)"
					( Origin gFrontEnd )
				)
				( attribute "CHIPS_PART_NAME" "RES"
					( Origin gPackager )
				)
				( attribute "CDS_PART_NAME" "RES_0402-10.0K,1%,1/16W,CHIP,GA"
					( Origin gPackager )
				)
				( objectStatus "R7E6" )
				( pin "a"
					( attribute "PN" "1"
						( Origin gPackager )
					)
					( objectStatus "R7E6.1" )
				)
				( pin "b"
					( attribute "PN" "2"
						( Origin gPackager )
					)
					( objectStatus "R7E6.2" )
				)
			)
			( gate "@baseboard_fab2_lib.baseboard_fab2(sch_1):page192_i34"
				( attribute "BOM_COST" "CPLD"
					( Origin gFrontEnd )
				)
				( attribute "CDS_LIB" "mstr_discrete"
					( Origin gPackager )
				)
				( attribute "CDS_LOCATION" "R2R1"
					( Origin gPackager )
				)
				( attribute "CDS_SEC" "1"
					( Origin gPackager )
				)
				( attribute "LOCATION" "R2R1"
					( Origin gFrontEnd )
				)
				( attribute "MATERIAL" "CHIP"
					( Origin gFrontEnd )
				)
				( attribute "PACK_TYPE" "0402"
					( Origin gFrontEnd )
				)
				( attribute "PART_NUMBER" "G21796-016"
					( Origin gFrontEnd )
				)
				( attribute "PHYS_PAGE" "192"
					( Origin gFrontEnd )
				)
				( attribute "ROOM" "CPLD"
					( Origin gFrontEnd )
				)
				( attribute "ROT" "0"
					( Origin gFrontEnd )
				)
				( attribute "SEC" "1"
					( Origin gPackager )
				)
				( attribute "TOLERANCE" "1%"
					( Origin gFrontEnd )
				)
				( attribute "VALUE" "10.0K"
					( Origin gFrontEnd )
				)
				( attribute "VER" "2"
					( Origin gFrontEnd )
				)
				( attribute "WATTAGE" "1/16W"
					( Origin gFrontEnd )
				)
				( attribute "XY" "(-5750,4400)"
					( Origin gFrontEnd )
				)
				( attribute "CHIPS_PART_NAME" "RES"
					( Origin gPackager )
				)
				( attribute "CDS_PART_NAME" "RES_0402-10.0K,1%,1/16W,CHIP,GA"
					( Origin gPackager )
				)
				( objectStatus "R2R1" )
				( pin "a"
					( attribute "PN" "1"
						( Origin gPackager )
					)
					( objectStatus "R2R1.1" )
				)
				( pin "b"
					( attribute "PN" "2"
						( Origin gPackager )
					)
					( objectStatus "R2R1.2" )
				)
			)
			( gate "@baseboard_fab2_lib.baseboard_fab2(sch_1):page192_i38"
				( attribute "BOM_COST" "CPLD"
					( Origin gFrontEnd )
				)
				( attribute "CDS_LIB" "mstr_discrete"
					( Origin gPackager )
				)
				( attribute "CDS_LOCATION" "R7E5"
					( Origin gPackager )
				)
				( attribute "CDS_SEC" "1"
					( Origin gPackager )
				)
				( attribute "LOCATION" "R7E5"
					( Origin gFrontEnd )
				)
				( attribute "MATERIAL" "CHIP"
					( Origin gFrontEnd )
				)
				( attribute "PACK_TYPE" "0402"
					( Origin gFrontEnd )
				)
				( attribute "PART_NUMBER" "G21796-016"
					( Origin gFrontEnd )
				)
				( attribute "PHYS_PAGE" "192"
					( Origin gFrontEnd )
				)
				( attribute "ROOM" "CPLD"
					( Origin gFrontEnd )
				)
				( attribute "ROT" "0"
					( Origin gFrontEnd )
				)
				( attribute "SEC" "1"
					( Origin gPackager )
				)
				( attribute "TOLERANCE" "1%"
					( Origin gFrontEnd )
				)
				( attribute "VALUE" "10.0K"
					( Origin gFrontEnd )
				)
				( attribute "VER" "2"
					( Origin gFrontEnd )
				)
				( attribute "WATTAGE" "1/16W"
					( Origin gFrontEnd )
				)
				( attribute "XY" "(-6550,4400)"
					( Origin gFrontEnd )
				)
				( attribute "CHIPS_PART_NAME" "RES"
					( Origin gPackager )
				)
				( attribute "CDS_PART_NAME" "RES_0402-10.0K,1%,1/16W,CHIP,GA"
					( Origin gPackager )
				)
				( objectStatus "R7E5" )
				( pin "a"
					( attribute "PN" "1"
						( Origin gPackager )
					)
					( objectStatus "R7E5.1" )
				)
				( pin "b"
					( attribute "PN" "2"
						( Origin gPackager )
					)
					( objectStatus "R7E5.2" )
				)
			)
			( gate "@baseboard_fab2_lib.baseboard_fab2(sch_1):page192_i41"
				( attribute "BOM_COST" "CPLD"
					( Origin gFrontEnd )
				)
				( attribute "CDS_LIB" "mstr_discrete"
					( Origin gPackager )
				)
				( attribute "CDS_LOCATION" "R2R3"
					( Origin gPackager )
				)
				( attribute "CDS_SEC" "1"
					( Origin gPackager )
				)
				( attribute "LOCATION" "R2R3"
					( Origin gFrontEnd )
				)
				( attribute "MATERIAL" "CHIP"
					( Origin gFrontEnd )
				)
				( attribute "PACK_TYPE" "0402"
					( Origin gFrontEnd )
				)
				( attribute "PART_NUMBER" "G21796-016"
					( Origin gFrontEnd )
				)
				( attribute "PHYS_PAGE" "192"
					( Origin gFrontEnd )
				)
				( attribute "ROOM" "CPLD"
					( Origin gFrontEnd )
				)
				( attribute "ROT" "0"
					( Origin gFrontEnd )
				)
				( attribute "SEC" "1"
					( Origin gPackager )
				)
				( attribute "TOLERANCE" "1%"
					( Origin gFrontEnd )
				)
				( attribute "VALUE" "10.0K"
					( Origin gFrontEnd )
				)
				( attribute "VER" "2"
					( Origin gFrontEnd )
				)
				( attribute "WATTAGE" "1/16W"
					( Origin gFrontEnd )
				)
				( attribute "XY" "(-6950,4400)"
					( Origin gFrontEnd )
				)
				( attribute "CHIPS_PART_NAME" "RES"
					( Origin gPackager )
				)
				( attribute "CDS_PART_NAME" "RES_0402-10.0K,1%,1/16W,CHIP,GA"
					( Origin gPackager )
				)
				( objectStatus "R2R3" )
				( pin "a"
					( attribute "PN" "1"
						( Origin gPackager )
					)
					( objectStatus "R2R3.1" )
				)
				( pin "b"
					( attribute "PN" "2"
						( Origin gPackager )
					)
					( objectStatus "R2R3.2" )
				)
			)
			( gate "@baseboard_fab2_lib.baseboard_fab2(sch_1):page192_i48"
				( attribute "BOM_COST" "CPLD"
					( Origin gFrontEnd )
				)
				( attribute "CDS_LIB" "mstr_discrete"
					( Origin gPackager )
				)
				( attribute "CDS_LOCATION" "R3R16"
					( Origin gPackager )
				)
				( attribute "CDS_SEC" "1"
					( Origin gPackager )
				)
				( attribute "LOCATION" "R3R16"
					( Origin gFrontEnd )
				)
				( attribute "MATERIAL" "CHIP"
					( Origin gFrontEnd )
				)
				( attribute "PACK_TYPE" "0402"
					( Origin gFrontEnd )
				)
				( attribute "PART_NUMBER" "G21796-072"
					( Origin gFrontEnd )
				)
				( attribute "PHYS_PAGE" "192"
					( Origin gFrontEnd )
				)
				( attribute "ROOM" "CPLD"
					( Origin gFrontEnd )
				)
				( attribute "ROT" "0"
					( Origin gFrontEnd )
				)
				( attribute "SEC" "1"
					( Origin gFrontEnd )
				)
				( attribute "SEC_TYPE" "0402"
					( Origin gFrontEnd )
				)
				( attribute "TOLERANCE" "1%"
					( Origin gFrontEnd )
				)
				( attribute "VALUE" "4.75K"
					( Origin gFrontEnd )
				)
				( attribute "VER" "2"
					( Origin gFrontEnd )
				)
				( attribute "WATTAGE" "1/16W"
					( Origin gFrontEnd )
				)
				( attribute "XY" "(-6150,2800)"
					( Origin gFrontEnd )
				)
				( attribute "CHIPS_PART_NAME" "RES"
					( Origin gPackager )
				)
				( attribute "CDS_PART_NAME" "RES_0402-4.75K,1%,1/16W,CHIP,GA"
					( Origin gPackager )
				)
				( objectStatus "R3R16" )
				( pin "a"
					( attribute "PN" "1"
						( Origin gPackager )
					)
					( objectStatus "R3R16.1" )
				)
				( pin "b"
					( attribute "PN" "2"
						( Origin gPackager )
					)
					( objectStatus "R3R16.2" )
				)
			)
			( gate "@baseboard_fab2_lib.baseboard_fab2(sch_1):page192_i49"
				( attribute "BOM_COST" "CPLD"
					( Origin gFrontEnd )
				)
				( attribute "CDS_LIB" "mstr_discrete"
					( Origin gPackager )
				)
				( attribute "CDS_LOCATION" "R6M9"
					( Origin gPackager )
				)
				( attribute "CDS_SEC" "1"
					( Origin gPackager )
				)
				( attribute "LOCATION" "R6M9"
					( Origin gFrontEnd )
				)
				( attribute "MATERIAL" "CHIP"
					( Origin gFrontEnd )
				)
				( attribute "PACK_TYPE" "0402"
					( Origin gFrontEnd )
				)
				( attribute "PART_NUMBER" "G21796-072"
					( Origin gFrontEnd )
				)
				( attribute "PHYS_PAGE" "192"
					( Origin gFrontEnd )
				)
				( attribute "ROOM" "CPLD"
					( Origin gFrontEnd )
				)
				( attribute "ROT" "0"
					( Origin gFrontEnd )
				)
				( attribute "SEC" "1"
					( Origin gFrontEnd )
				)
				( attribute "SEC_TYPE" "0402"
					( Origin gFrontEnd )
				)
				( attribute "TOLERANCE" "1%"
					( Origin gFrontEnd )
				)
				( attribute "VALUE" "4.75K"
					( Origin gFrontEnd )
				)
				( attribute "VER" "2"
					( Origin gFrontEnd )
				)
				( attribute "WATTAGE" "1/16W"
					( Origin gFrontEnd )
				)
				( attribute "XY" "(-5750,2800)"
					( Origin gFrontEnd )
				)
				( attribute "CHIPS_PART_NAME" "RES"
					( Origin gPackager )
				)
				( attribute "CDS_PART_NAME" "RES_0402-4.75K,1%,1/16W,CHIP,GA"
					( Origin gPackager )
				)
				( objectStatus "R6M9" )
				( pin "a"
					( attribute "PN" "1"
						( Origin gPackager )
					)
					( objectStatus "R6M9.1" )
				)
				( pin "b"
					( attribute "PN" "2"
						( Origin gPackager )
					)
					( objectStatus "R6M9.2" )
				)
			)
			( gate "@baseboard_fab2_lib.baseboard_fab2(sch_1):page192_i55"
				( attribute "BOM_COST" "CPLD"
					( Origin gFrontEnd )
				)
				( attribute "CDS_LIB" "mstr_discrete"
					( Origin gPackager )
				)
				( attribute "CDS_LOCATION" "R7E18"
					( Origin gPackager )
				)
				( attribute "CDS_SEC" "1"
					( Origin gPackager )
				)
				( attribute "LOCATION" "R7E18"
					( Origin gFrontEnd )
				)
				( attribute "MATERIAL" "CHIP"
					( Origin gFrontEnd )
				)
				( attribute "PACK_TYPE" "0402"
					( Origin gFrontEnd )
				)
				( attribute "PART_NUMBER" "G21796-072"
					( Origin gFrontEnd )
				)
				( attribute "PHYS_PAGE" "192"
					( Origin gFrontEnd )
				)
				( attribute "ROOM" "CPLD"
					( Origin gFrontEnd )
				)
				( attribute "ROT" "0"
					( Origin gFrontEnd )
				)
				( attribute "SEC" "1"
					( Origin gPackager )
				)
				( attribute "TOLERANCE" "1%"
					( Origin gFrontEnd )
				)
				( attribute "VALUE" "4.75K"
					( Origin gFrontEnd )
				)
				( attribute "VER" "2"
					( Origin gFrontEnd )
				)
				( attribute "WATTAGE" "1/16W"
					( Origin gFrontEnd )
				)
				( attribute "XY" "(-7350,4400)"
					( Origin gFrontEnd )
				)
				( attribute "CHIPS_PART_NAME" "RES"
					( Origin gPackager )
				)
				( attribute "CDS_PART_NAME" "RES_0402-4.75K,1%,1/16W,CHIP,GA"
					( Origin gPackager )
				)
				( objectStatus "R7E18" )
				( pin "a"
					( attribute "PN" "1"
						( Origin gPackager )
					)
					( objectStatus "R7E18.1" )
				)
				( pin "b"
					( attribute "PN" "2"
						( Origin gPackager )
					)
					( objectStatus "R7E18.2" )
				)
			)
			( gate "@baseboard_fab2_lib.baseboard_fab2(sch_1):page192_i57"
				( attribute "BOM_COST" "CPLD"
					( Origin gFrontEnd )
				)
				( attribute "CDS_LIB" "mstr_discrete"
					( Origin gPackager )
				)
				( attribute "CDS_LOCATION" "R7E19"
					( Origin gPackager )
				)
				( attribute "CDS_SEC" "1"
					( Origin gPackager )
				)
				( attribute "LOCATION" "R7E19"
					( Origin gFrontEnd )
				)
				( attribute "MATERIAL" "EMPTY"
					( Origin gFrontEnd )
				)
				( attribute "PACK_TYPE" "0402"
					( Origin gFrontEnd )
				)
				( attribute "PART_NUMBER" "G21796-026"
					( Origin gFrontEnd )
				)
				( attribute "PHYS_PAGE" "192"
					( Origin gFrontEnd )
				)
				( attribute "ROOM" "CPLD"
					( Origin gFrontEnd )
				)
				( attribute "ROT" "0"
					( Origin gFrontEnd )
				)
				( attribute "SEC" "1"
					( Origin gPackager )
				)
				( attribute "TOLERANCE" "1%"
					( Origin gFrontEnd )
				)
				( attribute "VALUE" "1.00K"
					( Origin gFrontEnd )
				)
				( attribute "VER" "2"
					( Origin gFrontEnd )
				)
				( attribute "WATTAGE" "1/16W"
					( Origin gFrontEnd )
				)
				( attribute "XY" "(-7750,4400)"
					( Origin gFrontEnd )
				)
				( attribute "CHIPS_PART_NAME" "RES"
					( Origin gPackager )
				)
				( attribute "CDS_PART_NAME" "RES_0402-1.00K,1%,1/16W,EMPTY,A"
					( Origin gPackager )
				)
				( objectStatus "R7E19" )
				( pin "a"
					( attribute "PN" "1"
						( Origin gPackager )
					)
					( objectStatus "R7E19.1" )
				)
				( pin "b"
					( attribute "PN" "2"
						( Origin gPackager )
					)
					( objectStatus "R7E19.2" )
				)
			)
			( gate "@baseboard_fab2_lib.baseboard_fab2(sch_1):page192_i59"
				( attribute "BOM_COST" "CPLD"
					( Origin gFrontEnd )
				)
				( attribute "CDS_LIB" "mstr_discrete"
					( Origin gPackager )
				)
				( attribute "CDS_LOCATION" "R7E20"
					( Origin gPackager )
				)
				( attribute "CDS_SEC" "1"
					( Origin gPackager )
				)
				( attribute "LOCATION" "R7E20"
					( Origin gFrontEnd )
				)
				( attribute "MATERIAL" "CHIP"
					( Origin gFrontEnd )
				)
				( attribute "PACK_TYPE" "0402"
					( Origin gFrontEnd )
				)
				( attribute "PART_NUMBER" "G21796-026"
					( Origin gFrontEnd )
				)
				( attribute "PHYS_PAGE" "192"
					( Origin gFrontEnd )
				)
				( attribute "ROOM" "CPLD"
					( Origin gFrontEnd )
				)
				( attribute "ROT" "0"
					( Origin gFrontEnd )
				)
				( attribute "SEC" "1"
					( Origin gPackager )
				)
				( attribute "TOLERANCE" "1%"
					( Origin gFrontEnd )
				)
				( attribute "VALUE" "1.00K"
					( Origin gFrontEnd )
				)
				( attribute "VER" "2"
					( Origin gFrontEnd )
				)
				( attribute "WATTAGE" "1/16W"
					( Origin gFrontEnd )
				)
				( attribute "XY" "(-7750,3500)"
					( Origin gFrontEnd )
				)
				( attribute "CHIPS_PART_NAME" "RES"
					( Origin gPackager )
				)
				( attribute "CDS_PART_NAME" "RES_0402-1.00K,1%,1/16W,CHIP,GA"
					( Origin gPackager )
				)
				( objectStatus "R7E20" )
				( pin "a"
					( attribute "PN" "1"
						( Origin gPackager )
					)
					( objectStatus "R7E20.1" )
				)
				( pin "b"
					( attribute "PN" "2"
						( Origin gPackager )
					)
					( objectStatus "R7E20.2" )
				)
			)
			( gate "@baseboard_fab2_lib.baseboard_fab2(sch_1):page193_i29"
				( attribute "BOM_COST" "PROC_VRD_VCCIN_CPU1"
					( Origin gFrontEnd )
				)
				( attribute "CDS_LIB" "mstr_discrete"
					( Origin gPackager )
				)
				( attribute "CDS_LOCATION" "C4C1"
					( Origin gPackager )
				)
				( attribute "CDS_SEC" "1"
					( Origin gPackager )
				)
				( attribute "LOCATION" "C4C1"
					( Origin gFrontEnd )
				)
				( attribute "MATERIAL" "ALUM"
					( Origin gFrontEnd )
				)
				( attribute "PACK_TYPE" "3018"
					( Origin gFrontEnd )
				)
				( attribute "PART_NUMBER" "699013-049"
					( Origin gFrontEnd )
				)
				( attribute "PHYS_PAGE" "193"
					( Origin gFrontEnd )
				)
				( attribute "ROOM" "P0V95_MCP_CPU1_DECAP_VR"
					( Origin gFrontEnd )
				)
				( attribute "ROT" "0"
					( Origin gFrontEnd )
				)
				( attribute "SEC" "1"
					( Origin gFrontEnd )
				)
				( attribute "SEC_TYPE" "3018"
					( Origin gFrontEnd )
				)
				( attribute "TOLERANCE" "20%"
					( Origin gFrontEnd )
				)
				( attribute "VALUE" "470UF"
					( Origin gFrontEnd )
				)
				( attribute "VER" "1"
					( Origin gFrontEnd )
				)
				( attribute "VOLTAGE" "2.5V"
					( Units "uVoltage" "V" 1.000000)
					( Origin gFrontEnd )
				)
				( attribute "XY" "(-1775,4275)"
					( Origin gFrontEnd )
				)
				( attribute "CHIPS_PART_NAME" "CAPP"
					( Origin gPackager )
				)
				( attribute "CDS_PART_NAME" "CAPP_3018-470UF,2.5V,20%,ALUM,A"
					( Origin gPackager )
				)
				( objectStatus "C4C1" )
				( pin "a"
					( attribute "PN" "1"
						( Origin gPackager )
					)
					( objectStatus "C4C1.1" )
				)
				( pin "b"
					( attribute "PN" "2"
						( Origin gPackager )
					)
					( objectStatus "C4C1.2" )
				)
			)
			( gate "@baseboard_fab2_lib.baseboard_fab2(sch_1):page193_i31"
				( attribute "CDS_LIB" "dev_discrete"
					( Origin gPackager )
				)
				( attribute "CDS_LOCATION" "C3C2"
					( Origin gPackager )
				)
				( attribute "CDS_SEC" "1"
					( Origin gPackager )
				)
				( attribute "LOCATION" "C3C2"
					( Origin gFrontEnd )
				)
				( attribute "MATERIAL" "X6S"
					( Origin gFrontEnd )
				)
				( attribute "PACK_TYPE" "0402V"
					( Origin gFrontEnd )
				)
				( attribute "PART_NUMBER" "D97712-004"
					( Origin gFrontEnd )
				)
				( attribute "PHYS_PAGE" "193"
					( Origin gFrontEnd )
				)
				( attribute "ROOM" "P0V95_FPGA_CPU1"
					( Origin gFrontEnd )
				)
				( attribute "ROT" "2"
					( Origin gFrontEnd )
				)
				( attribute "SEC" "1"
					( Origin gFrontEnd )
				)
				( attribute "SEC_TYPE" "0402V"
					( Origin gFrontEnd )
				)
				( attribute "TOLERANCE" "10%"
					( Origin gFrontEnd )
				)
				( attribute "VALUE" "1.0UF"
					( Origin gFrontEnd )
				)
				( attribute "VER" "1"
					( Origin gFrontEnd )
				)
				( attribute "VOLTAGE" "6.3V"
					( Units "uVoltage" "V" 1.000000)
					( Origin gFrontEnd )
				)
				( attribute "XY" "(-700,4225)"
					( Origin gFrontEnd )
				)
				( attribute "CHIPS_PART_NAME" "CAP_A"
					( Origin gPackager )
				)
				( attribute "CDS_PART_NAME" "CAP_A_0402V-1.0UF,6.3V,10%,X6SA"
					( Origin gPackager )
				)
				( objectStatus "C3C2" )
				( pin "a"
					( attribute "PN" "1"
						( Origin gPackager )
					)
					( objectStatus "C3C2.1" )
				)
				( pin "b"
					( attribute "PN" "2"
						( Origin gPackager )
					)
					( objectStatus "C3C2.2" )
				)
			)
			( gate "@baseboard_fab2_lib.baseboard_fab2(sch_1):page193_i38"
				( attribute "CDS_LIB" "dev_discrete"
					( Origin gPackager )
				)
				( attribute "CDS_LOCATION" "C3C1"
					( Origin gPackager )
				)
				( attribute "CDS_SEC" "1"
					( Origin gPackager )
				)
				( attribute "LOCATION" "C3C1"
					( Origin gFrontEnd )
				)
				( attribute "MATERIAL" "X6S"
					( Origin gFrontEnd )
				)
				( attribute "PACK_TYPE" "0402V"
					( Origin gFrontEnd )
				)
				( attribute "PART_NUMBER" "D97712-004"
					( Origin gFrontEnd )
				)
				( attribute "PHYS_PAGE" "193"
					( Origin gFrontEnd )
				)
				( attribute "ROOM" "P0V95_FPGA_CPU1"
					( Origin gFrontEnd )
				)
				( attribute "ROT" "2"
					( Origin gFrontEnd )
				)
				( attribute "SEC" "1"
					( Origin gFrontEnd )
				)
				( attribute "SEC_TYPE" "0402V"
					( Origin gFrontEnd )
				)
				( attribute "TOLERANCE" "10%"
					( Origin gFrontEnd )
				)
				( attribute "VALUE" "1.0UF"
					( Origin gFrontEnd )
				)
				( attribute "VER" "1"
					( Origin gFrontEnd )
				)
				( attribute "VOLTAGE" "6.3V"
					( Units "uVoltage" "V" 1.000000)
					( Origin gFrontEnd )
				)
				( attribute "XY" "(-1150,4200)"
					( Origin gFrontEnd )
				)
				( attribute "CHIPS_PART_NAME" "CAP_A"
					( Origin gPackager )
				)
				( attribute "CDS_PART_NAME" "CAP_A_0402V-1.0UF,6.3V,10%,X6SA"
					( Origin gPackager )
				)
				( objectStatus "C3C1" )
				( pin "a"
					( attribute "PN" "1"
						( Origin gPackager )
					)
					( objectStatus "C3C1.1" )
				)
				( pin "b"
					( attribute "PN" "2"
						( Origin gPackager )
					)
					( objectStatus "C3C1.2" )
				)
			)
			( gate "@baseboard_fab2_lib.baseboard_fab2(sch_1):page193_i45"
				( attribute "CDS_LIB" "mstr_sconn"
					( Origin gPackager )
				)
				( attribute "CDS_LOCATION" "J4E1"
					( Origin gPackager )
				)
				( attribute "CDS_SEC" "1"
					( Origin gPackager )
				)
				( attribute "LOCATION" "J4E1"
					( Origin gFrontEnd )
				)
				( attribute "MATERIAL" "CONN"
					( Origin gFrontEnd )
				)
				( attribute "PACK_TYPE" "SM"
					( Origin gFrontEnd )
				)
				( attribute "PART_NUMBER" "H61426-002"
					( Origin gFrontEnd )
				)
				( attribute "PHYS_PAGE" "193"
					( Origin gFrontEnd )
				)
				( attribute "ROOM" "MCP VRM CPU1"
					( Origin gFrontEnd )
				)
				( attribute "ROT" "0"
					( Origin gFrontEnd )
				)
				( attribute "SEC" "1"
					( Origin gFrontEnd )
				)
				( attribute "SEC_TYPE" "SM"
					( Origin gFrontEnd )
				)
				( attribute "VER" "1"
					( Origin gFrontEnd )
				)
				( attribute "XY" "(-3150,2800)"
					( Origin gFrontEnd )
				)
				( attribute "CHIPS_PART_NAME" "SCONN120_H61426002"
					( Origin gPackager )
				)
				( attribute "CDS_PART_NAME" "SCONN120_H61426002_SM-CONN,H61A"
					( Origin gPackager )
				)
				( objectStatus "J4E1" )
				( pin "ioa1"
					( attribute "PN" "A1"
						( Origin gPackager )
					)
					( objectStatus "J4E1.A1" )
				)
				( pin "ioa2"
					( attribute "PN" "A2"
						( Origin gPackager )
					)
					( objectStatus "J4E1.A2" )
				)
				( pin "ioa3"
					( attribute "PN" "A3"
						( Origin gPackager )
					)
					( objectStatus "J4E1.A3" )
				)
				( pin "ioa4"
					( attribute "PN" "A4"
						( Origin gPackager )
					)
					( objectStatus "J4E1.A4" )
				)
				( pin "ioa5"
					( attribute "PN" "A5"
						( Origin gPackager )
					)
					( objectStatus "J4E1.A5" )
				)
				( pin "ioa6"
					( attribute "PN" "A6"
						( Origin gPackager )
					)
					( objectStatus "J4E1.A6" )
				)
				( pin "ioa7"
					( attribute "PN" "A7"
						( Origin gPackager )
					)
					( objectStatus "J4E1.A7" )
				)
				( pin "ioa8"
					( attribute "PN" "A8"
						( Origin gPackager )
					)
					( objectStatus "J4E1.A8" )
				)
				( pin "ioa9"
					( attribute "PN" "A9"
						( Origin gPackager )
					)
					( objectStatus "J4E1.A9" )
				)
				( pin "ioa10"
					( attribute "PN" "A10"
						( Origin gPackager )
					)
					( objectStatus "J4E1.A10" )
				)
				( pin "ioa11"
					( attribute "PN" "A11"
						( Origin gPackager )
					)
					( objectStatus "J4E1.A11" )
				)
				( pin "ioa12"
					( attribute "PN" "A12"
						( Origin gPackager )
					)
					( objectStatus "J4E1.A12" )
				)
				( pin "ioa13"
					( attribute "PN" "A13"
						( Origin gPackager )
					)
					( objectStatus "J4E1.A13" )
				)
				( pin "ioa14"
					( attribute "PN" "A14"
						( Origin gPackager )
					)
					( objectStatus "J4E1.A14" )
				)
				( pin "ioa15"
					( attribute "PN" "A15"
						( Origin gPackager )
					)
					( objectStatus "J4E1.A15" )
				)
				( pin "ioa16"
					( attribute "PN" "A16"
						( Origin gPackager )
					)
					( objectStatus "J4E1.A16" )
				)
				( pin "ioa17"
					( attribute "PN" "A17"
						( Origin gPackager )
					)
					( objectStatus "J4E1.A17" )
				)
				( pin "ioa18"
					( attribute "PN" "A18"
						( Origin gPackager )
					)
					( objectStatus "J4E1.A18" )
				)
				( pin "ioa19"
					( attribute "PN" "A19"
						( Origin gPackager )
					)
					( objectStatus "J4E1.A19" )
				)
				( pin "ioa20"
					( attribute "PN" "A20"
						( Origin gPackager )
					)
					( objectStatus "J4E1.A20" )
				)
				( pin "iob1"
					( attribute "PN" "B1"
						( Origin gPackager )
					)
					( objectStatus "J4E1.B1" )
				)
				( pin "iob2"
					( attribute "PN" "B2"
						( Origin gPackager )
					)
					( objectStatus "J4E1.B2" )
				)
				( pin "iob3"
					( attribute "PN" "B3"
						( Origin gPackager )
					)
					( objectStatus "J4E1.B3" )
				)
				( pin "iob4"
					( attribute "PN" "B4"
						( Origin gPackager )
					)
					( objectStatus "J4E1.B4" )
				)
				( pin "iob5"
					( attribute "PN" "B5"
						( Origin gPackager )
					)
					( objectStatus "J4E1.B5" )
				)
				( pin "iob6"
					( attribute "PN" "B6"
						( Origin gPackager )
					)
					( objectStatus "J4E1.B6" )
				)
				( pin "iob7"
					( attribute "PN" "B7"
						( Origin gPackager )
					)
					( objectStatus "J4E1.B7" )
				)
				( pin "iob8"
					( attribute "PN" "B8"
						( Origin gPackager )
					)
					( objectStatus "J4E1.B8" )
				)
				( pin "iob9"
					( attribute "PN" "B9"
						( Origin gPackager )
					)
					( objectStatus "J4E1.B9" )
				)
				( pin "iob10"
					( attribute "PN" "B10"
						( Origin gPackager )
					)
					( objectStatus "J4E1.B10" )
				)
				( pin "iob11"
					( attribute "PN" "B11"
						( Origin gPackager )
					)
					( objectStatus "J4E1.B11" )
				)
				( pin "iob12"
					( attribute "PN" "B12"
						( Origin gPackager )
					)
					( objectStatus "J4E1.B12" )
				)
				( pin "iob13"
					( attribute "PN" "B13"
						( Origin gPackager )
					)
					( objectStatus "J4E1.B13" )
				)
				( pin "iob14"
					( attribute "PN" "B14"
						( Origin gPackager )
					)
					( objectStatus "J4E1.B14" )
				)
				( pin "iob15"
					( attribute "PN" "B15"
						( Origin gPackager )
					)
					( objectStatus "J4E1.B15" )
				)
				( pin "iob16"
					( attribute "PN" "B16"
						( Origin gPackager )
					)
					( objectStatus "J4E1.B16" )
				)
				( pin "iob17"
					( attribute "PN" "B17"
						( Origin gPackager )
					)
					( objectStatus "J4E1.B17" )
				)
				( pin "iob18"
					( attribute "PN" "B18"
						( Origin gPackager )
					)
					( objectStatus "J4E1.B18" )
				)
				( pin "iob19"
					( attribute "PN" "B19"
						( Origin gPackager )
					)
					( objectStatus "J4E1.B19" )
				)
				( pin "iob20"
					( attribute "PN" "B20"
						( Origin gPackager )
					)
					( objectStatus "J4E1.B20" )
				)
				( pin "ioc1"
					( attribute "PN" "C1"
						( Origin gPackager )
					)
					( objectStatus "J4E1.C1" )
				)
				( pin "ioc2"
					( attribute "PN" "C2"
						( Origin gPackager )
					)
					( objectStatus "J4E1.C2" )
				)
				( pin "ioc3"
					( attribute "PN" "C3"
						( Origin gPackager )
					)
					( objectStatus "J4E1.C3" )
				)
				( pin "ioc4"
					( attribute "PN" "C4"
						( Origin gPackager )
					)
					( objectStatus "J4E1.C4" )
				)
				( pin "ioc5"
					( attribute "PN" "C5"
						( Origin gPackager )
					)
					( objectStatus "J4E1.C5" )
				)
				( pin "ioc6"
					( attribute "PN" "C6"
						( Origin gPackager )
					)
					( objectStatus "J4E1.C6" )
				)
				( pin "ioc7"
					( attribute "PN" "C7"
						( Origin gPackager )
					)
					( objectStatus "J4E1.C7" )
				)
				( pin "ioc8"
					( attribute "PN" "C8"
						( Origin gPackager )
					)
					( objectStatus "J4E1.C8" )
				)
				( pin "ioc9"
					( attribute "PN" "C9"
						( Origin gPackager )
					)
					( objectStatus "J4E1.C9" )
				)
				( pin "ioc10"
					( attribute "PN" "C10"
						( Origin gPackager )
					)
					( objectStatus "J4E1.C10" )
				)
				( pin "ioc11"
					( attribute "PN" "C11"
						( Origin gPackager )
					)
					( objectStatus "J4E1.C11" )
				)
				( pin "ioc12"
					( attribute "PN" "C12"
						( Origin gPackager )
					)
					( objectStatus "J4E1.C12" )
				)
				( pin "ioc13"
					( attribute "PN" "C13"
						( Origin gPackager )
					)
					( objectStatus "J4E1.C13" )
				)
				( pin "ioc14"
					( attribute "PN" "C14"
						( Origin gPackager )
					)
					( objectStatus "J4E1.C14" )
				)
				( pin "ioc15"
					( attribute "PN" "C15"
						( Origin gPackager )
					)
					( objectStatus "J4E1.C15" )
				)
				( pin "ioc16"
					( attribute "PN" "C16"
						( Origin gPackager )
					)
					( objectStatus "J4E1.C16" )
				)
				( pin "ioc17"
					( attribute "PN" "C17"
						( Origin gPackager )
					)
					( objectStatus "J4E1.C17" )
				)
				( pin "ioc18"
					( attribute "PN" "C18"
						( Origin gPackager )
					)
					( objectStatus "J4E1.C18" )
				)
				( pin "ioc19"
					( attribute "PN" "C19"
						( Origin gPackager )
					)
					( objectStatus "J4E1.C19" )
				)
				( pin "ioc20"
					( attribute "PN" "C20"
						( Origin gPackager )
					)
					( objectStatus "J4E1.C20" )
				)
				( pin "iod1"
					( attribute "PN" "D1"
						( Origin gPackager )
					)
					( objectStatus "J4E1.D1" )
				)
				( pin "iod2"
					( attribute "PN" "D2"
						( Origin gPackager )
					)
					( objectStatus "J4E1.D2" )
				)
				( pin "iod3"
					( attribute "PN" "D3"
						( Origin gPackager )
					)
					( objectStatus "J4E1.D3" )
				)
				( pin "iod4"
					( attribute "PN" "D4"
						( Origin gPackager )
					)
					( objectStatus "J4E1.D4" )
				)
				( pin "iod5"
					( attribute "PN" "D5"
						( Origin gPackager )
					)
					( objectStatus "J4E1.D5" )
				)
				( pin "iod6"
					( attribute "PN" "D6"
						( Origin gPackager )
					)
					( objectStatus "J4E1.D6" )
				)
				( pin "iod7"
					( attribute "PN" "D7"
						( Origin gPackager )
					)
					( objectStatus "J4E1.D7" )
				)
				( pin "iod8"
					( attribute "PN" "D8"
						( Origin gPackager )
					)
					( objectStatus "J4E1.D8" )
				)
				( pin "iod9"
					( attribute "PN" "D9"
						( Origin gPackager )
					)
					( objectStatus "J4E1.D9" )
				)
				( pin "iod10"
					( attribute "PN" "D10"
						( Origin gPackager )
					)
					( objectStatus "J4E1.D10" )
				)
				( pin "iod11"
					( attribute "PN" "D11"
						( Origin gPackager )
					)
					( objectStatus "J4E1.D11" )
				)
				( pin "iod12"
					( attribute "PN" "D12"
						( Origin gPackager )
					)
					( objectStatus "J4E1.D12" )
				)
				( pin "iod13"
					( attribute "PN" "D13"
						( Origin gPackager )
					)
					( objectStatus "J4E1.D13" )
				)
				( pin "iod14"
					( attribute "PN" "D14"
						( Origin gPackager )
					)
					( objectStatus "J4E1.D14" )
				)
				( pin "iod15"
					( attribute "PN" "D15"
						( Origin gPackager )
					)
					( objectStatus "J4E1.D15" )
				)
				( pin "iod16"
					( attribute "PN" "D16"
						( Origin gPackager )
					)
					( objectStatus "J4E1.D16" )
				)
				( pin "iod17"
					( attribute "PN" "D17"
						( Origin gPackager )
					)
					( objectStatus "J4E1.D17" )
				)
				( pin "iod18"
					( attribute "PN" "D18"
						( Origin gPackager )
					)
					( objectStatus "J4E1.D18" )
				)
				( pin "iod19"
					( attribute "PN" "D19"
						( Origin gPackager )
					)
					( objectStatus "J4E1.D19" )
				)
				( pin "iod20"
					( attribute "PN" "D20"
						( Origin gPackager )
					)
					( objectStatus "J4E1.D20" )
				)
				( pin "ioe1"
					( attribute "PN" "E1"
						( Origin gPackager )
					)
					( objectStatus "J4E1.E1" )
				)
				( pin "ioe2"
					( attribute "PN" "E2"
						( Origin gPackager )
					)
					( objectStatus "J4E1.E2" )
				)
				( pin "ioe3"
					( attribute "PN" "E3"
						( Origin gPackager )
					)
					( objectStatus "J4E1.E3" )
				)
				( pin "ioe4"
					( attribute "PN" "E4"
						( Origin gPackager )
					)
					( objectStatus "J4E1.E4" )
				)
				( pin "ioe5"
					( attribute "PN" "E5"
						( Origin gPackager )
					)
					( objectStatus "J4E1.E5" )
				)
				( pin "ioe6"
					( attribute "PN" "E6"
						( Origin gPackager )
					)
					( objectStatus "J4E1.E6" )
				)
				( pin "ioe7"
					( attribute "PN" "E7"
						( Origin gPackager )
					)
					( objectStatus "J4E1.E7" )
				)
				( pin "ioe8"
					( attribute "PN" "E8"
						( Origin gPackager )
					)
					( objectStatus "J4E1.E8" )
				)
				( pin "ioe9"
					( attribute "PN" "E9"
						( Origin gPackager )
					)
					( objectStatus "J4E1.E9" )
				)
				( pin "ioe10"
					( attribute "PN" "E10"
						( Origin gPackager )
					)
					( objectStatus "J4E1.E10" )
				)
				( pin "ioe11"
					( attribute "PN" "E11"
						( Origin gPackager )
					)
					( objectStatus "J4E1.E11" )
				)
				( pin "ioe12"
					( attribute "PN" "E12"
						( Origin gPackager )
					)
					( objectStatus "J4E1.E12" )
				)
				( pin "ioe13"
					( attribute "PN" "E13"
						( Origin gPackager )
					)
					( objectStatus "J4E1.E13" )
				)
				( pin "ioe14"
					( attribute "PN" "E14"
						( Origin gPackager )
					)
					( objectStatus "J4E1.E14" )
				)
				( pin "ioe15"
					( attribute "PN" "E15"
						( Origin gPackager )
					)
					( objectStatus "J4E1.E15" )
				)
				( pin "ioe16"
					( attribute "PN" "E16"
						( Origin gPackager )
					)
					( objectStatus "J4E1.E16" )
				)
				( pin "ioe17"
					( attribute "PN" "E17"
						( Origin gPackager )
					)
					( objectStatus "J4E1.E17" )
				)
				( pin "ioe18"
					( attribute "PN" "E18"
						( Origin gPackager )
					)
					( objectStatus "J4E1.E18" )
				)
				( pin "ioe19"
					( attribute "PN" "E19"
						( Origin gPackager )
					)
					( objectStatus "J4E1.E19" )
				)
				( pin "ioe20"
					( attribute "PN" "E20"
						( Origin gPackager )
					)
					( objectStatus "J4E1.E20" )
				)
				( pin "iof1"
					( attribute "PN" "F1"
						( Origin gPackager )
					)
					( objectStatus "J4E1.F1" )
				)
				( pin "iof2"
					( attribute "PN" "F2"
						( Origin gPackager )
					)
					( objectStatus "J4E1.F2" )
				)
				( pin "iof3"
					( attribute "PN" "F3"
						( Origin gPackager )
					)
					( objectStatus "J4E1.F3" )
				)
				( pin "iof4"
					( attribute "PN" "F4"
						( Origin gPackager )
					)
					( objectStatus "J4E1.F4" )
				)
				( pin "iof5"
					( attribute "PN" "F5"
						( Origin gPackager )
					)
					( objectStatus "J4E1.F5" )
				)
				( pin "iof6"
					( attribute "PN" "F6"
						( Origin gPackager )
					)
					( objectStatus "J4E1.F6" )
				)
				( pin "iof7"
					( attribute "PN" "F7"
						( Origin gPackager )
					)
					( objectStatus "J4E1.F7" )
				)
				( pin "iof8"
					( attribute "PN" "F8"
						( Origin gPackager )
					)
					( objectStatus "J4E1.F8" )
				)
				( pin "iof9"
					( attribute "PN" "F9"
						( Origin gPackager )
					)
					( objectStatus "J4E1.F9" )
				)
				( pin "iof10"
					( attribute "PN" "F10"
						( Origin gPackager )
					)
					( objectStatus "J4E1.F10" )
				)
				( pin "iof11"
					( attribute "PN" "F11"
						( Origin gPackager )
					)
					( objectStatus "J4E1.F11" )
				)
				( pin "iof12"
					( attribute "PN" "F12"
						( Origin gPackager )
					)
					( objectStatus "J4E1.F12" )
				)
				( pin "iof13"
					( attribute "PN" "F13"
						( Origin gPackager )
					)
					( objectStatus "J4E1.F13" )
				)
				( pin "iof14"
					( attribute "PN" "F14"
						( Origin gPackager )
					)
					( objectStatus "J4E1.F14" )
				)
				( pin "iof15"
					( attribute "PN" "F15"
						( Origin gPackager )
					)
					( objectStatus "J4E1.F15" )
				)
				( pin "iof16"
					( attribute "PN" "F16"
						( Origin gPackager )
					)
					( objectStatus "J4E1.F16" )
				)
				( pin "iof17"
					( attribute "PN" "F17"
						( Origin gPackager )
					)
					( objectStatus "J4E1.F17" )
				)
				( pin "iof18"
					( attribute "PN" "F18"
						( Origin gPackager )
					)
					( objectStatus "J4E1.F18" )
				)
				( pin "iof19"
					( attribute "PN" "F19"
						( Origin gPackager )
					)
					( objectStatus "J4E1.F19" )
				)
				( pin "iof20"
					( attribute "PN" "F20"
						( Origin gPackager )
					)
					( objectStatus "J4E1.F20" )
				)
			)
			( gate "@baseboard_fab2_lib.baseboard_fab2(sch_1):page193_i46"
				( attribute "CDS_LIB" "mstr_sconn"
					( Origin gPackager )
				)
				( attribute "CDS_LOCATION" "J4B2"
					( Origin gPackager )
				)
				( attribute "CDS_SEC" "1"
					( Origin gPackager )
				)
				( attribute "LOCATION" "J4B2"
					( Origin gFrontEnd )
				)
				( attribute "MATERIAL" "CONN"
					( Origin gFrontEnd )
				)
				( attribute "PACK_TYPE" "SM"
					( Origin gFrontEnd )
				)
				( attribute "PART_NUMBER" "H61426-002"
					( Origin gFrontEnd )
				)
				( attribute "PHYS_PAGE" "193"
					( Origin gFrontEnd )
				)
				( attribute "ROOM" "MCP VRM CPU1"
					( Origin gFrontEnd )
				)
				( attribute "ROT" "0"
					( Origin gFrontEnd )
				)
				( attribute "SEC" "1"
					( Origin gFrontEnd )
				)
				( attribute "SEC_TYPE" "SM"
					( Origin gFrontEnd )
				)
				( attribute "VER" "1"
					( Origin gFrontEnd )
				)
				( attribute "XY" "(-6325,2725)"
					( Origin gFrontEnd )
				)
				( attribute "CHIPS_PART_NAME" "SCONN120_H61426002"
					( Origin gPackager )
				)
				( attribute "CDS_PART_NAME" "SCONN120_H61426002_SM-CONN,H61A"
					( Origin gPackager )
				)
				( objectStatus "J4B2" )
				( pin "ioa1"
					( attribute "PN" "A1"
						( Origin gPackager )
					)
					( objectStatus "J4B2.A1" )
				)
				( pin "ioa2"
					( attribute "PN" "A2"
						( Origin gPackager )
					)
					( objectStatus "J4B2.A2" )
				)
				( pin "ioa3"
					( attribute "PN" "A3"
						( Origin gPackager )
					)
					( objectStatus "J4B2.A3" )
				)
				( pin "ioa4"
					( attribute "PN" "A4"
						( Origin gPackager )
					)
					( objectStatus "J4B2.A4" )
				)
				( pin "ioa5"
					( attribute "PN" "A5"
						( Origin gPackager )
					)
					( objectStatus "J4B2.A5" )
				)
				( pin "ioa6"
					( attribute "PN" "A6"
						( Origin gPackager )
					)
					( objectStatus "J4B2.A6" )
				)
				( pin "ioa7"
					( attribute "PN" "A7"
						( Origin gPackager )
					)
					( objectStatus "J4B2.A7" )
				)
				( pin "ioa8"
					( attribute "PN" "A8"
						( Origin gPackager )
					)
					( objectStatus "J4B2.A8" )
				)
				( pin "ioa9"
					( attribute "PN" "A9"
						( Origin gPackager )
					)
					( objectStatus "J4B2.A9" )
				)
				( pin "ioa10"
					( attribute "PN" "A10"
						( Origin gPackager )
					)
					( objectStatus "J4B2.A10" )
				)
				( pin "ioa11"
					( attribute "PN" "A11"
						( Origin gPackager )
					)
					( objectStatus "J4B2.A11" )
				)
				( pin "ioa12"
					( attribute "PN" "A12"
						( Origin gPackager )
					)
					( objectStatus "J4B2.A12" )
				)
				( pin "ioa13"
					( attribute "PN" "A13"
						( Origin gPackager )
					)
					( objectStatus "J4B2.A13" )
				)
				( pin "ioa14"
					( attribute "PN" "A14"
						( Origin gPackager )
					)
					( objectStatus "J4B2.A14" )
				)
				( pin "ioa15"
					( attribute "PN" "A15"
						( Origin gPackager )
					)
					( objectStatus "J4B2.A15" )
				)
				( pin "ioa16"
					( attribute "PN" "A16"
						( Origin gPackager )
					)
					( objectStatus "J4B2.A16" )
				)
				( pin "ioa17"
					( attribute "PN" "A17"
						( Origin gPackager )
					)
					( objectStatus "J4B2.A17" )
				)
				( pin "ioa18"
					( attribute "PN" "A18"
						( Origin gPackager )
					)
					( objectStatus "J4B2.A18" )
				)
				( pin "ioa19"
					( attribute "PN" "A19"
						( Origin gPackager )
					)
					( objectStatus "J4B2.A19" )
				)
				( pin "ioa20"
					( attribute "PN" "A20"
						( Origin gPackager )
					)
					( objectStatus "J4B2.A20" )
				)
				( pin "iob1"
					( attribute "PN" "B1"
						( Origin gPackager )
					)
					( objectStatus "J4B2.B1" )
				)
				( pin "iob2"
					( attribute "PN" "B2"
						( Origin gPackager )
					)
					( objectStatus "J4B2.B2" )
				)
				( pin "iob3"
					( attribute "PN" "B3"
						( Origin gPackager )
					)
					( objectStatus "J4B2.B3" )
				)
				( pin "iob4"
					( attribute "PN" "B4"
						( Origin gPackager )
					)
					( objectStatus "J4B2.B4" )
				)
				( pin "iob5"
					( attribute "PN" "B5"
						( Origin gPackager )
					)
					( objectStatus "J4B2.B5" )
				)
				( pin "iob6"
					( attribute "PN" "B6"
						( Origin gPackager )
					)
					( objectStatus "J4B2.B6" )
				)
				( pin "iob7"
					( attribute "PN" "B7"
						( Origin gPackager )
					)
					( objectStatus "J4B2.B7" )
				)
				( pin "iob8"
					( attribute "PN" "B8"
						( Origin gPackager )
					)
					( objectStatus "J4B2.B8" )
				)
				( pin "iob9"
					( attribute "PN" "B9"
						( Origin gPackager )
					)
					( objectStatus "J4B2.B9" )
				)
				( pin "iob10"
					( attribute "PN" "B10"
						( Origin gPackager )
					)
					( objectStatus "J4B2.B10" )
				)
				( pin "iob11"
					( attribute "PN" "B11"
						( Origin gPackager )
					)
					( objectStatus "J4B2.B11" )
				)
				( pin "iob12"
					( attribute "PN" "B12"
						( Origin gPackager )
					)
					( objectStatus "J4B2.B12" )
				)
				( pin "iob13"
					( attribute "PN" "B13"
						( Origin gPackager )
					)
					( objectStatus "J4B2.B13" )
				)
				( pin "iob14"
					( attribute "PN" "B14"
						( Origin gPackager )
					)
					( objectStatus "J4B2.B14" )
				)
				( pin "iob15"
					( attribute "PN" "B15"
						( Origin gPackager )
					)
					( objectStatus "J4B2.B15" )
				)
				( pin "iob16"
					( attribute "PN" "B16"
						( Origin gPackager )
					)
					( objectStatus "J4B2.B16" )
				)
				( pin "iob17"
					( attribute "PN" "B17"
						( Origin gPackager )
					)
					( objectStatus "J4B2.B17" )
				)
				( pin "iob18"
					( attribute "PN" "B18"
						( Origin gPackager )
					)
					( objectStatus "J4B2.B18" )
				)
				( pin "iob19"
					( attribute "PN" "B19"
						( Origin gPackager )
					)
					( objectStatus "J4B2.B19" )
				)
				( pin "iob20"
					( attribute "PN" "B20"
						( Origin gPackager )
					)
					( objectStatus "J4B2.B20" )
				)
				( pin "ioc1"
					( attribute "PN" "C1"
						( Origin gPackager )
					)
					( objectStatus "J4B2.C1" )
				)
				( pin "ioc2"
					( attribute "PN" "C2"
						( Origin gPackager )
					)
					( objectStatus "J4B2.C2" )
				)
				( pin "ioc3"
					( attribute "PN" "C3"
						( Origin gPackager )
					)
					( objectStatus "J4B2.C3" )
				)
				( pin "ioc4"
					( attribute "PN" "C4"
						( Origin gPackager )
					)
					( objectStatus "J4B2.C4" )
				)
				( pin "ioc5"
					( attribute "PN" "C5"
						( Origin gPackager )
					)
					( objectStatus "J4B2.C5" )
				)
				( pin "ioc6"
					( attribute "PN" "C6"
						( Origin gPackager )
					)
					( objectStatus "J4B2.C6" )
				)
				( pin "ioc7"
					( attribute "PN" "C7"
						( Origin gPackager )
					)
					( objectStatus "J4B2.C7" )
				)
				( pin "ioc8"
					( attribute "PN" "C8"
						( Origin gPackager )
					)
					( objectStatus "J4B2.C8" )
				)
				( pin "ioc9"
					( attribute "PN" "C9"
						( Origin gPackager )
					)
					( objectStatus "J4B2.C9" )
				)
				( pin "ioc10"
					( attribute "PN" "C10"
						( Origin gPackager )
					)
					( objectStatus "J4B2.C10" )
				)
				( pin "ioc11"
					( attribute "PN" "C11"
						( Origin gPackager )
					)
					( objectStatus "J4B2.C11" )
				)
				( pin "ioc12"
					( attribute "PN" "C12"
						( Origin gPackager )
					)
					( objectStatus "J4B2.C12" )
				)
				( pin "ioc13"
					( attribute "PN" "C13"
						( Origin gPackager )
					)
					( objectStatus "J4B2.C13" )
				)
				( pin "ioc14"
					( attribute "PN" "C14"
						( Origin gPackager )
					)
					( objectStatus "J4B2.C14" )
				)
				( pin "ioc15"
					( attribute "PN" "C15"
						( Origin gPackager )
					)
					( objectStatus "J4B2.C15" )
				)
				( pin "ioc16"
					( attribute "PN" "C16"
						( Origin gPackager )
					)
					( objectStatus "J4B2.C16" )
				)
				( pin "ioc17"
					( attribute "PN" "C17"
						( Origin gPackager )
					)
					( objectStatus "J4B2.C17" )
				)
				( pin "ioc18"
					( attribute "PN" "C18"
						( Origin gPackager )
					)
					( objectStatus "J4B2.C18" )
				)
				( pin "ioc19"
					( attribute "PN" "C19"
						( Origin gPackager )
					)
					( objectStatus "J4B2.C19" )
				)
				( pin "ioc20"
					( attribute "PN" "C20"
						( Origin gPackager )
					)
					( objectStatus "J4B2.C20" )
				)
				( pin "iod1"
					( attribute "PN" "D1"
						( Origin gPackager )
					)
					( objectStatus "J4B2.D1" )
				)
				( pin "iod2"
					( attribute "PN" "D2"
						( Origin gPackager )
					)
					( objectStatus "J4B2.D2" )
				)
				( pin "iod3"
					( attribute "PN" "D3"
						( Origin gPackager )
					)
					( objectStatus "J4B2.D3" )
				)
				( pin "iod4"
					( attribute "PN" "D4"
						( Origin gPackager )
					)
					( objectStatus "J4B2.D4" )
				)
				( pin "iod5"
					( attribute "PN" "D5"
						( Origin gPackager )
					)
					( objectStatus "J4B2.D5" )
				)
				( pin "iod6"
					( attribute "PN" "D6"
						( Origin gPackager )
					)
					( objectStatus "J4B2.D6" )
				)
				( pin "iod7"
					( attribute "PN" "D7"
						( Origin gPackager )
					)
					( objectStatus "J4B2.D7" )
				)
				( pin "iod8"
					( attribute "PN" "D8"
						( Origin gPackager )
					)
					( objectStatus "J4B2.D8" )
				)
				( pin "iod9"
					( attribute "PN" "D9"
						( Origin gPackager )
					)
					( objectStatus "J4B2.D9" )
				)
				( pin "iod10"
					( attribute "PN" "D10"
						( Origin gPackager )
					)
					( objectStatus "J4B2.D10" )
				)
				( pin "iod11"
					( attribute "PN" "D11"
						( Origin gPackager )
					)
					( objectStatus "J4B2.D11" )
				)
				( pin "iod12"
					( attribute "PN" "D12"
						( Origin gPackager )
					)
					( objectStatus "J4B2.D12" )
				)
				( pin "iod13"
					( attribute "PN" "D13"
						( Origin gPackager )
					)
					( objectStatus "J4B2.D13" )
				)
				( pin "iod14"
					( attribute "PN" "D14"
						( Origin gPackager )
					)
					( objectStatus "J4B2.D14" )
				)
				( pin "iod15"
					( attribute "PN" "D15"
						( Origin gPackager )
					)
					( objectStatus "J4B2.D15" )
				)
				( pin "iod16"
					( attribute "PN" "D16"
						( Origin gPackager )
					)
					( objectStatus "J4B2.D16" )
				)
				( pin "iod17"
					( attribute "PN" "D17"
						( Origin gPackager )
					)
					( objectStatus "J4B2.D17" )
				)
				( pin "iod18"
					( attribute "PN" "D18"
						( Origin gPackager )
					)
					( objectStatus "J4B2.D18" )
				)
				( pin "iod19"
					( attribute "PN" "D19"
						( Origin gPackager )
					)
					( objectStatus "J4B2.D19" )
				)
				( pin "iod20"
					( attribute "PN" "D20"
						( Origin gPackager )
					)
					( objectStatus "J4B2.D20" )
				)
				( pin "ioe1"
					( attribute "PN" "E1"
						( Origin gPackager )
					)
					( objectStatus "J4B2.E1" )
				)
				( pin "ioe2"
					( attribute "PN" "E2"
						( Origin gPackager )
					)
					( objectStatus "J4B2.E2" )
				)
				( pin "ioe3"
					( attribute "PN" "E3"
						( Origin gPackager )
					)
					( objectStatus "J4B2.E3" )
				)
				( pin "ioe4"
					( attribute "PN" "E4"
						( Origin gPackager )
					)
					( objectStatus "J4B2.E4" )
				)
				( pin "ioe5"
					( attribute "PN" "E5"
						( Origin gPackager )
					)
					( objectStatus "J4B2.E5" )
				)
				( pin "ioe6"
					( attribute "PN" "E6"
						( Origin gPackager )
					)
					( objectStatus "J4B2.E6" )
				)
				( pin "ioe7"
					( attribute "PN" "E7"
						( Origin gPackager )
					)
					( objectStatus "J4B2.E7" )
				)
				( pin "ioe8"
					( attribute "PN" "E8"
						( Origin gPackager )
					)
					( objectStatus "J4B2.E8" )
				)
				( pin "ioe9"
					( attribute "PN" "E9"
						( Origin gPackager )
					)
					( objectStatus "J4B2.E9" )
				)
				( pin "ioe10"
					( attribute "PN" "E10"
						( Origin gPackager )
					)
					( objectStatus "J4B2.E10" )
				)
				( pin "ioe11"
					( attribute "PN" "E11"
						( Origin gPackager )
					)
					( objectStatus "J4B2.E11" )
				)
				( pin "ioe12"
					( attribute "PN" "E12"
						( Origin gPackager )
					)
					( objectStatus "J4B2.E12" )
				)
				( pin "ioe13"
					( attribute "PN" "E13"
						( Origin gPackager )
					)
					( objectStatus "J4B2.E13" )
				)
				( pin "ioe14"
					( attribute "PN" "E14"
						( Origin gPackager )
					)
					( objectStatus "J4B2.E14" )
				)
				( pin "ioe15"
					( attribute "PN" "E15"
						( Origin gPackager )
					)
					( objectStatus "J4B2.E15" )
				)
				( pin "ioe16"
					( attribute "PN" "E16"
						( Origin gPackager )
					)
					( objectStatus "J4B2.E16" )
				)
				( pin "ioe17"
					( attribute "PN" "E17"
						( Origin gPackager )
					)
					( objectStatus "J4B2.E17" )
				)
				( pin "ioe18"
					( attribute "PN" "E18"
						( Origin gPackager )
					)
					( objectStatus "J4B2.E18" )
				)
				( pin "ioe19"
					( attribute "PN" "E19"
						( Origin gPackager )
					)
					( objectStatus "J4B2.E19" )
				)
				( pin "ioe20"
					( attribute "PN" "E20"
						( Origin gPackager )
					)
					( objectStatus "J4B2.E20" )
				)
				( pin "iof1"
					( attribute "PN" "F1"
						( Origin gPackager )
					)
					( objectStatus "J4B2.F1" )
				)
				( pin "iof2"
					( attribute "PN" "F2"
						( Origin gPackager )
					)
					( objectStatus "J4B2.F2" )
				)
				( pin "iof3"
					( attribute "PN" "F3"
						( Origin gPackager )
					)
					( objectStatus "J4B2.F3" )
				)
				( pin "iof4"
					( attribute "PN" "F4"
						( Origin gPackager )
					)
					( objectStatus "J4B2.F4" )
				)
				( pin "iof5"
					( attribute "PN" "F5"
						( Origin gPackager )
					)
					( objectStatus "J4B2.F5" )
				)
				( pin "iof6"
					( attribute "PN" "F6"
						( Origin gPackager )
					)
					( objectStatus "J4B2.F6" )
				)
				( pin "iof7"
					( attribute "PN" "F7"
						( Origin gPackager )
					)
					( objectStatus "J4B2.F7" )
				)
				( pin "iof8"
					( attribute "PN" "F8"
						( Origin gPackager )
					)
					( objectStatus "J4B2.F8" )
				)
				( pin "iof9"
					( attribute "PN" "F9"
						( Origin gPackager )
					)
					( objectStatus "J4B2.F9" )
				)
				( pin "iof10"
					( attribute "PN" "F10"
						( Origin gPackager )
					)
					( objectStatus "J4B2.F10" )
				)
				( pin "iof11"
					( attribute "PN" "F11"
						( Origin gPackager )
					)
					( objectStatus "J4B2.F11" )
				)
				( pin "iof12"
					( attribute "PN" "F12"
						( Origin gPackager )
					)
					( objectStatus "J4B2.F12" )
				)
				( pin "iof13"
					( attribute "PN" "F13"
						( Origin gPackager )
					)
					( objectStatus "J4B2.F13" )
				)
				( pin "iof14"
					( attribute "PN" "F14"
						( Origin gPackager )
					)
					( objectStatus "J4B2.F14" )
				)
				( pin "iof15"
					( attribute "PN" "F15"
						( Origin gPackager )
					)
					( objectStatus "J4B2.F15" )
				)
				( pin "iof16"
					( attribute "PN" "F16"
						( Origin gPackager )
					)
					( objectStatus "J4B2.F16" )
				)
				( pin "iof17"
					( attribute "PN" "F17"
						( Origin gPackager )
					)
					( objectStatus "J4B2.F17" )
				)
				( pin "iof18"
					( attribute "PN" "F18"
						( Origin gPackager )
					)
					( objectStatus "J4B2.F18" )
				)
				( pin "iof19"
					( attribute "PN" "F19"
						( Origin gPackager )
					)
					( objectStatus "J4B2.F19" )
				)
				( pin "iof20"
					( attribute "PN" "F20"
						( Origin gPackager )
					)
					( objectStatus "J4B2.F20" )
				)
			)
			( gate "@baseboard_fab2_lib.baseboard_fab2(sch_1):page193_i61"
				( attribute "BOM_COST" "PVMCP_MCP_CPU1_VR"
					( Origin gFrontEnd )
				)
				( attribute "CDS_LIB" "mstr_discrete"
					( Origin gPackager )
				)
				( attribute "CDS_LOCATION" "C4E24"
					( Origin gPackager )
				)
				( attribute "CDS_SEC" "1"
					( Origin gPackager )
				)
				( attribute "LOCATION" "C4E24"
					( Origin gFrontEnd )
				)
				( attribute "MATERIAL" "ALUM"
					( Origin gFrontEnd )
				)
				( attribute "PACK_TYPE" "3018"
					( Origin gFrontEnd )
				)
				( attribute "PART_NUMBER" "699013-049"
					( Origin gFrontEnd )
				)
				( attribute "PHYS_PAGE" "193"
					( Origin gFrontEnd )
				)
				( attribute "ROOM" "PVMCP_MCP_CPU1_VR"
					( Origin gFrontEnd )
				)
				( attribute "ROT" "0"
					( Origin gFrontEnd )
				)
				( attribute "SEC" "1"
					( Origin gPackager )
				)
				( attribute "TOLERANCE" "20%"
					( Origin gFrontEnd )
				)
				( attribute "VALUE" "470UF"
					( Origin gFrontEnd )
				)
				( attribute "VER" "1"
					( Origin gFrontEnd )
				)
				( attribute "VOLTAGE" "2.5V"
					( Units "uVoltage" "V" 1.000000)
					( Origin gFrontEnd )
				)
				( attribute "XY" "(-1675,2975)"
					( Origin gFrontEnd )
				)
				( attribute "CHIPS_PART_NAME" "CAPP"
					( Origin gPackager )
				)
				( attribute "CDS_PART_NAME" "CAPP_3018-470UF,2.5V,20%,ALUM,A"
					( Origin gPackager )
				)
				( objectStatus "C4E24" )
				( pin "a"
					( attribute "PN" "1"
						( Origin gPackager )
					)
					( objectStatus "C4E24.1" )
				)
				( pin "b"
					( attribute "PN" "2"
						( Origin gPackager )
					)
					( objectStatus "C4E24.2" )
				)
			)
			( gate "@baseboard_fab2_lib.baseboard_fab2(sch_1):page193_i62"
				( attribute "BOM_COST" "PVMCP_MCP_CPU1_VR"
					( Origin gFrontEnd )
				)
				( attribute "CDS_LIB" "mstr_discrete"
					( Origin gPackager )
				)
				( attribute "CDS_LOCATION" "C6R16"
					( Origin gPackager )
				)
				( attribute "CDS_SEC" "1"
					( Origin gPackager )
				)
				( attribute "LOCATION" "C6R16"
					( Origin gFrontEnd )
				)
				( attribute "MATERIAL" "ALUM"
					( Origin gFrontEnd )
				)
				( attribute "PACK_TYPE" "3018"
					( Origin gFrontEnd )
				)
				( attribute "PART_NUMBER" "699013-049"
					( Origin gFrontEnd )
				)
				( attribute "PHYS_PAGE" "193"
					( Origin gFrontEnd )
				)
				( attribute "ROOM" "PVMCP_MCP_CPU1_VR"
					( Origin gFrontEnd )
				)
				( attribute "ROT" "0"
					( Origin gFrontEnd )
				)
				( attribute "SEC" "1"
					( Origin gFrontEnd )
				)
				( attribute "SEC_TYPE" "3018"
					( Origin gFrontEnd )
				)
				( attribute "TOLERANCE" "20%"
					( Origin gFrontEnd )
				)
				( attribute "VALUE" "470UF"
					( Origin gFrontEnd )
				)
				( attribute "VER" "1"
					( Origin gFrontEnd )
				)
				( attribute "VOLTAGE" "2.5V"
					( Units "uVoltage" "V" 1.000000)
					( Origin gFrontEnd )
				)
				( attribute "XY" "(-1400,2975)"
					( Origin gFrontEnd )
				)
				( attribute "CHIPS_PART_NAME" "CAPP"
					( Origin gPackager )
				)
				( attribute "CDS_PART_NAME" "CAPP_3018-470UF,2.5V,20%,ALUM,A"
					( Origin gPackager )
				)
				( objectStatus "C6R16" )
				( pin "a"
					( attribute "PN" "1"
						( Origin gPackager )
					)
					( objectStatus "C6R16.1" )
				)
				( pin "b"
					( attribute "PN" "2"
						( Origin gPackager )
					)
					( objectStatus "C6R16.2" )
				)
			)
			( gate "@baseboard_fab2_lib.baseboard_fab2(sch_1):page193_i68"
				( attribute "CDS_LIB" "dev_discrete"
					( Origin gPackager )
				)
				( attribute "CDS_LOCATION" "C4F1"
					( Origin gPackager )
				)
				( attribute "CDS_SEC" "1"
					( Origin gPackager )
				)
				( attribute "LOCATION" "C4F1"
					( Origin gFrontEnd )
				)
				( attribute "MATERIAL" "X6S"
					( Origin gFrontEnd )
				)
				( attribute "PACK_TYPE" "0402V"
					( Origin gFrontEnd )
				)
				( attribute "PART_NUMBER" "D97712-004"
					( Origin gFrontEnd )
				)
				( attribute "PHYS_PAGE" "193"
					( Origin gFrontEnd )
				)
				( attribute "ROOM" "P1V8_MCP_CPU1"
					( Origin gFrontEnd )
				)
				( attribute "ROT" "2"
					( Origin gFrontEnd )
				)
				( attribute "SEC" "1"
					( Origin gFrontEnd )
				)
				( attribute "SEC_TYPE" "0402V"
					( Origin gFrontEnd )
				)
				( attribute "TOLERANCE" "10%"
					( Origin gFrontEnd )
				)
				( attribute "VALUE" "1.0UF"
					( Origin gFrontEnd )
				)
				( attribute "VER" "1"
					( Origin gFrontEnd )
				)
				( attribute "VOLTAGE" "6.3V"
					( Units "uVoltage" "V" 1.000000)
					( Origin gFrontEnd )
				)
				( attribute "XY" "(-775,1850)"
					( Origin gFrontEnd )
				)
				( attribute "CHIPS_PART_NAME" "CAP_A"
					( Origin gPackager )
				)
				( attribute "CDS_PART_NAME" "CAP_A_0402V-1.0UF,6.3V,10%,X6SA"
					( Origin gPackager )
				)
				( objectStatus "C4F1" )
				( pin "a"
					( attribute "PN" "1"
						( Origin gPackager )
					)
					( objectStatus "C4F1.1" )
				)
				( pin "b"
					( attribute "PN" "2"
						( Origin gPackager )
					)
					( objectStatus "C4F1.2" )
				)
			)
			( gate "@baseboard_fab2_lib.baseboard_fab2(sch_1):page193_i70"
				( attribute "CDS_LIB" "dev_discrete"
					( Origin gPackager )
				)
				( attribute "CDS_LOCATION" "C4F3"
					( Origin gPackager )
				)
				( attribute "CDS_SEC" "1"
					( Origin gPackager )
				)
				( attribute "LOCATION" "C4F3"
					( Origin gFrontEnd )
				)
				( attribute "MATERIAL" "X6S"
					( Origin gFrontEnd )
				)
				( attribute "PACK_TYPE" "0402V"
					( Origin gFrontEnd )
				)
				( attribute "PART_NUMBER" "D97712-004"
					( Origin gFrontEnd )
				)
				( attribute "PHYS_PAGE" "193"
					( Origin gFrontEnd )
				)
				( attribute "ROOM" "P1V8_MCP_CPU1"
					( Origin gFrontEnd )
				)
				( attribute "ROT" "2"
					( Origin gFrontEnd )
				)
				( attribute "SEC" "1"
					( Origin gFrontEnd )
				)
				( attribute "SEC_TYPE" "0402V"
					( Origin gFrontEnd )
				)
				( attribute "TOLERANCE" "10%"
					( Origin gFrontEnd )
				)
				( attribute "VALUE" "1.0UF"
					( Origin gFrontEnd )
				)
				( attribute "VER" "1"
					( Origin gFrontEnd )
				)
				( attribute "VOLTAGE" "6.3V"
					( Units "uVoltage" "V" 1.000000)
					( Origin gFrontEnd )
				)
				( attribute "XY" "(-1225,1850)"
					( Origin gFrontEnd )
				)
				( attribute "CHIPS_PART_NAME" "CAP_A"
					( Origin gPackager )
				)
				( attribute "CDS_PART_NAME" "CAP_A_0402V-1.0UF,6.3V,10%,X6SA"
					( Origin gPackager )
				)
				( objectStatus "C4F3" )
				( pin "a"
					( attribute "PN" "1"
						( Origin gPackager )
					)
					( objectStatus "C4F3.1" )
				)
				( pin "b"
					( attribute "PN" "2"
						( Origin gPackager )
					)
					( objectStatus "C4F3.2" )
				)
			)
			( gate "@baseboard_fab2_lib.baseboard_fab2(sch_1):page193_i140"
				( attribute "CDS_LIB" "dev_discrete"
					( Origin gPackager )
				)
				( attribute "CDS_LOCATION" "C3F1"
					( Origin gPackager )
				)
				( attribute "CDS_SEC" "1"
					( Origin gPackager )
				)
				( attribute "LOCATION" "C3F1"
					( Origin gFrontEnd )
				)
				( attribute "MATERIAL" "X5R"
					( Origin gFrontEnd )
				)
				( attribute "PACK_TYPE" "0603V"
					( Origin gFrontEnd )
				)
				( attribute "PART_NUMBER" "602433-106"
					( Origin gFrontEnd )
				)
				( attribute "PHYS_PAGE" "193"
					( Origin gFrontEnd )
				)
				( attribute "ROT" "0"
					( Origin gFrontEnd )
				)
				( attribute "SEC" "1"
					( Origin gFrontEnd )
				)
				( attribute "SEC_TYPE" "0603V"
					( Origin gFrontEnd )
				)
				( attribute "TOLERANCE" "20%"
					( Origin gFrontEnd )
				)
				( attribute "VALUE" "47UF"
					( Origin gFrontEnd )
				)
				( attribute "VER" "1"
					( Origin gFrontEnd )
				)
				( attribute "VOLTAGE" "4V"
					( Units "uVoltage" "V" 1.000000)
					( Origin gFrontEnd )
				)
				( attribute "XY" "(-1950,1875)"
					( Origin gFrontEnd )
				)
				( attribute "CHIPS_PART_NAME" "CAP_A"
					( Origin gPackager )
				)
				( attribute "CDS_PART_NAME" "CAP_A_0603V-47UF,4V,20%,X5R,60A"
					( Origin gPackager )
				)
				( objectStatus "C3F1" )
				( pin "a"
					( attribute "PN" "1"
						( Origin gPackager )
					)
					( objectStatus "C3F1.1" )
				)
				( pin "b"
					( attribute "PN" "2"
						( Origin gPackager )
					)
					( objectStatus "C3F1.2" )
				)
			)
			( gate "@baseboard_fab2_lib.baseboard_fab2(sch_1):page193_i141"
				( attribute "CDS_LIB" "dev_discrete"
					( Origin gPackager )
				)
				( attribute "CDS_LOCATION" "C4F2"
					( Origin gPackager )
				)
				( attribute "CDS_SEC" "1"
					( Origin gPackager )
				)
				( attribute "LOCATION" "C4F2"
					( Origin gFrontEnd )
				)
				( attribute "MATERIAL" "X5R"
					( Origin gFrontEnd )
				)
				( attribute "PACK_TYPE" "0603V"
					( Origin gFrontEnd )
				)
				( attribute "PART_NUMBER" "602433-106"
					( Origin gFrontEnd )
				)
				( attribute "PHYS_PAGE" "193"
					( Origin gFrontEnd )
				)
				( attribute "ROT" "0"
					( Origin gFrontEnd )
				)
				( attribute "SEC" "1"
					( Origin gFrontEnd )
				)
				( attribute "SEC_TYPE" "0603V"
					( Origin gFrontEnd )
				)
				( attribute "TOLERANCE" "20%"
					( Origin gFrontEnd )
				)
				( attribute "VALUE" "47UF"
					( Origin gFrontEnd )
				)
				( attribute "VER" "1"
					( Origin gFrontEnd )
				)
				( attribute "VOLTAGE" "4V"
					( Units "uVoltage" "V" 1.000000)
					( Origin gFrontEnd )
				)
				( attribute "XY" "(-1700,1875)"
					( Origin gFrontEnd )
				)
				( attribute "CHIPS_PART_NAME" "CAP_A"
					( Origin gPackager )
				)
				( attribute "CDS_PART_NAME" "CAP_A_0603V-47UF,4V,20%,X5R,60A"
					( Origin gPackager )
				)
				( objectStatus "C4F2" )
				( pin "a"
					( attribute "PN" "1"
						( Origin gPackager )
					)
					( objectStatus "C4F2.1" )
				)
				( pin "b"
					( attribute "PN" "2"
						( Origin gPackager )
					)
					( objectStatus "C4F2.2" )
				)
			)
			( gate "@baseboard_fab2_lib.baseboard_fab2(sch_1):page193_i169"
				( attribute "CDS_LIB" "mstr_discrete"
					( Origin gPackager )
				)
				( attribute "CDS_LOCATION" "R4C12"
					( Origin gPackager )
				)
				( attribute "CDS_SEC" "1"
					( Origin gPackager )
				)
				( attribute "LOCATION" "R4C12"
					( Origin gFrontEnd )
				)
				( attribute "MATERIAL" "CHIP"
					( Origin gFrontEnd )
				)
				( attribute "PACK_TYPE" "0402"
					( Origin gFrontEnd )
				)
				( attribute "PART_NUMBER" "G21796-078"
					( Origin gFrontEnd )
				)
				( attribute "PHYS_PAGE" "193"
					( Origin gFrontEnd )
				)
				( attribute "ROOM" "PVCCIN_CPU0_VR"
					( Origin gFrontEnd )
				)
				( attribute "ROT" "0"
					( Origin gFrontEnd )
				)
				( attribute "SEC" "1"
					( Origin gFrontEnd )
				)
				( attribute "SEC_TYPE" "0402"
					( Origin gFrontEnd )
				)
				( attribute "TOLERANCE" "1%"
					( Origin gFrontEnd )
				)
				( attribute "VALUE" "8.06K"
					( Origin gFrontEnd )
				)
				( attribute "VER" "2"
					( Origin gFrontEnd )
				)
				( attribute "WATTAGE" "1/16W"
					( Origin gFrontEnd )
				)
				( attribute "XY" "(-7950,775)"
					( Origin gFrontEnd )
				)
				( attribute "CHIPS_PART_NAME" "RES"
					( Origin gPackager )
				)
				( attribute "CDS_PART_NAME" "RES_0402-8.06K,1%,1/16W,CHIP,GA"
					( Origin gPackager )
				)
				( objectStatus "R4C12" )
				( pin "a"
					( attribute "PN" "1"
						( Origin gPackager )
					)
					( objectStatus "R4C12.1" )
				)
				( pin "b"
					( attribute "PN" "2"
						( Origin gPackager )
					)
					( objectStatus "R4C12.2" )
				)
			)
			( gate "@baseboard_fab2_lib.baseboard_fab2(sch_1):page193_i170"
				( attribute "CDS_LIB" "mstr_discrete"
					( Origin gPackager )
				)
				( attribute "CDS_LOCATION" "R4C11"
					( Origin gPackager )
				)
				( attribute "CDS_SEC" "1"
					( Origin gPackager )
				)
				( attribute "LOCATION" "R4C11"
					( Origin gFrontEnd )
				)
				( attribute "MATERIAL" "CHIP"
					( Origin gFrontEnd )
				)
				( attribute "PACK_TYPE" "0402"
					( Origin gFrontEnd )
				)
				( attribute "PART_NUMBER" "G21796-043"
					( Origin gFrontEnd )
				)
				( attribute "PHYS_PAGE" "193"
					( Origin gFrontEnd )
				)
				( attribute "ROOM" "PVCCIN_CPU0_VR"
					( Origin gFrontEnd )
				)
				( attribute "ROT" "0"
					( Origin gFrontEnd )
				)
				( attribute "SEC" "1"
					( Origin gFrontEnd )
				)
				( attribute "SEC_TYPE" "0402"
					( Origin gFrontEnd )
				)
				( attribute "TOLERANCE" "1%"
					( Origin gFrontEnd )
				)
				( attribute "VALUE" "3.16K"
					( Origin gFrontEnd )
				)
				( attribute "VER" "2"
					( Origin gFrontEnd )
				)
				( attribute "WATTAGE" "1/16W"
					( Origin gFrontEnd )
				)
				( attribute "XY" "(-7600,750)"
					( Origin gFrontEnd )
				)
				( attribute "CHIPS_PART_NAME" "RES"
					( Origin gPackager )
				)
				( attribute "CDS_PART_NAME" "RES_0402-3.16K,1%,1/16W,CHIP,GA"
					( Origin gPackager )
				)
				( objectStatus "R4C11" )
				( pin "a"
					( attribute "PN" "1"
						( Origin gPackager )
					)
					( objectStatus "R4C11.1" )
				)
				( pin "b"
					( attribute "PN" "2"
						( Origin gPackager )
					)
					( objectStatus "R4C11.2" )
				)
			)
			( gate "@baseboard_fab2_lib.baseboard_fab2(sch_1):page194_i9"
				( attribute "CDS_LIB" "dev_discrete"
					( Origin gPackager )
				)
				( attribute "CDS_LOCATION" "C4T2"
					( Origin gPackager )
				)
				( attribute "CDS_SEC" "1"
					( Origin gPackager )
				)
				( attribute "LOCATION" "C4T2"
					( Origin gFrontEnd )
				)
				( attribute "MATERIAL" "X6S"
					( Origin gFrontEnd )
				)
				( attribute "PACK_TYPE" "0402V"
					( Origin gFrontEnd )
				)
				( attribute "PART_NUMBER" "D97712-004"
					( Origin gFrontEnd )
				)
				( attribute "PHYS_PAGE" "194"
					( Origin gFrontEnd )
				)
				( attribute "ROOM" "P1V8_MCP_CPU0"
					( Origin gFrontEnd )
				)
				( attribute "ROT" "2"
					( Origin gFrontEnd )
				)
				( attribute "SEC" "1"
					( Origin gFrontEnd )
				)
				( attribute "SEC_TYPE" "0402V"
					( Origin gFrontEnd )
				)
				( attribute "TOLERANCE" "10%"
					( Origin gFrontEnd )
				)
				( attribute "VALUE" "1.0UF"
					( Origin gFrontEnd )
				)
				( attribute "VER" "1"
					( Origin gFrontEnd )
				)
				( attribute "VOLTAGE" "6.3V"
					( Units "uVoltage" "V" 1.000000)
					( Origin gFrontEnd )
				)
				( attribute "XY" "(-475,1075)"
					( Origin gFrontEnd )
				)
				( attribute "CHIPS_PART_NAME" "CAP_A"
					( Origin gPackager )
				)
				( attribute "CDS_PART_NAME" "CAP_A_0402V-1.0UF,6.3V,10%,X6SA"
					( Origin gPackager )
				)
				( objectStatus "C4T2" )
				( pin "a"
					( attribute "PN" "1"
						( Origin gPackager )
					)
					( objectStatus "C4T2.1" )
				)
				( pin "b"
					( attribute "PN" "2"
						( Origin gPackager )
					)
					( objectStatus "C4T2.2" )
				)
			)
			( gate "@baseboard_fab2_lib.baseboard_fab2(sch_1):page194_i16"
				( attribute "CDS_LIB" "dev_discrete"
					( Origin gPackager )
				)
				( attribute "CDS_LOCATION" "C4T1"
					( Origin gPackager )
				)
				( attribute "CDS_SEC" "1"
					( Origin gPackager )
				)
				( attribute "LOCATION" "C4T1"
					( Origin gFrontEnd )
				)
				( attribute "MATERIAL" "X6S"
					( Origin gFrontEnd )
				)
				( attribute "PACK_TYPE" "0402V"
					( Origin gFrontEnd )
				)
				( attribute "PART_NUMBER" "D97712-004"
					( Origin gFrontEnd )
				)
				( attribute "PHYS_PAGE" "194"
					( Origin gFrontEnd )
				)
				( attribute "ROOM" "P1V8_MCP_CPU0"
					( Origin gFrontEnd )
				)
				( attribute "ROT" "2"
					( Origin gFrontEnd )
				)
				( attribute "SEC" "1"
					( Origin gFrontEnd )
				)
				( attribute "SEC_TYPE" "0402V"
					( Origin gFrontEnd )
				)
				( attribute "TOLERANCE" "10%"
					( Origin gFrontEnd )
				)
				( attribute "VALUE" "1.0UF"
					( Origin gFrontEnd )
				)
				( attribute "VER" "1"
					( Origin gFrontEnd )
				)
				( attribute "VOLTAGE" "6.3V"
					( Units "uVoltage" "V" 1.000000)
					( Origin gFrontEnd )
				)
				( attribute "XY" "(-900,1075)"
					( Origin gFrontEnd )
				)
				( attribute "CHIPS_PART_NAME" "CAP_A"
					( Origin gPackager )
				)
				( attribute "CDS_PART_NAME" "CAP_A_0402V-1.0UF,6.3V,10%,X6SA"
					( Origin gPackager )
				)
				( objectStatus "C4T1" )
				( pin "a"
					( attribute "PN" "1"
						( Origin gPackager )
					)
					( objectStatus "C4T1.1" )
				)
				( pin "b"
					( attribute "PN" "2"
						( Origin gPackager )
					)
					( objectStatus "C4T1.2" )
				)
			)
			( gate "@baseboard_fab2_lib.baseboard_fab2(sch_1):page194_i29"
				( attribute "BOM_COST" "PVMCP_MCP_CPU0_VR"
					( Origin gFrontEnd )
				)
				( attribute "CDS_LIB" "mstr_discrete"
					( Origin gPackager )
				)
				( attribute "CDS_LOCATION" "C4R1"
					( Origin gPackager )
				)
				( attribute "CDS_SEC" "1"
					( Origin gPackager )
				)
				( attribute "LOCATION" "C4R1"
					( Origin gFrontEnd )
				)
				( attribute "MATERIAL" "ALUM"
					( Origin gFrontEnd )
				)
				( attribute "PACK_TYPE" "3018"
					( Origin gFrontEnd )
				)
				( attribute "PART_NUMBER" "699013-049"
					( Origin gFrontEnd )
				)
				( attribute "PHYS_PAGE" "194"
					( Origin gFrontEnd )
				)
				( attribute "ROOM" "PVMCP_MCP_CPU0_VR"
					( Origin gFrontEnd )
				)
				( attribute "ROT" "0"
					( Origin gFrontEnd )
				)
				( attribute "SEC" "1"
					( Origin gFrontEnd )
				)
				( attribute "SEC_TYPE" "3018"
					( Origin gFrontEnd )
				)
				( attribute "TOLERANCE" "20%"
					( Origin gFrontEnd )
				)
				( attribute "VALUE" "470UF"
					( Origin gFrontEnd )
				)
				( attribute "VER" "1"
					( Origin gFrontEnd )
				)
				( attribute "VOLTAGE" "2.5V"
					( Units "uVoltage" "V" 1.000000)
					( Origin gFrontEnd )
				)
				( attribute "XY" "(-850,2275)"
					( Origin gFrontEnd )
				)
				( attribute "CHIPS_PART_NAME" "CAPP"
					( Origin gPackager )
				)
				( attribute "CDS_PART_NAME" "CAPP_3018-470UF,2.5V,20%,ALUM,A"
					( Origin gPackager )
				)
				( objectStatus "C4R1" )
				( pin "a"
					( attribute "PN" "1"
						( Origin gPackager )
					)
					( objectStatus "C4R1.1" )
				)
				( pin "b"
					( attribute "PN" "2"
						( Origin gPackager )
					)
					( objectStatus "C4R1.2" )
				)
			)
			( gate "@baseboard_fab2_lib.baseboard_fab2(sch_1):page194_i31"
				( attribute "BOM_COST" "PVMCP_MCP_CPU0_VR"
					( Origin gFrontEnd )
				)
				( attribute "CDS_LIB" "mstr_discrete"
					( Origin gPackager )
				)
				( attribute "CDS_LOCATION" "C3R4"
					( Origin gPackager )
				)
				( attribute "CDS_SEC" "1"
					( Origin gPackager )
				)
				( attribute "LOCATION" "C3R4"
					( Origin gFrontEnd )
				)
				( attribute "MATERIAL" "ALUM"
					( Origin gFrontEnd )
				)
				( attribute "PACK_TYPE" "3018"
					( Origin gFrontEnd )
				)
				( attribute "PART_NUMBER" "699013-049"
					( Origin gFrontEnd )
				)
				( attribute "PHYS_PAGE" "194"
					( Origin gFrontEnd )
				)
				( attribute "ROOM" "PVMCP_MCP_CPU0_VR"
					( Origin gFrontEnd )
				)
				( attribute "ROT" "0"
					( Origin gFrontEnd )
				)
				( attribute "SEC" "1"
					( Origin gPackager )
				)
				( attribute "TOLERANCE" "20%"
					( Origin gFrontEnd )
				)
				( attribute "VALUE" "470UF"
					( Origin gFrontEnd )
				)
				( attribute "VER" "1"
					( Origin gFrontEnd )
				)
				( attribute "VOLTAGE" "2.5V"
					( Units "uVoltage" "V" 1.000000)
					( Origin gFrontEnd )
				)
				( attribute "XY" "(-1275,2275)"
					( Origin gFrontEnd )
				)
				( attribute "CHIPS_PART_NAME" "CAPP"
					( Origin gPackager )
				)
				( attribute "CDS_PART_NAME" "CAPP_3018-470UF,2.5V,20%,ALUM,A"
					( Origin gPackager )
				)
				( objectStatus "C3R4" )
				( pin "a"
					( attribute "PN" "1"
						( Origin gPackager )
					)
					( objectStatus "C3R4.1" )
				)
				( pin "b"
					( attribute "PN" "2"
						( Origin gPackager )
					)
					( objectStatus "C3R4.2" )
				)
			)
			( gate "@baseboard_fab2_lib.baseboard_fab2(sch_1):page194_i55"
				( attribute "CDS_LIB" "mstr_sconn"
					( Origin gPackager )
				)
				( attribute "CDS_LOCATION" "J6E1"
					( Origin gPackager )
				)
				( attribute "CDS_SEC" "1"
					( Origin gPackager )
				)
				( attribute "LOCATION" "J6E1"
					( Origin gFrontEnd )
				)
				( attribute "MATERIAL" "CONN"
					( Origin gFrontEnd )
				)
				( attribute "PACK_TYPE" "SM"
					( Origin gFrontEnd )
				)
				( attribute "PART_NUMBER" "H61426-002"
					( Origin gFrontEnd )
				)
				( attribute "PHYS_PAGE" "194"
					( Origin gFrontEnd )
				)
				( attribute "ROOM" "MCP VRM CPU0"
					( Origin gFrontEnd )
				)
				( attribute "ROT" "0"
					( Origin gFrontEnd )
				)
				( attribute "SEC" "1"
					( Origin gFrontEnd )
				)
				( attribute "SEC_TYPE" "SM"
					( Origin gFrontEnd )
				)
				( attribute "VER" "1"
					( Origin gFrontEnd )
				)
				( attribute "XY" "(-3150,2100)"
					( Origin gFrontEnd )
				)
				( attribute "CHIPS_PART_NAME" "SCONN120_H61426002"
					( Origin gPackager )
				)
				( attribute "CDS_PART_NAME" "SCONN120_H61426002_SM-CONN,H61A"
					( Origin gPackager )
				)
				( objectStatus "J6E1" )
				( pin "ioa1"
					( attribute "PN" "A1"
						( Origin gPackager )
					)
					( objectStatus "J6E1.A1" )
				)
				( pin "ioa2"
					( attribute "PN" "A2"
						( Origin gPackager )
					)
					( objectStatus "J6E1.A2" )
				)
				( pin "ioa3"
					( attribute "PN" "A3"
						( Origin gPackager )
					)
					( objectStatus "J6E1.A3" )
				)
				( pin "ioa4"
					( attribute "PN" "A4"
						( Origin gPackager )
					)
					( objectStatus "J6E1.A4" )
				)
				( pin "ioa5"
					( attribute "PN" "A5"
						( Origin gPackager )
					)
					( objectStatus "J6E1.A5" )
				)
				( pin "ioa6"
					( attribute "PN" "A6"
						( Origin gPackager )
					)
					( objectStatus "J6E1.A6" )
				)
				( pin "ioa7"
					( attribute "PN" "A7"
						( Origin gPackager )
					)
					( objectStatus "J6E1.A7" )
				)
				( pin "ioa8"
					( attribute "PN" "A8"
						( Origin gPackager )
					)
					( objectStatus "J6E1.A8" )
				)
				( pin "ioa9"
					( attribute "PN" "A9"
						( Origin gPackager )
					)
					( objectStatus "J6E1.A9" )
				)
				( pin "ioa10"
					( attribute "PN" "A10"
						( Origin gPackager )
					)
					( objectStatus "J6E1.A10" )
				)
				( pin "ioa11"
					( attribute "PN" "A11"
						( Origin gPackager )
					)
					( objectStatus "J6E1.A11" )
				)
				( pin "ioa12"
					( attribute "PN" "A12"
						( Origin gPackager )
					)
					( objectStatus "J6E1.A12" )
				)
				( pin "ioa13"
					( attribute "PN" "A13"
						( Origin gPackager )
					)
					( objectStatus "J6E1.A13" )
				)
				( pin "ioa14"
					( attribute "PN" "A14"
						( Origin gPackager )
					)
					( objectStatus "J6E1.A14" )
				)
				( pin "ioa15"
					( attribute "PN" "A15"
						( Origin gPackager )
					)
					( objectStatus "J6E1.A15" )
				)
				( pin "ioa16"
					( attribute "PN" "A16"
						( Origin gPackager )
					)
					( objectStatus "J6E1.A16" )
				)
				( pin "ioa17"
					( attribute "PN" "A17"
						( Origin gPackager )
					)
					( objectStatus "J6E1.A17" )
				)
				( pin "ioa18"
					( attribute "PN" "A18"
						( Origin gPackager )
					)
					( objectStatus "J6E1.A18" )
				)
				( pin "ioa19"
					( attribute "PN" "A19"
						( Origin gPackager )
					)
					( objectStatus "J6E1.A19" )
				)
				( pin "ioa20"
					( attribute "PN" "A20"
						( Origin gPackager )
					)
					( objectStatus "J6E1.A20" )
				)
				( pin "iob1"
					( attribute "PN" "B1"
						( Origin gPackager )
					)
					( objectStatus "J6E1.B1" )
				)
				( pin "iob2"
					( attribute "PN" "B2"
						( Origin gPackager )
					)
					( objectStatus "J6E1.B2" )
				)
				( pin "iob3"
					( attribute "PN" "B3"
						( Origin gPackager )
					)
					( objectStatus "J6E1.B3" )
				)
				( pin "iob4"
					( attribute "PN" "B4"
						( Origin gPackager )
					)
					( objectStatus "J6E1.B4" )
				)
				( pin "iob5"
					( attribute "PN" "B5"
						( Origin gPackager )
					)
					( objectStatus "J6E1.B5" )
				)
				( pin "iob6"
					( attribute "PN" "B6"
						( Origin gPackager )
					)
					( objectStatus "J6E1.B6" )
				)
				( pin "iob7"
					( attribute "PN" "B7"
						( Origin gPackager )
					)
					( objectStatus "J6E1.B7" )
				)
				( pin "iob8"
					( attribute "PN" "B8"
						( Origin gPackager )
					)
					( objectStatus "J6E1.B8" )
				)
				( pin "iob9"
					( attribute "PN" "B9"
						( Origin gPackager )
					)
					( objectStatus "J6E1.B9" )
				)
				( pin "iob10"
					( attribute "PN" "B10"
						( Origin gPackager )
					)
					( objectStatus "J6E1.B10" )
				)
				( pin "iob11"
					( attribute "PN" "B11"
						( Origin gPackager )
					)
					( objectStatus "J6E1.B11" )
				)
				( pin "iob12"
					( attribute "PN" "B12"
						( Origin gPackager )
					)
					( objectStatus "J6E1.B12" )
				)
				( pin "iob13"
					( attribute "PN" "B13"
						( Origin gPackager )
					)
					( objectStatus "J6E1.B13" )
				)
				( pin "iob14"
					( attribute "PN" "B14"
						( Origin gPackager )
					)
					( objectStatus "J6E1.B14" )
				)
				( pin "iob15"
					( attribute "PN" "B15"
						( Origin gPackager )
					)
					( objectStatus "J6E1.B15" )
				)
				( pin "iob16"
					( attribute "PN" "B16"
						( Origin gPackager )
					)
					( objectStatus "J6E1.B16" )
				)
				( pin "iob17"
					( attribute "PN" "B17"
						( Origin gPackager )
					)
					( objectStatus "J6E1.B17" )
				)
				( pin "iob18"
					( attribute "PN" "B18"
						( Origin gPackager )
					)
					( objectStatus "J6E1.B18" )
				)
				( pin "iob19"
					( attribute "PN" "B19"
						( Origin gPackager )
					)
					( objectStatus "J6E1.B19" )
				)
				( pin "iob20"
					( attribute "PN" "B20"
						( Origin gPackager )
					)
					( objectStatus "J6E1.B20" )
				)
				( pin "ioc1"
					( attribute "PN" "C1"
						( Origin gPackager )
					)
					( objectStatus "J6E1.C1" )
				)
				( pin "ioc2"
					( attribute "PN" "C2"
						( Origin gPackager )
					)
					( objectStatus "J6E1.C2" )
				)
				( pin "ioc3"
					( attribute "PN" "C3"
						( Origin gPackager )
					)
					( objectStatus "J6E1.C3" )
				)
				( pin "ioc4"
					( attribute "PN" "C4"
						( Origin gPackager )
					)
					( objectStatus "J6E1.C4" )
				)
				( pin "ioc5"
					( attribute "PN" "C5"
						( Origin gPackager )
					)
					( objectStatus "J6E1.C5" )
				)
				( pin "ioc6"
					( attribute "PN" "C6"
						( Origin gPackager )
					)
					( objectStatus "J6E1.C6" )
				)
				( pin "ioc7"
					( attribute "PN" "C7"
						( Origin gPackager )
					)
					( objectStatus "J6E1.C7" )
				)
				( pin "ioc8"
					( attribute "PN" "C8"
						( Origin gPackager )
					)
					( objectStatus "J6E1.C8" )
				)
				( pin "ioc9"
					( attribute "PN" "C9"
						( Origin gPackager )
					)
					( objectStatus "J6E1.C9" )
				)
				( pin "ioc10"
					( attribute "PN" "C10"
						( Origin gPackager )
					)
					( objectStatus "J6E1.C10" )
				)
				( pin "ioc11"
					( attribute "PN" "C11"
						( Origin gPackager )
					)
					( objectStatus "J6E1.C11" )
				)
				( pin "ioc12"
					( attribute "PN" "C12"
						( Origin gPackager )
					)
					( objectStatus "J6E1.C12" )
				)
				( pin "ioc13"
					( attribute "PN" "C13"
						( Origin gPackager )
					)
					( objectStatus "J6E1.C13" )
				)
				( pin "ioc14"
					( attribute "PN" "C14"
						( Origin gPackager )
					)
					( objectStatus "J6E1.C14" )
				)
				( pin "ioc15"
					( attribute "PN" "C15"
						( Origin gPackager )
					)
					( objectStatus "J6E1.C15" )
				)
				( pin "ioc16"
					( attribute "PN" "C16"
						( Origin gPackager )
					)
					( objectStatus "J6E1.C16" )
				)
				( pin "ioc17"
					( attribute "PN" "C17"
						( Origin gPackager )
					)
					( objectStatus "J6E1.C17" )
				)
				( pin "ioc18"
					( attribute "PN" "C18"
						( Origin gPackager )
					)
					( objectStatus "J6E1.C18" )
				)
				( pin "ioc19"
					( attribute "PN" "C19"
						( Origin gPackager )
					)
					( objectStatus "J6E1.C19" )
				)
				( pin "ioc20"
					( attribute "PN" "C20"
						( Origin gPackager )
					)
					( objectStatus "J6E1.C20" )
				)
				( pin "iod1"
					( attribute "PN" "D1"
						( Origin gPackager )
					)
					( objectStatus "J6E1.D1" )
				)
				( pin "iod2"
					( attribute "PN" "D2"
						( Origin gPackager )
					)
					( objectStatus "J6E1.D2" )
				)
				( pin "iod3"
					( attribute "PN" "D3"
						( Origin gPackager )
					)
					( objectStatus "J6E1.D3" )
				)
				( pin "iod4"
					( attribute "PN" "D4"
						( Origin gPackager )
					)
					( objectStatus "J6E1.D4" )
				)
				( pin "iod5"
					( attribute "PN" "D5"
						( Origin gPackager )
					)
					( objectStatus "J6E1.D5" )
				)
				( pin "iod6"
					( attribute "PN" "D6"
						( Origin gPackager )
					)
					( objectStatus "J6E1.D6" )
				)
				( pin "iod7"
					( attribute "PN" "D7"
						( Origin gPackager )
					)
					( objectStatus "J6E1.D7" )
				)
				( pin "iod8"
					( attribute "PN" "D8"
						( Origin gPackager )
					)
					( objectStatus "J6E1.D8" )
				)
				( pin "iod9"
					( attribute "PN" "D9"
						( Origin gPackager )
					)
					( objectStatus "J6E1.D9" )
				)
				( pin "iod10"
					( attribute "PN" "D10"
						( Origin gPackager )
					)
					( objectStatus "J6E1.D10" )
				)
				( pin "iod11"
					( attribute "PN" "D11"
						( Origin gPackager )
					)
					( objectStatus "J6E1.D11" )
				)
				( pin "iod12"
					( attribute "PN" "D12"
						( Origin gPackager )
					)
					( objectStatus "J6E1.D12" )
				)
				( pin "iod13"
					( attribute "PN" "D13"
						( Origin gPackager )
					)
					( objectStatus "J6E1.D13" )
				)
				( pin "iod14"
					( attribute "PN" "D14"
						( Origin gPackager )
					)
					( objectStatus "J6E1.D14" )
				)
				( pin "iod15"
					( attribute "PN" "D15"
						( Origin gPackager )
					)
					( objectStatus "J6E1.D15" )
				)
				( pin "iod16"
					( attribute "PN" "D16"
						( Origin gPackager )
					)
					( objectStatus "J6E1.D16" )
				)
				( pin "iod17"
					( attribute "PN" "D17"
						( Origin gPackager )
					)
					( objectStatus "J6E1.D17" )
				)
				( pin "iod18"
					( attribute "PN" "D18"
						( Origin gPackager )
					)
					( objectStatus "J6E1.D18" )
				)
				( pin "iod19"
					( attribute "PN" "D19"
						( Origin gPackager )
					)
					( objectStatus "J6E1.D19" )
				)
				( pin "iod20"
					( attribute "PN" "D20"
						( Origin gPackager )
					)
					( objectStatus "J6E1.D20" )
				)
				( pin "ioe1"
					( attribute "PN" "E1"
						( Origin gPackager )
					)
					( objectStatus "J6E1.E1" )
				)
				( pin "ioe2"
					( attribute "PN" "E2"
						( Origin gPackager )
					)
					( objectStatus "J6E1.E2" )
				)
				( pin "ioe3"
					( attribute "PN" "E3"
						( Origin gPackager )
					)
					( objectStatus "J6E1.E3" )
				)
				( pin "ioe4"
					( attribute "PN" "E4"
						( Origin gPackager )
					)
					( objectStatus "J6E1.E4" )
				)
				( pin "ioe5"
					( attribute "PN" "E5"
						( Origin gPackager )
					)
					( objectStatus "J6E1.E5" )
				)
				( pin "ioe6"
					( attribute "PN" "E6"
						( Origin gPackager )
					)
					( objectStatus "J6E1.E6" )
				)
				( pin "ioe7"
					( attribute "PN" "E7"
						( Origin gPackager )
					)
					( objectStatus "J6E1.E7" )
				)
				( pin "ioe8"
					( attribute "PN" "E8"
						( Origin gPackager )
					)
					( objectStatus "J6E1.E8" )
				)
				( pin "ioe9"
					( attribute "PN" "E9"
						( Origin gPackager )
					)
					( objectStatus "J6E1.E9" )
				)
				( pin "ioe10"
					( attribute "PN" "E10"
						( Origin gPackager )
					)
					( objectStatus "J6E1.E10" )
				)
				( pin "ioe11"
					( attribute "PN" "E11"
						( Origin gPackager )
					)
					( objectStatus "J6E1.E11" )
				)
				( pin "ioe12"
					( attribute "PN" "E12"
						( Origin gPackager )
					)
					( objectStatus "J6E1.E12" )
				)
				( pin "ioe13"
					( attribute "PN" "E13"
						( Origin gPackager )
					)
					( objectStatus "J6E1.E13" )
				)
				( pin "ioe14"
					( attribute "PN" "E14"
						( Origin gPackager )
					)
					( objectStatus "J6E1.E14" )
				)
				( pin "ioe15"
					( attribute "PN" "E15"
						( Origin gPackager )
					)
					( objectStatus "J6E1.E15" )
				)
				( pin "ioe16"
					( attribute "PN" "E16"
						( Origin gPackager )
					)
					( objectStatus "J6E1.E16" )
				)
				( pin "ioe17"
					( attribute "PN" "E17"
						( Origin gPackager )
					)
					( objectStatus "J6E1.E17" )
				)
				( pin "ioe18"
					( attribute "PN" "E18"
						( Origin gPackager )
					)
					( objectStatus "J6E1.E18" )
				)
				( pin "ioe19"
					( attribute "PN" "E19"
						( Origin gPackager )
					)
					( objectStatus "J6E1.E19" )
				)
				( pin "ioe20"
					( attribute "PN" "E20"
						( Origin gPackager )
					)
					( objectStatus "J6E1.E20" )
				)
				( pin "iof1"
					( attribute "PN" "F1"
						( Origin gPackager )
					)
					( objectStatus "J6E1.F1" )
				)
				( pin "iof2"
					( attribute "PN" "F2"
						( Origin gPackager )
					)
					( objectStatus "J6E1.F2" )
				)
				( pin "iof3"
					( attribute "PN" "F3"
						( Origin gPackager )
					)
					( objectStatus "J6E1.F3" )
				)
				( pin "iof4"
					( attribute "PN" "F4"
						( Origin gPackager )
					)
					( objectStatus "J6E1.F4" )
				)
				( pin "iof5"
					( attribute "PN" "F5"
						( Origin gPackager )
					)
					( objectStatus "J6E1.F5" )
				)
				( pin "iof6"
					( attribute "PN" "F6"
						( Origin gPackager )
					)
					( objectStatus "J6E1.F6" )
				)
				( pin "iof7"
					( attribute "PN" "F7"
						( Origin gPackager )
					)
					( objectStatus "J6E1.F7" )
				)
				( pin "iof8"
					( attribute "PN" "F8"
						( Origin gPackager )
					)
					( objectStatus "J6E1.F8" )
				)
				( pin "iof9"
					( attribute "PN" "F9"
						( Origin gPackager )
					)
					( objectStatus "J6E1.F9" )
				)
				( pin "iof10"
					( attribute "PN" "F10"
						( Origin gPackager )
					)
					( objectStatus "J6E1.F10" )
				)
				( pin "iof11"
					( attribute "PN" "F11"
						( Origin gPackager )
					)
					( objectStatus "J6E1.F11" )
				)
				( pin "iof12"
					( attribute "PN" "F12"
						( Origin gPackager )
					)
					( objectStatus "J6E1.F12" )
				)
				( pin "iof13"
					( attribute "PN" "F13"
						( Origin gPackager )
					)
					( objectStatus "J6E1.F13" )
				)
				( pin "iof14"
					( attribute "PN" "F14"
						( Origin gPackager )
					)
					( objectStatus "J6E1.F14" )
				)
				( pin "iof15"
					( attribute "PN" "F15"
						( Origin gPackager )
					)
					( objectStatus "J6E1.F15" )
				)
				( pin "iof16"
					( attribute "PN" "F16"
						( Origin gPackager )
					)
					( objectStatus "J6E1.F16" )
				)
				( pin "iof17"
					( attribute "PN" "F17"
						( Origin gPackager )
					)
					( objectStatus "J6E1.F17" )
				)
				( pin "iof18"
					( attribute "PN" "F18"
						( Origin gPackager )
					)
					( objectStatus "J6E1.F18" )
				)
				( pin "iof19"
					( attribute "PN" "F19"
						( Origin gPackager )
					)
					( objectStatus "J6E1.F19" )
				)
				( pin "iof20"
					( attribute "PN" "F20"
						( Origin gPackager )
					)
					( objectStatus "J6E1.F20" )
				)
			)
			( gate "@baseboard_fab2_lib.baseboard_fab2(sch_1):page194_i56"
				( attribute "CDS_LIB" "mstr_sconn"
					( Origin gPackager )
				)
				( attribute "CDS_LOCATION" "J6B1"
					( Origin gPackager )
				)
				( attribute "CDS_SEC" "1"
					( Origin gPackager )
				)
				( attribute "LOCATION" "J6B1"
					( Origin gFrontEnd )
				)
				( attribute "MATERIAL" "CONN"
					( Origin gFrontEnd )
				)
				( attribute "PACK_TYPE" "SM"
					( Origin gFrontEnd )
				)
				( attribute "PART_NUMBER" "H61426-002"
					( Origin gFrontEnd )
				)
				( attribute "PHYS_PAGE" "194"
					( Origin gFrontEnd )
				)
				( attribute "ROOM" "MCP VRM CPU0"
					( Origin gFrontEnd )
				)
				( attribute "ROT" "0"
					( Origin gFrontEnd )
				)
				( attribute "SEC" "1"
					( Origin gFrontEnd )
				)
				( attribute "SEC_TYPE" "SM"
					( Origin gFrontEnd )
				)
				( attribute "VER" "1"
					( Origin gFrontEnd )
				)
				( attribute "XY" "(-6550,2075)"
					( Origin gFrontEnd )
				)
				( attribute "CHIPS_PART_NAME" "SCONN120_H61426002"
					( Origin gPackager )
				)
				( attribute "CDS_PART_NAME" "SCONN120_H61426002_SM-CONN,H61A"
					( Origin gPackager )
				)
				( objectStatus "J6B1" )
				( pin "ioa1"
					( attribute "PN" "A1"
						( Origin gPackager )
					)
					( objectStatus "J6B1.A1" )
				)
				( pin "ioa2"
					( attribute "PN" "A2"
						( Origin gPackager )
					)
					( objectStatus "J6B1.A2" )
				)
				( pin "ioa3"
					( attribute "PN" "A3"
						( Origin gPackager )
					)
					( objectStatus "J6B1.A3" )
				)
				( pin "ioa4"
					( attribute "PN" "A4"
						( Origin gPackager )
					)
					( objectStatus "J6B1.A4" )
				)
				( pin "ioa5"
					( attribute "PN" "A5"
						( Origin gPackager )
					)
					( objectStatus "J6B1.A5" )
				)
				( pin "ioa6"
					( attribute "PN" "A6"
						( Origin gPackager )
					)
					( objectStatus "J6B1.A6" )
				)
				( pin "ioa7"
					( attribute "PN" "A7"
						( Origin gPackager )
					)
					( objectStatus "J6B1.A7" )
				)
				( pin "ioa8"
					( attribute "PN" "A8"
						( Origin gPackager )
					)
					( objectStatus "J6B1.A8" )
				)
				( pin "ioa9"
					( attribute "PN" "A9"
						( Origin gPackager )
					)
					( objectStatus "J6B1.A9" )
				)
				( pin "ioa10"
					( attribute "PN" "A10"
						( Origin gPackager )
					)
					( objectStatus "J6B1.A10" )
				)
				( pin "ioa11"
					( attribute "PN" "A11"
						( Origin gPackager )
					)
					( objectStatus "J6B1.A11" )
				)
				( pin "ioa12"
					( attribute "PN" "A12"
						( Origin gPackager )
					)
					( objectStatus "J6B1.A12" )
				)
				( pin "ioa13"
					( attribute "PN" "A13"
						( Origin gPackager )
					)
					( objectStatus "J6B1.A13" )
				)
				( pin "ioa14"
					( attribute "PN" "A14"
						( Origin gPackager )
					)
					( objectStatus "J6B1.A14" )
				)
				( pin "ioa15"
					( attribute "PN" "A15"
						( Origin gPackager )
					)
					( objectStatus "J6B1.A15" )
				)
				( pin "ioa16"
					( attribute "PN" "A16"
						( Origin gPackager )
					)
					( objectStatus "J6B1.A16" )
				)
				( pin "ioa17"
					( attribute "PN" "A17"
						( Origin gPackager )
					)
					( objectStatus "J6B1.A17" )
				)
				( pin "ioa18"
					( attribute "PN" "A18"
						( Origin gPackager )
					)
					( objectStatus "J6B1.A18" )
				)
				( pin "ioa19"
					( attribute "PN" "A19"
						( Origin gPackager )
					)
					( objectStatus "J6B1.A19" )
				)
				( pin "ioa20"
					( attribute "PN" "A20"
						( Origin gPackager )
					)
					( objectStatus "J6B1.A20" )
				)
				( pin "iob1"
					( attribute "PN" "B1"
						( Origin gPackager )
					)
					( objectStatus "J6B1.B1" )
				)
				( pin "iob2"
					( attribute "PN" "B2"
						( Origin gPackager )
					)
					( objectStatus "J6B1.B2" )
				)
				( pin "iob3"
					( attribute "PN" "B3"
						( Origin gPackager )
					)
					( objectStatus "J6B1.B3" )
				)
				( pin "iob4"
					( attribute "PN" "B4"
						( Origin gPackager )
					)
					( objectStatus "J6B1.B4" )
				)
				( pin "iob5"
					( attribute "PN" "B5"
						( Origin gPackager )
					)
					( objectStatus "J6B1.B5" )
				)
				( pin "iob6"
					( attribute "PN" "B6"
						( Origin gPackager )
					)
					( objectStatus "J6B1.B6" )
				)
				( pin "iob7"
					( attribute "PN" "B7"
						( Origin gPackager )
					)
					( objectStatus "J6B1.B7" )
				)
				( pin "iob8"
					( attribute "PN" "B8"
						( Origin gPackager )
					)
					( objectStatus "J6B1.B8" )
				)
				( pin "iob9"
					( attribute "PN" "B9"
						( Origin gPackager )
					)
					( objectStatus "J6B1.B9" )
				)
				( pin "iob10"
					( attribute "PN" "B10"
						( Origin gPackager )
					)
					( objectStatus "J6B1.B10" )
				)
				( pin "iob11"
					( attribute "PN" "B11"
						( Origin gPackager )
					)
					( objectStatus "J6B1.B11" )
				)
				( pin "iob12"
					( attribute "PN" "B12"
						( Origin gPackager )
					)
					( objectStatus "J6B1.B12" )
				)
				( pin "iob13"
					( attribute "PN" "B13"
						( Origin gPackager )
					)
					( objectStatus "J6B1.B13" )
				)
				( pin "iob14"
					( attribute "PN" "B14"
						( Origin gPackager )
					)
					( objectStatus "J6B1.B14" )
				)
				( pin "iob15"
					( attribute "PN" "B15"
						( Origin gPackager )
					)
					( objectStatus "J6B1.B15" )
				)
				( pin "iob16"
					( attribute "PN" "B16"
						( Origin gPackager )
					)
					( objectStatus "J6B1.B16" )
				)
				( pin "iob17"
					( attribute "PN" "B17"
						( Origin gPackager )
					)
					( objectStatus "J6B1.B17" )
				)
				( pin "iob18"
					( attribute "PN" "B18"
						( Origin gPackager )
					)
					( objectStatus "J6B1.B18" )
				)
				( pin "iob19"
					( attribute "PN" "B19"
						( Origin gPackager )
					)
					( objectStatus "J6B1.B19" )
				)
				( pin "iob20"
					( attribute "PN" "B20"
						( Origin gPackager )
					)
					( objectStatus "J6B1.B20" )
				)
				( pin "ioc1"
					( attribute "PN" "C1"
						( Origin gPackager )
					)
					( objectStatus "J6B1.C1" )
				)
				( pin "ioc2"
					( attribute "PN" "C2"
						( Origin gPackager )
					)
					( objectStatus "J6B1.C2" )
				)
				( pin "ioc3"
					( attribute "PN" "C3"
						( Origin gPackager )
					)
					( objectStatus "J6B1.C3" )
				)
				( pin "ioc4"
					( attribute "PN" "C4"
						( Origin gPackager )
					)
					( objectStatus "J6B1.C4" )
				)
				( pin "ioc5"
					( attribute "PN" "C5"
						( Origin gPackager )
					)
					( objectStatus "J6B1.C5" )
				)
				( pin "ioc6"
					( attribute "PN" "C6"
						( Origin gPackager )
					)
					( objectStatus "J6B1.C6" )
				)
				( pin "ioc7"
					( attribute "PN" "C7"
						( Origin gPackager )
					)
					( objectStatus "J6B1.C7" )
				)
				( pin "ioc8"
					( attribute "PN" "C8"
						( Origin gPackager )
					)
					( objectStatus "J6B1.C8" )
				)
				( pin "ioc9"
					( attribute "PN" "C9"
						( Origin gPackager )
					)
					( objectStatus "J6B1.C9" )
				)
				( pin "ioc10"
					( attribute "PN" "C10"
						( Origin gPackager )
					)
					( objectStatus "J6B1.C10" )
				)
				( pin "ioc11"
					( attribute "PN" "C11"
						( Origin gPackager )
					)
					( objectStatus "J6B1.C11" )
				)
				( pin "ioc12"
					( attribute "PN" "C12"
						( Origin gPackager )
					)
					( objectStatus "J6B1.C12" )
				)
				( pin "ioc13"
					( attribute "PN" "C13"
						( Origin gPackager )
					)
					( objectStatus "J6B1.C13" )
				)
				( pin "ioc14"
					( attribute "PN" "C14"
						( Origin gPackager )
					)
					( objectStatus "J6B1.C14" )
				)
				( pin "ioc15"
					( attribute "PN" "C15"
						( Origin gPackager )
					)
					( objectStatus "J6B1.C15" )
				)
				( pin "ioc16"
					( attribute "PN" "C16"
						( Origin gPackager )
					)
					( objectStatus "J6B1.C16" )
				)
				( pin "ioc17"
					( attribute "PN" "C17"
						( Origin gPackager )
					)
					( objectStatus "J6B1.C17" )
				)
				( pin "ioc18"
					( attribute "PN" "C18"
						( Origin gPackager )
					)
					( objectStatus "J6B1.C18" )
				)
				( pin "ioc19"
					( attribute "PN" "C19"
						( Origin gPackager )
					)
					( objectStatus "J6B1.C19" )
				)
				( pin "ioc20"
					( attribute "PN" "C20"
						( Origin gPackager )
					)
					( objectStatus "J6B1.C20" )
				)
				( pin "iod1"
					( attribute "PN" "D1"
						( Origin gPackager )
					)
					( objectStatus "J6B1.D1" )
				)
				( pin "iod2"
					( attribute "PN" "D2"
						( Origin gPackager )
					)
					( objectStatus "J6B1.D2" )
				)
				( pin "iod3"
					( attribute "PN" "D3"
						( Origin gPackager )
					)
					( objectStatus "J6B1.D3" )
				)
				( pin "iod4"
					( attribute "PN" "D4"
						( Origin gPackager )
					)
					( objectStatus "J6B1.D4" )
				)
				( pin "iod5"
					( attribute "PN" "D5"
						( Origin gPackager )
					)
					( objectStatus "J6B1.D5" )
				)
				( pin "iod6"
					( attribute "PN" "D6"
						( Origin gPackager )
					)
					( objectStatus "J6B1.D6" )
				)
				( pin "iod7"
					( attribute "PN" "D7"
						( Origin gPackager )
					)
					( objectStatus "J6B1.D7" )
				)
				( pin "iod8"
					( attribute "PN" "D8"
						( Origin gPackager )
					)
					( objectStatus "J6B1.D8" )
				)
				( pin "iod9"
					( attribute "PN" "D9"
						( Origin gPackager )
					)
					( objectStatus "J6B1.D9" )
				)
				( pin "iod10"
					( attribute "PN" "D10"
						( Origin gPackager )
					)
					( objectStatus "J6B1.D10" )
				)
				( pin "iod11"
					( attribute "PN" "D11"
						( Origin gPackager )
					)
					( objectStatus "J6B1.D11" )
				)
				( pin "iod12"
					( attribute "PN" "D12"
						( Origin gPackager )
					)
					( objectStatus "J6B1.D12" )
				)
				( pin "iod13"
					( attribute "PN" "D13"
						( Origin gPackager )
					)
					( objectStatus "J6B1.D13" )
				)
				( pin "iod14"
					( attribute "PN" "D14"
						( Origin gPackager )
					)
					( objectStatus "J6B1.D14" )
				)
				( pin "iod15"
					( attribute "PN" "D15"
						( Origin gPackager )
					)
					( objectStatus "J6B1.D15" )
				)
				( pin "iod16"
					( attribute "PN" "D16"
						( Origin gPackager )
					)
					( objectStatus "J6B1.D16" )
				)
				( pin "iod17"
					( attribute "PN" "D17"
						( Origin gPackager )
					)
					( objectStatus "J6B1.D17" )
				)
				( pin "iod18"
					( attribute "PN" "D18"
						( Origin gPackager )
					)
					( objectStatus "J6B1.D18" )
				)
				( pin "iod19"
					( attribute "PN" "D19"
						( Origin gPackager )
					)
					( objectStatus "J6B1.D19" )
				)
				( pin "iod20"
					( attribute "PN" "D20"
						( Origin gPackager )
					)
					( objectStatus "J6B1.D20" )
				)
				( pin "ioe1"
					( attribute "PN" "E1"
						( Origin gPackager )
					)
					( objectStatus "J6B1.E1" )
				)
				( pin "ioe2"
					( attribute "PN" "E2"
						( Origin gPackager )
					)
					( objectStatus "J6B1.E2" )
				)
				( pin "ioe3"
					( attribute "PN" "E3"
						( Origin gPackager )
					)
					( objectStatus "J6B1.E3" )
				)
				( pin "ioe4"
					( attribute "PN" "E4"
						( Origin gPackager )
					)
					( objectStatus "J6B1.E4" )
				)
				( pin "ioe5"
					( attribute "PN" "E5"
						( Origin gPackager )
					)
					( objectStatus "J6B1.E5" )
				)
				( pin "ioe6"
					( attribute "PN" "E6"
						( Origin gPackager )
					)
					( objectStatus "J6B1.E6" )
				)
				( pin "ioe7"
					( attribute "PN" "E7"
						( Origin gPackager )
					)
					( objectStatus "J6B1.E7" )
				)
				( pin "ioe8"
					( attribute "PN" "E8"
						( Origin gPackager )
					)
					( objectStatus "J6B1.E8" )
				)
				( pin "ioe9"
					( attribute "PN" "E9"
						( Origin gPackager )
					)
					( objectStatus "J6B1.E9" )
				)
				( pin "ioe10"
					( attribute "PN" "E10"
						( Origin gPackager )
					)
					( objectStatus "J6B1.E10" )
				)
				( pin "ioe11"
					( attribute "PN" "E11"
						( Origin gPackager )
					)
					( objectStatus "J6B1.E11" )
				)
				( pin "ioe12"
					( attribute "PN" "E12"
						( Origin gPackager )
					)
					( objectStatus "J6B1.E12" )
				)
				( pin "ioe13"
					( attribute "PN" "E13"
						( Origin gPackager )
					)
					( objectStatus "J6B1.E13" )
				)
				( pin "ioe14"
					( attribute "PN" "E14"
						( Origin gPackager )
					)
					( objectStatus "J6B1.E14" )
				)
				( pin "ioe15"
					( attribute "PN" "E15"
						( Origin gPackager )
					)
					( objectStatus "J6B1.E15" )
				)
				( pin "ioe16"
					( attribute "PN" "E16"
						( Origin gPackager )
					)
					( objectStatus "J6B1.E16" )
				)
				( pin "ioe17"
					( attribute "PN" "E17"
						( Origin gPackager )
					)
					( objectStatus "J6B1.E17" )
				)
				( pin "ioe18"
					( attribute "PN" "E18"
						( Origin gPackager )
					)
					( objectStatus "J6B1.E18" )
				)
				( pin "ioe19"
					( attribute "PN" "E19"
						( Origin gPackager )
					)
					( objectStatus "J6B1.E19" )
				)
				( pin "ioe20"
					( attribute "PN" "E20"
						( Origin gPackager )
					)
					( objectStatus "J6B1.E20" )
				)
				( pin "iof1"
					( attribute "PN" "F1"
						( Origin gPackager )
					)
					( objectStatus "J6B1.F1" )
				)
				( pin "iof2"
					( attribute "PN" "F2"
						( Origin gPackager )
					)
					( objectStatus "J6B1.F2" )
				)
				( pin "iof3"
					( attribute "PN" "F3"
						( Origin gPackager )
					)
					( objectStatus "J6B1.F3" )
				)
				( pin "iof4"
					( attribute "PN" "F4"
						( Origin gPackager )
					)
					( objectStatus "J6B1.F4" )
				)
				( pin "iof5"
					( attribute "PN" "F5"
						( Origin gPackager )
					)
					( objectStatus "J6B1.F5" )
				)
				( pin "iof6"
					( attribute "PN" "F6"
						( Origin gPackager )
					)
					( objectStatus "J6B1.F6" )
				)
				( pin "iof7"
					( attribute "PN" "F7"
						( Origin gPackager )
					)
					( objectStatus "J6B1.F7" )
				)
				( pin "iof8"
					( attribute "PN" "F8"
						( Origin gPackager )
					)
					( objectStatus "J6B1.F8" )
				)
				( pin "iof9"
					( attribute "PN" "F9"
						( Origin gPackager )
					)
					( objectStatus "J6B1.F9" )
				)
				( pin "iof10"
					( attribute "PN" "F10"
						( Origin gPackager )
					)
					( objectStatus "J6B1.F10" )
				)
				( pin "iof11"
					( attribute "PN" "F11"
						( Origin gPackager )
					)
					( objectStatus "J6B1.F11" )
				)
				( pin "iof12"
					( attribute "PN" "F12"
						( Origin gPackager )
					)
					( objectStatus "J6B1.F12" )
				)
				( pin "iof13"
					( attribute "PN" "F13"
						( Origin gPackager )
					)
					( objectStatus "J6B1.F13" )
				)
				( pin "iof14"
					( attribute "PN" "F14"
						( Origin gPackager )
					)
					( objectStatus "J6B1.F14" )
				)
				( pin "iof15"
					( attribute "PN" "F15"
						( Origin gPackager )
					)
					( objectStatus "J6B1.F15" )
				)
				( pin "iof16"
					( attribute "PN" "F16"
						( Origin gPackager )
					)
					( objectStatus "J6B1.F16" )
				)
				( pin "iof17"
					( attribute "PN" "F17"
						( Origin gPackager )
					)
					( objectStatus "J6B1.F17" )
				)
				( pin "iof18"
					( attribute "PN" "F18"
						( Origin gPackager )
					)
					( objectStatus "J6B1.F18" )
				)
				( pin "iof19"
					( attribute "PN" "F19"
						( Origin gPackager )
					)
					( objectStatus "J6B1.F19" )
				)
				( pin "iof20"
					( attribute "PN" "F20"
						( Origin gPackager )
					)
					( objectStatus "J6B1.F20" )
				)
			)
			( gate "@baseboard_fab2_lib.baseboard_fab2(sch_1):page194_i86"
				( attribute "CDS_LIB" "dev_discrete"
					( Origin gPackager )
				)
				( attribute "CDS_LOCATION" "C3N40"
					( Origin gPackager )
				)
				( attribute "CDS_SEC" "1"
					( Origin gPackager )
				)
				( attribute "LOCATION" "C3N40"
					( Origin gFrontEnd )
				)
				( attribute "MATERIAL" "X6S"
					( Origin gFrontEnd )
				)
				( attribute "PACK_TYPE" "0402V"
					( Origin gFrontEnd )
				)
				( attribute "PART_NUMBER" "D97712-004"
					( Origin gFrontEnd )
				)
				( attribute "PHYS_PAGE" "194"
					( Origin gFrontEnd )
				)
				( attribute "ROOM" "P0V95_MCP_CPU0"
					( Origin gFrontEnd )
				)
				( attribute "ROT" "2"
					( Origin gFrontEnd )
				)
				( attribute "SEC" "1"
					( Origin gFrontEnd )
				)
				( attribute "SEC_TYPE" "0402V"
					( Origin gFrontEnd )
				)
				( attribute "TOLERANCE" "10%"
					( Origin gFrontEnd )
				)
				( attribute "VALUE" "1.0UF"
					( Origin gFrontEnd )
				)
				( attribute "VER" "1"
					( Origin gFrontEnd )
				)
				( attribute "VOLTAGE" "6.3V"
					( Units "uVoltage" "V" 1.000000)
					( Origin gFrontEnd )
				)
				( attribute "XY" "(-600,3250)"
					( Origin gFrontEnd )
				)
				( attribute "CHIPS_PART_NAME" "CAP_A"
					( Origin gPackager )
				)
				( attribute "CDS_PART_NAME" "CAP_A_0402V-1.0UF,6.3V,10%,X6SA"
					( Origin gPackager )
				)
				( objectStatus "C3N40" )
				( pin "a"
					( attribute "PN" "1"
						( Origin gPackager )
					)
					( objectStatus "C3N40.1" )
				)
				( pin "b"
					( attribute "PN" "2"
						( Origin gPackager )
					)
					( objectStatus "C3N40.2" )
				)
			)
			( gate "@baseboard_fab2_lib.baseboard_fab2(sch_1):page194_i99"
				( attribute "CDS_LIB" "dev_discrete"
					( Origin gPackager )
				)
				( attribute "CDS_LOCATION" "C3M46"
					( Origin gPackager )
				)
				( attribute "CDS_SEC" "1"
					( Origin gPackager )
				)
				( attribute "LOCATION" "C3M46"
					( Origin gFrontEnd )
				)
				( attribute "MATERIAL" "X6S"
					( Origin gFrontEnd )
				)
				( attribute "PACK_TYPE" "0402V"
					( Origin gFrontEnd )
				)
				( attribute "PART_NUMBER" "D97712-004"
					( Origin gFrontEnd )
				)
				( attribute "PHYS_PAGE" "194"
					( Origin gFrontEnd )
				)
				( attribute "ROOM" "P0V95_MCP_CPU0"
					( Origin gFrontEnd )
				)
				( attribute "ROT" "2"
					( Origin gFrontEnd )
				)
				( attribute "SEC" "1"
					( Origin gFrontEnd )
				)
				( attribute "SEC_TYPE" "0402V"
					( Origin gFrontEnd )
				)
				( attribute "TOLERANCE" "10%"
					( Origin gFrontEnd )
				)
				( attribute "VALUE" "1.0UF"
					( Origin gFrontEnd )
				)
				( attribute "VER" "1"
					( Origin gFrontEnd )
				)
				( attribute "VOLTAGE" "6.3V"
					( Units "uVoltage" "V" 1.000000)
					( Origin gFrontEnd )
				)
				( attribute "XY" "(-1025,3250)"
					( Origin gFrontEnd )
				)
				( attribute "CHIPS_PART_NAME" "CAP_A"
					( Origin gPackager )
				)
				( attribute "CDS_PART_NAME" "CAP_A_0402V-1.0UF,6.3V,10%,X6SA"
					( Origin gPackager )
				)
				( objectStatus "C3M46" )
				( pin "a"
					( attribute "PN" "1"
						( Origin gPackager )
					)
					( objectStatus "C3M46.1" )
				)
				( pin "b"
					( attribute "PN" "2"
						( Origin gPackager )
					)
					( objectStatus "C3M46.2" )
				)
			)
			( gate "@baseboard_fab2_lib.baseboard_fab2(sch_1):page194_i101"
				( attribute "BOM_COST" "PROC_VRD_VCCIN_CPU0"
					( Origin gFrontEnd )
				)
				( attribute "CDS_LIB" "mstr_discrete"
					( Origin gPackager )
				)
				( attribute "CDS_LOCATION" "C3N14"
					( Origin gPackager )
				)
				( attribute "CDS_SEC" "1"
					( Origin gPackager )
				)
				( attribute "LOCATION" "C3N14"
					( Origin gFrontEnd )
				)
				( attribute "MATERIAL" "ALUM"
					( Origin gFrontEnd )
				)
				( attribute "PACK_TYPE" "3018"
					( Origin gFrontEnd )
				)
				( attribute "PART_NUMBER" "699013-049"
					( Origin gFrontEnd )
				)
				( attribute "PHYS_PAGE" "194"
					( Origin gFrontEnd )
				)
				( attribute "ROOM" "P0V95_MCP_CPU0_DECAP_VR"
					( Origin gFrontEnd )
				)
				( attribute "ROT" "0"
					( Origin gFrontEnd )
				)
				( attribute "SEC" "1"
					( Origin gFrontEnd )
				)
				( attribute "SEC_TYPE" "3018"
					( Origin gFrontEnd )
				)
				( attribute "TOLERANCE" "20%"
					( Origin gFrontEnd )
				)
				( attribute "VALUE" "470UF"
					( Origin gFrontEnd )
				)
				( attribute "VER" "1"
					( Origin gFrontEnd )
				)
				( attribute "VOLTAGE" "2.5V"
					( Units "uVoltage" "V" 1.000000)
					( Origin gFrontEnd )
				)
				( attribute "XY" "(-1450,3150)"
					( Origin gFrontEnd )
				)
				( attribute "CHIPS_PART_NAME" "CAPP"
					( Origin gPackager )
				)
				( attribute "CDS_PART_NAME" "CAPP_3018-470UF,2.5V,20%,ALUM,A"
					( Origin gPackager )
				)
				( objectStatus "C3N14" )
				( pin "a"
					( attribute "PN" "1"
						( Origin gPackager )
					)
					( objectStatus "C3N14.1" )
				)
				( pin "b"
					( attribute "PN" "2"
						( Origin gPackager )
					)
					( objectStatus "C3N14.2" )
				)
			)
			( gate "@baseboard_fab2_lib.baseboard_fab2(sch_1):page194_i149"
				( attribute "CDS_LIB" "dev_discrete"
					( Origin gPackager )
				)
				( attribute "CDS_LOCATION" "C3T1"
					( Origin gPackager )
				)
				( attribute "CDS_SEC" "1"
					( Origin gPackager )
				)
				( attribute "LOCATION" "C3T1"
					( Origin gFrontEnd )
				)
				( attribute "MATERIAL" "X5R"
					( Origin gFrontEnd )
				)
				( attribute "PACK_TYPE" "0603V"
					( Origin gFrontEnd )
				)
				( attribute "PART_NUMBER" "602433-106"
					( Origin gFrontEnd )
				)
				( attribute "PHYS_PAGE" "194"
					( Origin gFrontEnd )
				)
				( attribute "ROT" "0"
					( Origin gFrontEnd )
				)
				( attribute "SEC" "1"
					( Origin gFrontEnd )
				)
				( attribute "SEC_TYPE" "0603V"
					( Origin gFrontEnd )
				)
				( attribute "TOLERANCE" "20%"
					( Origin gFrontEnd )
				)
				( attribute "VALUE" "47UF"
					( Origin gFrontEnd )
				)
				( attribute "VER" "1"
					( Origin gFrontEnd )
				)
				( attribute "VOLTAGE" "4V"
					( Units "uVoltage" "V" 1.000000)
					( Origin gFrontEnd )
				)
				( attribute "XY" "(-1450,1100)"
					( Origin gFrontEnd )
				)
				( attribute "CHIPS_PART_NAME" "CAP_A"
					( Origin gPackager )
				)
				( attribute "CDS_PART_NAME" "CAP_A_0603V-47UF,4V,20%,X5R,60A"
					( Origin gPackager )
				)
				( objectStatus "C3T1" )
				( pin "a"
					( attribute "PN" "1"
						( Origin gPackager )
					)
					( objectStatus "C3T1.1" )
				)
				( pin "b"
					( attribute "PN" "2"
						( Origin gPackager )
					)
					( objectStatus "C3T1.2" )
				)
			)
			( gate "@baseboard_fab2_lib.baseboard_fab2(sch_1):page194_i150"
				( attribute "CDS_LIB" "dev_discrete"
					( Origin gPackager )
				)
				( attribute "CDS_LOCATION" "C3T2"
					( Origin gPackager )
				)
				( attribute "CDS_SEC" "1"
					( Origin gPackager )
				)
				( attribute "LOCATION" "C3T2"
					( Origin gFrontEnd )
				)
				( attribute "MATERIAL" "X5R"
					( Origin gFrontEnd )
				)
				( attribute "PACK_TYPE" "0603V"
					( Origin gFrontEnd )
				)
				( attribute "PART_NUMBER" "602433-106"
					( Origin gFrontEnd )
				)
				( attribute "PHYS_PAGE" "194"
					( Origin gFrontEnd )
				)
				( attribute "ROT" "0"
					( Origin gFrontEnd )
				)
				( attribute "SEC" "1"
					( Origin gFrontEnd )
				)
				( attribute "SEC_TYPE" "0603V"
					( Origin gFrontEnd )
				)
				( attribute "TOLERANCE" "20%"
					( Origin gFrontEnd )
				)
				( attribute "VALUE" "47UF"
					( Origin gFrontEnd )
				)
				( attribute "VER" "1"
					( Origin gFrontEnd )
				)
				( attribute "VOLTAGE" "4V"
					( Units "uVoltage" "V" 1.000000)
					( Origin gFrontEnd )
				)
				( attribute "XY" "(-1750,1075)"
					( Origin gFrontEnd )
				)
				( attribute "CHIPS_PART_NAME" "CAP_A"
					( Origin gPackager )
				)
				( attribute "CDS_PART_NAME" "CAP_A_0603V-47UF,4V,20%,X5R,60A"
					( Origin gPackager )
				)
				( objectStatus "C3T2" )
				( pin "a"
					( attribute "PN" "1"
						( Origin gPackager )
					)
					( objectStatus "C3T2.1" )
				)
				( pin "b"
					( attribute "PN" "2"
						( Origin gPackager )
					)
					( objectStatus "C3T2.2" )
				)
			)
			( gate "@baseboard_fab2_lib.baseboard_fab2(sch_1):page194_i155"
				( attribute "CDS_LIB" "mstr_discrete"
					( Origin gPackager )
				)
				( attribute "CDS_LOCATION" "R7C24"
					( Origin gPackager )
				)
				( attribute "CDS_SEC" "1"
					( Origin gPackager )
				)
				( attribute "LOCATION" "R7C24"
					( Origin gFrontEnd )
				)
				( attribute "MATERIAL" "CHIP"
					( Origin gFrontEnd )
				)
				( attribute "PACK_TYPE" "0402"
					( Origin gFrontEnd )
				)
				( attribute "PART_NUMBER" "G21796-082"
					( Origin gFrontEnd )
				)
				( attribute "PHYS_PAGE" "194"
					( Origin gFrontEnd )
				)
				( attribute "ROOM" "PVCCIN_CPU1_VR"
					( Origin gFrontEnd )
				)
				( attribute "ROT" "0"
					( Origin gFrontEnd )
				)
				( attribute "SEC" "1"
					( Origin gFrontEnd )
				)
				( attribute "SEC_TYPE" "0402"
					( Origin gFrontEnd )
				)
				( attribute "TOLERANCE" "1%"
					( Origin gFrontEnd )
				)
				( attribute "VALUE" "4.02K"
					( Origin gFrontEnd )
				)
				( attribute "VER" "2"
					( Origin gFrontEnd )
				)
				( attribute "WATTAGE" "1/16W"
					( Origin gFrontEnd )
				)
				( attribute "XY" "(-7825,100)"
					( Origin gFrontEnd )
				)
				( attribute "CHIPS_PART_NAME" "RES"
					( Origin gPackager )
				)
				( attribute "CDS_PART_NAME" "RES_0402-4.02K,1%,1/16W,CHIP,GA"
					( Origin gPackager )
				)
				( objectStatus "R7C24" )
				( pin "a"
					( attribute "PN" "1"
						( Origin gPackager )
					)
					( objectStatus "R7C24.1" )
				)
				( pin "b"
					( attribute "PN" "2"
						( Origin gPackager )
					)
					( objectStatus "R7C24.2" )
				)
			)
			( gate "@baseboard_fab2_lib.baseboard_fab2(sch_1):page194_i156"
				( attribute "CDS_LIB" "mstr_discrete"
					( Origin gPackager )
				)
				( attribute "CDS_LOCATION" "R3N29"
					( Origin gPackager )
				)
				( attribute "CDS_SEC" "1"
					( Origin gPackager )
				)
				( attribute "LOCATION" "R3N29"
					( Origin gFrontEnd )
				)
				( attribute "MATERIAL" "CHIP"
					( Origin gFrontEnd )
				)
				( attribute "PACK_TYPE" "0402"
					( Origin gFrontEnd )
				)
				( attribute "PART_NUMBER" "G21796-317"
					( Origin gFrontEnd )
				)
				( attribute "PHYS_PAGE" "194"
					( Origin gFrontEnd )
				)
				( attribute "ROOM" "VDDQ_ABC_PWR_VR"
					( Origin gFrontEnd )
				)
				( attribute "ROT" "0"
					( Origin gFrontEnd )
				)
				( attribute "SEC" "1"
					( Origin gFrontEnd )
				)
				( attribute "SEC_TYPE" "0402"
					( Origin gFrontEnd )
				)
				( attribute "TOLERANCE" "1.0%"
					( Origin gFrontEnd )
				)
				( attribute "VALUE" "16K"
					( Origin gFrontEnd )
				)
				( attribute "VER" "2"
					( Origin gFrontEnd )
				)
				( attribute "WATTAGE" "1/16W"
					( Origin gFrontEnd )
				)
				( attribute "XY" "(-8175,125)"
					( Origin gFrontEnd )
				)
				( attribute "CHIPS_PART_NAME" "RES"
					( Origin gPackager )
				)
				( attribute "CDS_PART_NAME" "RES_0402-16K,1.0%,1/16W,CHIP,GA"
					( Origin gPackager )
				)
				( objectStatus "R3N29" )
				( pin "a"
					( attribute "PN" "1"
						( Origin gPackager )
					)
					( objectStatus "R3N29.1" )
				)
				( pin "b"
					( attribute "PN" "2"
						( Origin gPackager )
					)
					( objectStatus "R3N29.2" )
				)
			)
			( gate "@baseboard_fab2_lib.baseboard_fab2(sch_1):page195_i26"
				( attribute "CDS_LIB" "mstr_conn"
					( Origin gPackager )
				)
				( attribute "CDS_LMAN_SYM_OUTLINE" "-150,200,150,-200"
					( Origin gPackager )
				)
				( attribute "CDS_LOCATION" "RM1E1"
					( Origin gPackager )
				)
				( attribute "CDS_SEC" "1"
					( Origin gPackager )
				)
				( attribute "LOCATION" "RM1E1"
					( Origin gFrontEnd )
				)
				( attribute "MATERIAL" "CONN"
					( Origin gFrontEnd )
				)
				( attribute "PACK_TYPE" "PIP"
					( Origin gFrontEnd )
				)
				( attribute "PART_NUMBER" "G98259-001"
					( Origin gFrontEnd )
				)
				( attribute "PHYS_PAGE" "195"
					( Origin gFrontEnd )
				)
				( attribute "ROT" "0"
					( Origin gFrontEnd )
				)
				( attribute "SEC" "1"
					( Origin gPackager )
				)
				( attribute "VER" "1"
					( Origin gFrontEnd )
				)
				( attribute "XY" "(-925,3725)"
					( Origin gFrontEnd )
				)
				( attribute "CHIPS_PART_NAME" "CONN3_G98259001"
					( Origin gPackager )
				)
				( attribute "CDS_PART_NAME" "CONN3_G98259001_PIP-CONN,G9825A"
					( Origin gPackager )
				)
				( objectStatus "RM1E1" )
				( pin "io1"
					( attribute "PN" "1"
						( Origin gPackager )
					)
					( objectStatus "RM1E1.1" )
				)
				( pin "io2"
					( attribute "PN" "2"
						( Origin gPackager )
					)
					( objectStatus "RM1E1.2" )
				)
				( pin "io3"
					( attribute "PN" "3"
						( Origin gPackager )
					)
					( objectStatus "RM1E1.3" )
				)
			)
			( gate "@baseboard_fab2_lib.baseboard_fab2(sch_1):page195_i29"
				( attribute "CDS_LIB" "mstr_conn"
					( Origin gPackager )
				)
				( attribute "CDS_LMAN_SYM_OUTLINE" "-200,250,200,-250"
					( Origin gPackager )
				)
				( attribute "CDS_LOCATION" "J1E1"
					( Origin gPackager )
				)
				( attribute "CDS_SEC" "1"
					( Origin gPackager )
				)
				( attribute "LOCATION" "J1E1"
					( Origin gFrontEnd )
				)
				( attribute "MATERIAL" "CONN"
					( Origin gFrontEnd )
				)
				( attribute "PACK_TYPE" "THMT"
					( Origin gFrontEnd )
				)
				( attribute "PART_NUMBER" "G98257-001"
					( Origin gFrontEnd )
				)
				( attribute "PHYS_PAGE" "195"
					( Origin gFrontEnd )
				)
				( attribute "ROOM" "HOT_SWAP"
					( Origin gFrontEnd )
				)
				( attribute "ROT" "0"
					( Origin gFrontEnd )
				)
				( attribute "SEC" "1"
					( Origin gFrontEnd )
				)
				( attribute "SEC_TYPE" "THMT"
					( Origin gFrontEnd )
				)
				( attribute "VER" "1"
					( Origin gFrontEnd )
				)
				( attribute "XY" "(-3025,2250)"
					( Origin gFrontEnd )
				)
				( attribute "CHIPS_PART_NAME" "CONN12_G98257001"
					( Origin gPackager )
				)
				( attribute "CDS_PART_NAME" "CONN12_G98257001_THMT-CONN,G98A"
					( Origin gPackager )
				)
				( objectStatus "J1E1" )
				( pin "a1"
					( attribute "PN" "A1"
						( Origin gPackager )
					)
					( objectStatus "J1E1.A1" )
				)
				( pin "a2"
					( attribute "PN" "A2"
						( Origin gPackager )
					)
					( objectStatus "J1E1.A2" )
				)
				( pin "a3"
					( attribute "PN" "A3"
						( Origin gPackager )
					)
					( objectStatus "J1E1.A3" )
				)
				( pin "b1"
					( attribute "PN" "B1"
						( Origin gPackager )
					)
					( objectStatus "J1E1.B1" )
				)
				( pin "b2"
					( attribute "PN" "B2"
						( Origin gPackager )
					)
					( objectStatus "J1E1.B2" )
				)
				( pin "b3"
					( attribute "PN" "B3"
						( Origin gPackager )
					)
					( objectStatus "J1E1.B3" )
				)
				( pin "c1"
					( attribute "PN" "C1"
						( Origin gPackager )
					)
					( objectStatus "J1E1.C1" )
				)
				( pin "c2"
					( attribute "PN" "C2"
						( Origin gPackager )
					)
					( objectStatus "J1E1.C2" )
				)
				( pin "c3"
					( attribute "PN" "C3"
						( Origin gPackager )
					)
					( objectStatus "J1E1.C3" )
				)
				( pin "d1"
					( attribute "PN" "D1"
						( Origin gPackager )
					)
					( objectStatus "J1E1.D1" )
				)
				( pin "d2"
					( attribute "PN" "D2"
						( Origin gPackager )
					)
					( objectStatus "J1E1.D2" )
				)
				( pin "d3"
					( attribute "PN" "D3"
						( Origin gPackager )
					)
					( objectStatus "J1E1.D3" )
				)
			)
			( gate "@baseboard_fab2_lib.baseboard_fab2(sch_1):page195_i31"
				( attribute "CDS_LIB" "mstr_discrete"
					( Origin gPackager )
				)
				( attribute "CDS_LOCATION" "C9R5"
					( Origin gPackager )
				)
				( attribute "CDS_SEC" "1"
					( Origin gPackager )
				)
				( attribute "LOCATION" "C9R5"
					( Origin gFrontEnd )
				)
				( attribute "MATERIAL" "X6S"
					( Origin gFrontEnd )
				)
				( attribute "PACK_TYPE" "0805"
					( Origin gFrontEnd )
				)
				( attribute "PART_NUMBER" "C95333-007"
					( Origin gFrontEnd )
				)
				( attribute "PHYS_PAGE" "195"
					( Origin gFrontEnd )
				)
				( attribute "ROOM" "HOT_SWAP"
					( Origin gFrontEnd )
				)
				( attribute "ROT" "0"
					( Origin gFrontEnd )
				)
				( attribute "SEC" "1"
					( Origin gFrontEnd )
				)
				( attribute "SEC_TYPE" "0805"
					( Origin gFrontEnd )
				)
				( attribute "TOLERANCE" "10%"
					( Origin gFrontEnd )
				)
				( attribute "VALUE" "10UF"
					( Origin gFrontEnd )
				)
				( attribute "VER" "1"
					( Origin gFrontEnd )
				)
				( attribute "VOLTAGE" "16V"
					( Units "uVoltage" "V" 1.000000)
					( Origin gFrontEnd )
				)
				( attribute "XY" "(-3700,3675)"
					( Origin gFrontEnd )
				)
				( attribute "CHIPS_PART_NAME" "CAP"
					( Origin gPackager )
				)
				( attribute "CDS_PART_NAME" "CAP_0805-10UF,16V,10%,X6S,C953A"
					( Origin gPackager )
				)
				( objectStatus "C9R5" )
				( pin "a"
					( attribute "PN" "1"
						( Origin gPackager )
					)
					( objectStatus "C9R5.1" )
				)
				( pin "b"
					( attribute "PN" "2"
						( Origin gPackager )
					)
					( objectStatus "C9R5.2" )
				)
			)
			( gate "@baseboard_fab2_lib.baseboard_fab2(sch_1):page195_i32"
				( attribute "CDS_LIB" "mstr_discrete"
					( Origin gPackager )
				)
				( attribute "CDS_LOCATION" "C1E12"
					( Origin gPackager )
				)
				( attribute "CDS_SEC" "1"
					( Origin gPackager )
				)
				( attribute "LOCATION" "C1E12"
					( Origin gFrontEnd )
				)
				( attribute "MATERIAL" "X6S"
					( Origin gFrontEnd )
				)
				( attribute "PACK_TYPE" "0805"
					( Origin gFrontEnd )
				)
				( attribute "PART_NUMBER" "C95333-007"
					( Origin gFrontEnd )
				)
				( attribute "PHYS_PAGE" "195"
					( Origin gFrontEnd )
				)
				( attribute "ROOM" "HOT_SWAP"
					( Origin gFrontEnd )
				)
				( attribute "ROT" "0"
					( Origin gFrontEnd )
				)
				( attribute "SEC" "1"
					( Origin gFrontEnd )
				)
				( attribute "SEC_TYPE" "0805"
					( Origin gFrontEnd )
				)
				( attribute "TOLERANCE" "10%"
					( Origin gFrontEnd )
				)
				( attribute "VALUE" "10UF"
					( Origin gFrontEnd )
				)
				( attribute "VER" "1"
					( Origin gFrontEnd )
				)
				( attribute "VOLTAGE" "16V"
					( Units "uVoltage" "V" 1.000000)
					( Origin gFrontEnd )
				)
				( attribute "XY" "(-3375,3675)"
					( Origin gFrontEnd )
				)
				( attribute "CHIPS_PART_NAME" "CAP"
					( Origin gPackager )
				)
				( attribute "CDS_PART_NAME" "CAP_0805-10UF,16V,10%,X6S,C953A"
					( Origin gPackager )
				)
				( objectStatus "C1E12" )
				( pin "a"
					( attribute "PN" "1"
						( Origin gPackager )
					)
					( objectStatus "C1E12.1" )
				)
				( pin "b"
					( attribute "PN" "2"
						( Origin gPackager )
					)
					( objectStatus "C1E12.2" )
				)
			)
			( gate "@baseboard_fab2_lib.baseboard_fab2(sch_1):page195_i35"
				( attribute "CDS_LIB" "mstr_discrete"
					( Origin gPackager )
				)
				( attribute "CDS_LOCATION" "C1E15"
					( Origin gPackager )
				)
				( attribute "CDS_SEC" "1"
					( Origin gPackager )
				)
				( attribute "LOCATION" "C1E15"
					( Origin gFrontEnd )
				)
				( attribute "MATERIAL" "X6S"
					( Origin gFrontEnd )
				)
				( attribute "PACK_TYPE" "0805"
					( Origin gFrontEnd )
				)
				( attribute "PART_NUMBER" "C95333-007"
					( Origin gFrontEnd )
				)
				( attribute "PHYS_PAGE" "195"
					( Origin gFrontEnd )
				)
				( attribute "ROOM" "HOT_SWAP"
					( Origin gFrontEnd )
				)
				( attribute "ROT" "0"
					( Origin gFrontEnd )
				)
				( attribute "SEC" "1"
					( Origin gFrontEnd )
				)
				( attribute "SEC_TYPE" "0805"
					( Origin gFrontEnd )
				)
				( attribute "TOLERANCE" "10%"
					( Origin gFrontEnd )
				)
				( attribute "VALUE" "10UF"
					( Origin gFrontEnd )
				)
				( attribute "VER" "1"
					( Origin gFrontEnd )
				)
				( attribute "VOLTAGE" "16V"
					( Units "uVoltage" "V" 1.000000)
					( Origin gFrontEnd )
				)
				( attribute "XY" "(-3025,3675)"
					( Origin gFrontEnd )
				)
				( attribute "CHIPS_PART_NAME" "CAP"
					( Origin gPackager )
				)
				( attribute "CDS_PART_NAME" "CAP_0805-10UF,16V,10%,X6S,C953A"
					( Origin gPackager )
				)
				( objectStatus "C1E15" )
				( pin "a"
					( attribute "PN" "1"
						( Origin gPackager )
					)
					( objectStatus "C1E15.1" )
				)
				( pin "b"
					( attribute "PN" "2"
						( Origin gPackager )
					)
					( objectStatus "C1E15.2" )
				)
			)
			( gate "@baseboard_fab2_lib.baseboard_fab2(sch_1):page195_i36"
				( attribute "BOM_COST" "HOT_SWAP"
					( Origin gFrontEnd )
				)
				( attribute "CDS_LIB" "dev_discrete"
					( Origin gPackager )
				)
				( attribute "CDS_LOCATION" "C9R12"
					( Origin gPackager )
				)
				( attribute "CDS_SEC" "1"
					( Origin gPackager )
				)
				( attribute "LOCATION" "C9R12"
					( Origin gFrontEnd )
				)
				( attribute "MATERIAL" "X7R"
					( Origin gFrontEnd )
				)
				( attribute "PACK_TYPE" "0402V"
					( Origin gFrontEnd )
				)
				( attribute "PART_NUMBER" "A36096-030"
					( Origin gFrontEnd )
				)
				( attribute "PHYS_PAGE" "195"
					( Origin gFrontEnd )
				)
				( attribute "ROOM" "HOT_SWAP"
					( Origin gFrontEnd )
				)
				( attribute "ROT" "0"
					( Origin gFrontEnd )
				)
				( attribute "SEC" "1"
					( Origin gFrontEnd )
				)
				( attribute "SEC_TYPE" "0402V"
					( Origin gFrontEnd )
				)
				( attribute "TOLERANCE" "10%"
					( Origin gFrontEnd )
				)
				( attribute "VALUE" "0.1UF"
					( Origin gFrontEnd )
				)
				( attribute "VER" "1"
					( Origin gFrontEnd )
				)
				( attribute "VOLTAGE" "16V"
					( Units "uVoltage" "V" 1.000000)
					( Origin gFrontEnd )
				)
				( attribute "XY" "(-2675,3675)"
					( Origin gFrontEnd )
				)
				( attribute "CHIPS_PART_NAME" "CAP_A"
					( Origin gPackager )
				)
				( attribute "CDS_PART_NAME" "CAP_A_0402V-0.1UF,16V,10%,X7R,A"
					( Origin gPackager )
				)
				( objectStatus "C9R12" )
				( pin "a"
					( attribute "PN" "1"
						( Origin gPackager )
					)
					( objectStatus "C9R12.1" )
				)
				( pin "b"
					( attribute "PN" "2"
						( Origin gPackager )
					)
					( objectStatus "C9R12.2" )
				)
			)
			( gate "@baseboard_fab2_lib.baseboard_fab2(sch_1):page195_i37"
				( attribute "BOM_COST" "HOT_SWAP"
					( Origin gFrontEnd )
				)
				( attribute "CDS_LIB" "dev_discrete"
					( Origin gPackager )
				)
				( attribute "CDS_LOCATION" "C9R6"
					( Origin gPackager )
				)
				( attribute "CDS_SEC" "1"
					( Origin gPackager )
				)
				( attribute "LOCATION" "C9R6"
					( Origin gFrontEnd )
				)
				( attribute "MATERIAL" "X7R"
					( Origin gFrontEnd )
				)
				( attribute "PACK_TYPE" "0402V"
					( Origin gFrontEnd )
				)
				( attribute "PART_NUMBER" "A36096-030"
					( Origin gFrontEnd )
				)
				( attribute "PHYS_PAGE" "195"
					( Origin gFrontEnd )
				)
				( attribute "ROOM" "HOT_SWAP"
					( Origin gFrontEnd )
				)
				( attribute "ROT" "0"
					( Origin gFrontEnd )
				)
				( attribute "SEC" "1"
					( Origin gFrontEnd )
				)
				( attribute "SEC_TYPE" "0402V"
					( Origin gFrontEnd )
				)
				( attribute "TOLERANCE" "10%"
					( Origin gFrontEnd )
				)
				( attribute "VALUE" "0.1UF"
					( Origin gFrontEnd )
				)
				( attribute "VER" "1"
					( Origin gFrontEnd )
				)
				( attribute "VOLTAGE" "16V"
					( Units "uVoltage" "V" 1.000000)
					( Origin gFrontEnd )
				)
				( attribute "XY" "(-2300,3675)"
					( Origin gFrontEnd )
				)
				( attribute "CHIPS_PART_NAME" "CAP_A"
					( Origin gPackager )
				)
				( attribute "CDS_PART_NAME" "CAP_A_0402V-0.1UF,16V,10%,X7R,A"
					( Origin gPackager )
				)
				( objectStatus "C9R6" )
				( pin "a"
					( attribute "PN" "1"
						( Origin gPackager )
					)
					( objectStatus "C9R6.1" )
				)
				( pin "b"
					( attribute "PN" "2"
						( Origin gPackager )
					)
					( objectStatus "C9R6.2" )
				)
			)
			( gate "@baseboard_fab2_lib.baseboard_fab2(sch_1):page195_i38"
				( attribute "BOM_COST" "HOT_SWAP"
					( Origin gFrontEnd )
				)
				( attribute "CDS_LIB" "dev_discrete"
					( Origin gPackager )
				)
				( attribute "CDS_LOCATION" "C1E17"
					( Origin gPackager )
				)
				( attribute "CDS_SEC" "1"
					( Origin gPackager )
				)
				( attribute "LOCATION" "C1E17"
					( Origin gFrontEnd )
				)
				( attribute "MATERIAL" "X7R"
					( Origin gFrontEnd )
				)
				( attribute "PACK_TYPE" "0402V"
					( Origin gFrontEnd )
				)
				( attribute "PART_NUMBER" "A36096-030"
					( Origin gFrontEnd )
				)
				( attribute "PHYS_PAGE" "195"
					( Origin gFrontEnd )
				)
				( attribute "ROOM" "HOT_SWAP"
					( Origin gFrontEnd )
				)
				( attribute "ROT" "0"
					( Origin gFrontEnd )
				)
				( attribute "SEC" "1"
					( Origin gFrontEnd )
				)
				( attribute "SEC_TYPE" "0402V"
					( Origin gFrontEnd )
				)
				( attribute "TOLERANCE" "10%"
					( Origin gFrontEnd )
				)
				( attribute "VALUE" "0.1UF"
					( Origin gFrontEnd )
				)
				( attribute "VER" "1"
					( Origin gFrontEnd )
				)
				( attribute "VOLTAGE" "16V"
					( Units "uVoltage" "V" 1.000000)
					( Origin gFrontEnd )
				)
				( attribute "XY" "(-1950,3675)"
					( Origin gFrontEnd )
				)
				( attribute "CHIPS_PART_NAME" "CAP_A"
					( Origin gPackager )
				)
				( attribute "CDS_PART_NAME" "CAP_A_0402V-0.1UF,16V,10%,X7R,A"
					( Origin gPackager )
				)
				( objectStatus "C1E17" )
				( pin "a"
					( attribute "PN" "1"
						( Origin gPackager )
					)
					( objectStatus "C1E17.1" )
				)
				( pin "b"
					( attribute "PN" "2"
						( Origin gPackager )
					)
					( objectStatus "C1E17.2" )
				)
			)
			( gate "@baseboard_fab2_lib.baseboard_fab2(sch_1):page195_i39"
				( attribute "BOM_COST" "HOT_SWAP"
					( Origin gFrontEnd )
				)
				( attribute "CDS_LIB" "dev_discrete"
					( Origin gPackager )
				)
				( attribute "CDS_LOCATION" "C1E16"
					( Origin gPackager )
				)
				( attribute "CDS_SEC" "1"
					( Origin gPackager )
				)
				( attribute "LOCATION" "C1E16"
					( Origin gFrontEnd )
				)
				( attribute "MATERIAL" "X7R"
					( Origin gFrontEnd )
				)
				( attribute "PACK_TYPE" "0402V"
					( Origin gFrontEnd )
				)
				( attribute "PART_NUMBER" "A36096-030"
					( Origin gFrontEnd )
				)
				( attribute "PHYS_PAGE" "195"
					( Origin gFrontEnd )
				)
				( attribute "ROOM" "HOT_SWAP"
					( Origin gFrontEnd )
				)
				( attribute "ROT" "0"
					( Origin gFrontEnd )
				)
				( attribute "SEC" "1"
					( Origin gFrontEnd )
				)
				( attribute "SEC_TYPE" "0402V"
					( Origin gFrontEnd )
				)
				( attribute "TOLERANCE" "10%"
					( Origin gFrontEnd )
				)
				( attribute "VALUE" "0.1UF"
					( Origin gFrontEnd )
				)
				( attribute "VER" "1"
					( Origin gFrontEnd )
				)
				( attribute "VOLTAGE" "16V"
					( Units "uVoltage" "V" 1.000000)
					( Origin gFrontEnd )
				)
				( attribute "XY" "(-1625,3675)"
					( Origin gFrontEnd )
				)
				( attribute "CHIPS_PART_NAME" "CAP_A"
					( Origin gPackager )
				)
				( attribute "CDS_PART_NAME" "CAP_A_0402V-0.1UF,16V,10%,X7R,A"
					( Origin gPackager )
				)
				( objectStatus "C1E16" )
				( pin "a"
					( attribute "PN" "1"
						( Origin gPackager )
					)
					( objectStatus "C1E16.1" )
				)
				( pin "b"
					( attribute "PN" "2"
						( Origin gPackager )
					)
					( objectStatus "C1E16.2" )
				)
			)
			( gate "@baseboard_fab2_lib.baseboard_fab2(sch_1):page195_i49"
				( attribute "BOM_COST" "TEST_MFG"
					( Origin gFrontEnd )
				)
				( attribute "CDS_LIB" "mstr_misc"
					( Origin gPackager )
				)
				( attribute "CDS_LOCATION" "TH4G1"
					( Origin gPackager )
				)
				( attribute "CDS_SEC" "1"
					( Origin gPackager )
				)
				( attribute "LOCATION" "TH4G1"
					( Origin gFrontEnd )
				)
				( attribute "MATERIAL" "EMPTY"
					( Origin gFrontEnd )
				)
				( attribute "PACK_TYPE" "TH"
					( Origin gFrontEnd )
				)
				( attribute "PART_NUMBER" "NA"
					( Origin gFrontEnd )
				)
				( attribute "PHYS_PAGE" "195"
					( Origin gFrontEnd )
				)
				( attribute "ROOM" "MOUNTING_HOLES"
					( Origin gFrontEnd )
				)
				( attribute "ROT" "0"
					( Origin gFrontEnd )
				)
				( attribute "SEC" "1"
					( Origin gPackager )
				)
				( attribute "VER" "1"
					( Origin gFrontEnd )
				)
				( attribute "XY" "(-6475,4725)"
					( Origin gFrontEnd )
				)
				( attribute "CHIPS_PART_NAME" "MTG_KEYHOLE"
					( Origin gPackager )
				)
				( attribute "CDS_PART_NAME" "MTG_KEYHOLE_TH-EMPTY,NA"
					( Origin gPackager )
				)
				( objectStatus "TH4G1" )
				( pin "\1\"
					( attribute "PN" "1"
						( Origin gPackager )
					)
					( objectStatus "TH4G1.1" )
				)
			)
			( gate "@baseboard_fab2_lib.baseboard_fab2(sch_1):page195_i52"
				( attribute "BOM_COST" "TEST_MFG"
					( Origin gFrontEnd )
				)
				( attribute "CDS_LIB" "mstr_misc"
					( Origin gPackager )
				)
				( attribute "CDS_LOCATION" "TH9G1"
					( Origin gPackager )
				)
				( attribute "CDS_SEC" "1"
					( Origin gPackager )
				)
				( attribute "LOCATION" "TH9G1"
					( Origin gFrontEnd )
				)
				( attribute "MATERIAL" "EMPTY"
					( Origin gFrontEnd )
				)
				( attribute "PACK_TYPE" "TH"
					( Origin gFrontEnd )
				)
				( attribute "PART_NUMBER" "NA"
					( Origin gFrontEnd )
				)
				( attribute "PHYS_PAGE" "195"
					( Origin gFrontEnd )
				)
				( attribute "ROOM" "MOUNTING_HOLES"
					( Origin gFrontEnd )
				)
				( attribute "ROT" "0"
					( Origin gFrontEnd )
				)
				( attribute "SEC" "1"
					( Origin gPackager )
				)
				( attribute "VER" "1"
					( Origin gFrontEnd )
				)
				( attribute "XY" "(-6425,4125)"
					( Origin gFrontEnd )
				)
				( attribute "CHIPS_PART_NAME" "MTG_KEYHOLE"
					( Origin gPackager )
				)
				( attribute "CDS_PART_NAME" "MTG_KEYHOLE_TH-EMPTY,NA"
					( Origin gPackager )
				)
				( objectStatus "TH9G1" )
				( pin "\1\"
					( attribute "PN" "1"
						( Origin gPackager )
					)
					( objectStatus "TH9G1.1" )
				)
			)
			( gate "@baseboard_fab2_lib.baseboard_fab2(sch_1):page195_i54"
				( attribute "BOM_COST" "TEST_MFG"
					( Origin gFrontEnd )
				)
				( attribute "CDS_LIB" "mstr_misc"
					( Origin gPackager )
				)
				( attribute "CDS_LOCATION" "TH9A1"
					( Origin gPackager )
				)
				( attribute "CDS_SEC" "1"
					( Origin gPackager )
				)
				( attribute "LOCATION" "TH9A1"
					( Origin gFrontEnd )
				)
				( attribute "MATERIAL" "EMPTY"
					( Origin gFrontEnd )
				)
				( attribute "PACK_TYPE" "TH"
					( Origin gFrontEnd )
				)
				( attribute "PART_NUMBER" "NA"
					( Origin gFrontEnd )
				)
				( attribute "PHYS_PAGE" "195"
					( Origin gFrontEnd )
				)
				( attribute "ROOM" "MOUNTING_HOLES"
					( Origin gFrontEnd )
				)
				( attribute "ROT" "0"
					( Origin gFrontEnd )
				)
				( attribute "SEC" "1"
					( Origin gPackager )
				)
				( attribute "VER" "1"
					( Origin gFrontEnd )
				)
				( attribute "XY" "(-4600,4725)"
					( Origin gFrontEnd )
				)
				( attribute "CHIPS_PART_NAME" "MTG_KEYHOLE"
					( Origin gPackager )
				)
				( attribute "CDS_PART_NAME" "MTG_KEYHOLE_TH-EMPTY,NA"
					( Origin gPackager )
				)
				( objectStatus "TH9A1" )
				( pin "\1\"
					( attribute "PN" "1"
						( Origin gPackager )
					)
					( objectStatus "TH9A1.1" )
				)
			)
			( gate "@baseboard_fab2_lib.baseboard_fab2(sch_1):page195_i56"
				( attribute "BOM_COST" "TEST_MFG"
					( Origin gFrontEnd )
				)
				( attribute "CDS_LIB" "mstr_misc"
					( Origin gPackager )
				)
				( attribute "CDS_LOCATION" "TH1A1"
					( Origin gPackager )
				)
				( attribute "CDS_SEC" "1"
					( Origin gPackager )
				)
				( attribute "LOCATION" "TH1A1"
					( Origin gFrontEnd )
				)
				( attribute "MATERIAL" "EMPTY"
					( Origin gFrontEnd )
				)
				( attribute "PACK_TYPE" "TH"
					( Origin gFrontEnd )
				)
				( attribute "PART_NUMBER" "NA"
					( Origin gFrontEnd )
				)
				( attribute "PHYS_PAGE" "195"
					( Origin gFrontEnd )
				)
				( attribute "ROOM" "MOUNTING_HOLES"
					( Origin gFrontEnd )
				)
				( attribute "ROT" "0"
					( Origin gFrontEnd )
				)
				( attribute "SEC" "1"
					( Origin gPackager )
				)
				( attribute "VER" "1"
					( Origin gFrontEnd )
				)
				( attribute "XY" "(-5525,4725)"
					( Origin gFrontEnd )
				)
				( attribute "CHIPS_PART_NAME" "MTG_KEYHOLE"
					( Origin gPackager )
				)
				( attribute "CDS_PART_NAME" "MTG_KEYHOLE_TH-EMPTY,NA"
					( Origin gPackager )
				)
				( objectStatus "TH1A1" )
				( pin "\1\"
					( attribute "PN" "1"
						( Origin gPackager )
					)
					( objectStatus "TH1A1.1" )
				)
			)
			( gate "@baseboard_fab2_lib.baseboard_fab2(sch_1):page195_i62"
				( attribute "BOM_COST" "TEST_MFG"
					( Origin gFrontEnd )
				)
				( attribute "CDS_LIB" "mstr_misc"
					( Origin gPackager )
				)
				( attribute "CDS_LOCATION" "TH4A1"
					( Origin gPackager )
				)
				( attribute "CDS_SEC" "1"
					( Origin gPackager )
				)
				( attribute "LOCATION" "TH4A1"
					( Origin gFrontEnd )
				)
				( attribute "MATERIAL" "EMPTY"
					( Origin gFrontEnd )
				)
				( attribute "PACK_TYPE" "TH"
					( Origin gFrontEnd )
				)
				( attribute "PART_NUMBER" "NA"
					( Origin gFrontEnd )
				)
				( attribute "PHYS_PAGE" "195"
					( Origin gFrontEnd )
				)
				( attribute "ROOM" "MOUNTING_HOLES"
					( Origin gFrontEnd )
				)
				( attribute "ROT" "0"
					( Origin gFrontEnd )
				)
				( attribute "SEC" "1"
					( Origin gPackager )
				)
				( attribute "VER" "1"
					( Origin gFrontEnd )
				)
				( attribute "XY" "(-7350,4125)"
					( Origin gFrontEnd )
				)
				( attribute "CHIPS_PART_NAME" "MTG_KEYHOLE"
					( Origin gPackager )
				)
				( attribute "CDS_PART_NAME" "MTG_KEYHOLE_TH-EMPTY,NA"
					( Origin gPackager )
				)
				( objectStatus "TH4A1" )
				( pin "\1\"
					( attribute "PN" "1"
						( Origin gPackager )
					)
					( objectStatus "TH4A1.1" )
				)
			)
			( gate "@baseboard_fab2_lib.baseboard_fab2(sch_1):page195_i65"
				( attribute "BOM_COST" "TEST_MFG"
					( Origin gFrontEnd )
				)
				( attribute "CDS_LIB" "mstr_misc"
					( Origin gPackager )
				)
				( attribute "CDS_LOCATION" "TH7A1"
					( Origin gPackager )
				)
				( attribute "CDS_SEC" "1"
					( Origin gPackager )
				)
				( attribute "LOCATION" "TH7A1"
					( Origin gFrontEnd )
				)
				( attribute "MATERIAL" "EMPTY"
					( Origin gFrontEnd )
				)
				( attribute "PACK_TYPE" "TH"
					( Origin gFrontEnd )
				)
				( attribute "PART_NUMBER" "NA"
					( Origin gFrontEnd )
				)
				( attribute "PHYS_PAGE" "195"
					( Origin gFrontEnd )
				)
				( attribute "ROOM" "MOUNTING_HOLES"
					( Origin gFrontEnd )
				)
				( attribute "ROT" "0"
					( Origin gFrontEnd )
				)
				( attribute "SEC" "1"
					( Origin gPackager )
				)
				( attribute "VER" "1"
					( Origin gFrontEnd )
				)
				( attribute "XY" "(-5525,4150)"
					( Origin gFrontEnd )
				)
				( attribute "CHIPS_PART_NAME" "MTG_KEYHOLE"
					( Origin gPackager )
				)
				( attribute "CDS_PART_NAME" "MTG_KEYHOLE_TH-EMPTY,NA"
					( Origin gPackager )
				)
				( objectStatus "TH7A1" )
				( pin "\1\"
					( attribute "PN" "1"
						( Origin gPackager )
					)
					( objectStatus "TH7A1.1" )
				)
			)
			( gate "@baseboard_fab2_lib.baseboard_fab2(sch_1):page195_i67"
				( attribute "BOM_COST" "TEST_MFG"
					( Origin gFrontEnd )
				)
				( attribute "CDS_LIB" "mstr_misc"
					( Origin gPackager )
				)
				( attribute "CDS_LOCATION" "TH7G1"
					( Origin gPackager )
				)
				( attribute "CDS_SEC" "1"
					( Origin gPackager )
				)
				( attribute "LOCATION" "TH7G1"
					( Origin gFrontEnd )
				)
				( attribute "MATERIAL" "EMPTY"
					( Origin gFrontEnd )
				)
				( attribute "PACK_TYPE" "TH"
					( Origin gFrontEnd )
				)
				( attribute "PART_NUMBER" "NA"
					( Origin gFrontEnd )
				)
				( attribute "PHYS_PAGE" "195"
					( Origin gFrontEnd )
				)
				( attribute "ROOM" "MOUNTING_HOLES"
					( Origin gFrontEnd )
				)
				( attribute "ROT" "0"
					( Origin gFrontEnd )
				)
				( attribute "SEC" "1"
					( Origin gPackager )
				)
				( attribute "VER" "1"
					( Origin gFrontEnd )
				)
				( attribute "XY" "(-4600,4150)"
					( Origin gFrontEnd )
				)
				( attribute "CHIPS_PART_NAME" "MTG_KEYHOLE"
					( Origin gPackager )
				)
				( attribute "CDS_PART_NAME" "MTG_KEYHOLE_TH-EMPTY,NA"
					( Origin gPackager )
				)
				( objectStatus "TH7G1" )
				( pin "\1\"
					( attribute "PN" "1"
						( Origin gPackager )
					)
					( objectStatus "TH7G1.1" )
				)
			)
			( gate "@baseboard_fab2_lib.baseboard_fab2(sch_1):page195_i76"
				( attribute "BOM_COST" "TEST_MFG"
					( Origin gFrontEnd )
				)
				( attribute "CDS_LIB" "mstr_misc"
					( Origin gPackager )
				)
				( attribute "CDS_LOCATION" "RM1G1"
					( Origin gPackager )
				)
				( attribute "LOCATION" "RM1G1"
					( Origin gFrontEnd )
				)
				( attribute "MATERIAL" "HDW"
					( Origin gFrontEnd )
				)
				( attribute "PACK_TYPE" "TH"
					( Origin gFrontEnd )
				)
				( attribute "PART_NUMBER" "H57868-001"
					( Origin gFrontEnd )
				)
				( attribute "PHYS_PAGE" "195"
					( Origin gFrontEnd )
				)
				( attribute "ROOM" "MOUNTING_HOLES"
					( Origin gFrontEnd )
				)
				( attribute "ROT" "0"
					( Origin gFrontEnd )
				)
				( attribute "VER" "1"
					( Origin gFrontEnd )
				)
				( attribute "XY" "(-7500,4725)"
					( Origin gFrontEnd )
				)
				( attribute "CHIPS_PART_NAME" "CAPTIVE_SCREW"
					( Origin gPackager )
				)
				( attribute "CDS_PART_NAME" "CAPTIVE_SCREW_TH-HDW,H57868-001"
					( Origin gPackager )
				)
				( objectStatus "RM1G1" )
			)
			( gate "@baseboard_fab2_lib.baseboard_fab2(sch_1):page195_i78"
				( attribute "CDS_LIB" "mstr_conn"
					( Origin gPackager )
				)
				( attribute "CDS_LMAN_SYM_OUTLINE" "-200,250,200,-250"
					( Origin gPackager )
				)
				( attribute "CDS_LOCATION" "J1D1"
					( Origin gPackager )
				)
				( attribute "CDS_SEC" "1"
					( Origin gPackager )
				)
				( attribute "LOCATION" "J1D1"
					( Origin gFrontEnd )
				)
				( attribute "MATERIAL" "CONN"
					( Origin gFrontEnd )
				)
				( attribute "PACK_TYPE" "THMT"
					( Origin gFrontEnd )
				)
				( attribute "PART_NUMBER" "G98257-001"
					( Origin gFrontEnd )
				)
				( attribute "PHYS_PAGE" "195"
					( Origin gFrontEnd )
				)
				( attribute "ROOM" "HOT_SWAP"
					( Origin gFrontEnd )
				)
				( attribute "ROT" "0"
					( Origin gFrontEnd )
				)
				( attribute "SEC" "1"
					( Origin gFrontEnd )
				)
				( attribute "SEC_TYPE" "THMT"
					( Origin gFrontEnd )
				)
				( attribute "VER" "1"
					( Origin gFrontEnd )
				)
				( attribute "XY" "(-1250,2275)"
					( Origin gFrontEnd )
				)
				( attribute "CHIPS_PART_NAME" "CONN12_G98257001"
					( Origin gPackager )
				)
				( attribute "CDS_PART_NAME" "CONN12_G98257001_THMT-CONN,G98A"
					( Origin gPackager )
				)
				( objectStatus "J1D1" )
				( pin "a1"
					( attribute "PN" "A1"
						( Origin gPackager )
					)
					( objectStatus "J1D1.A1" )
				)
				( pin "a2"
					( attribute "PN" "A2"
						( Origin gPackager )
					)
					( objectStatus "J1D1.A2" )
				)
				( pin "a3"
					( attribute "PN" "A3"
						( Origin gPackager )
					)
					( objectStatus "J1D1.A3" )
				)
				( pin "b1"
					( attribute "PN" "B1"
						( Origin gPackager )
					)
					( objectStatus "J1D1.B1" )
				)
				( pin "b2"
					( attribute "PN" "B2"
						( Origin gPackager )
					)
					( objectStatus "J1D1.B2" )
				)
				( pin "b3"
					( attribute "PN" "B3"
						( Origin gPackager )
					)
					( objectStatus "J1D1.B3" )
				)
				( pin "c1"
					( attribute "PN" "C1"
						( Origin gPackager )
					)
					( objectStatus "J1D1.C1" )
				)
				( pin "c2"
					( attribute "PN" "C2"
						( Origin gPackager )
					)
					( objectStatus "J1D1.C2" )
				)
				( pin "c3"
					( attribute "PN" "C3"
						( Origin gPackager )
					)
					( objectStatus "J1D1.C3" )
				)
				( pin "d1"
					( attribute "PN" "D1"
						( Origin gPackager )
					)
					( objectStatus "J1D1.D1" )
				)
				( pin "d2"
					( attribute "PN" "D2"
						( Origin gPackager )
					)
					( objectStatus "J1D1.D2" )
				)
				( pin "d3"
					( attribute "PN" "D3"
						( Origin gPackager )
					)
					( objectStatus "J1D1.D3" )
				)
			)
			( gate "@baseboard_fab2_lib.baseboard_fab2(sch_1):page195_i82"
				( attribute "CDS_LIB" "mstr_discrete"
					( Origin gPackager )
				)
				( attribute "CDS_LOCATION" "C4F6"
					( Origin gPackager )
				)
				( attribute "CDS_SEC" "1"
					( Origin gPackager )
				)
				( attribute "LOCATION" "C4F6"
					( Origin gFrontEnd )
				)
				( attribute "MATERIAL" "ALUM"
					( Origin gFrontEnd )
				)
				( attribute "PACK_TYPE" "4040LF"
					( Origin gFrontEnd )
				)
				( attribute "PART_NUMBER" "A93539-036"
					( Origin gFrontEnd )
				)
				( attribute "PHYS_PAGE" "195"
					( Origin gFrontEnd )
				)
				( attribute "ROT" "0"
					( Origin gFrontEnd )
				)
				( attribute "SEC" "1"
					( Origin gPackager )
				)
				( attribute "TOLERANCE" "20%"
					( Origin gFrontEnd )
				)
				( attribute "VALUE" "470UF"
					( Origin gFrontEnd )
				)
				( attribute "VER" "1"
					( Origin gFrontEnd )
				)
				( attribute "VOLTAGE" "16V"
					( Units "uVoltage" "V" 1.000000)
					( Origin gFrontEnd )
				)
				( attribute "XY" "(-7175,2950)"
					( Origin gFrontEnd )
				)
				( attribute "CHIPS_PART_NAME" "CAPP"
					( Origin gPackager )
				)
				( attribute "CDS_PART_NAME" "CAPP_4040LF-470UF,16V,20%,ALUMA"
					( Origin gPackager )
				)
				( objectStatus "C4F6" )
				( pin "a"
					( attribute "PN" "1"
						( Origin gPackager )
					)
					( objectStatus "C4F6.1" )
				)
				( pin "b"
					( attribute "PN" "2"
						( Origin gPackager )
					)
					( objectStatus "C4F6.2" )
				)
			)
			( gate "@baseboard_fab2_lib.baseboard_fab2(sch_1):page195_i83"
				( attribute "CDS_LIB" "mstr_discrete"
					( Origin gPackager )
				)
				( attribute "CDS_LOCATION" "C4B13"
					( Origin gPackager )
				)
				( attribute "CDS_SEC" "1"
					( Origin gPackager )
				)
				( attribute "LOCATION" "C4B13"
					( Origin gFrontEnd )
				)
				( attribute "MATERIAL" "ALUM"
					( Origin gFrontEnd )
				)
				( attribute "PACK_TYPE" "4040LF"
					( Origin gFrontEnd )
				)
				( attribute "PART_NUMBER" "A93539-036"
					( Origin gFrontEnd )
				)
				( attribute "PHYS_PAGE" "195"
					( Origin gFrontEnd )
				)
				( attribute "ROT" "0"
					( Origin gFrontEnd )
				)
				( attribute "SEC" "1"
					( Origin gPackager )
				)
				( attribute "TOLERANCE" "20%"
					( Origin gFrontEnd )
				)
				( attribute "VALUE" "470UF"
					( Origin gFrontEnd )
				)
				( attribute "VER" "1"
					( Origin gFrontEnd )
				)
				( attribute "VOLTAGE" "16V"
					( Units "uVoltage" "V" 1.000000)
					( Origin gFrontEnd )
				)
				( attribute "XY" "(-6675,2950)"
					( Origin gFrontEnd )
				)
				( attribute "CHIPS_PART_NAME" "CAPP"
					( Origin gPackager )
				)
				( attribute "CDS_PART_NAME" "CAPP_4040LF-470UF,16V,20%,ALUMA"
					( Origin gPackager )
				)
				( objectStatus "C4B13" )
				( pin "a"
					( attribute "PN" "1"
						( Origin gPackager )
					)
					( objectStatus "C4B13.1" )
				)
				( pin "b"
					( attribute "PN" "2"
						( Origin gPackager )
					)
					( objectStatus "C4B13.2" )
				)
			)
			( gate "@baseboard_fab2_lib.baseboard_fab2(sch_1):page195_i84"
				( attribute "CDS_LIB" "mstr_discrete"
					( Origin gPackager )
				)
				( attribute "CDS_LOCATION" "C1B14"
					( Origin gPackager )
				)
				( attribute "CDS_SEC" "1"
					( Origin gPackager )
				)
				( attribute "LOCATION" "C1B14"
					( Origin gFrontEnd )
				)
				( attribute "MATERIAL" "ALUM"
					( Origin gFrontEnd )
				)
				( attribute "PACK_TYPE" "4040LF"
					( Origin gFrontEnd )
				)
				( attribute "PART_NUMBER" "A93539-036"
					( Origin gFrontEnd )
				)
				( attribute "PHYS_PAGE" "195"
					( Origin gFrontEnd )
				)
				( attribute "ROT" "0"
					( Origin gFrontEnd )
				)
				( attribute "SEC" "1"
					( Origin gPackager )
				)
				( attribute "TOLERANCE" "20%"
					( Origin gFrontEnd )
				)
				( attribute "VALUE" "470UF"
					( Origin gFrontEnd )
				)
				( attribute "VER" "1"
					( Origin gFrontEnd )
				)
				( attribute "VOLTAGE" "16V"
					( Units "uVoltage" "V" 1.000000)
					( Origin gFrontEnd )
				)
				( attribute "XY" "(-6150,2925)"
					( Origin gFrontEnd )
				)
				( attribute "CHIPS_PART_NAME" "CAPP"
					( Origin gPackager )
				)
				( attribute "CDS_PART_NAME" "CAPP_4040LF-470UF,16V,20%,ALUMA"
					( Origin gPackager )
				)
				( objectStatus "C1B14" )
				( pin "a"
					( attribute "PN" "1"
						( Origin gPackager )
					)
					( objectStatus "C1B14.1" )
				)
				( pin "b"
					( attribute "PN" "2"
						( Origin gPackager )
					)
					( objectStatus "C1B14.2" )
				)
			)
			( gate "@baseboard_fab2_lib.baseboard_fab2(sch_1):page195_i85"
				( attribute "CDS_LIB" "mstr_discrete"
					( Origin gPackager )
				)
				( attribute "CDS_LOCATION" "C1F7"
					( Origin gPackager )
				)
				( attribute "CDS_SEC" "1"
					( Origin gPackager )
				)
				( attribute "LOCATION" "C1F7"
					( Origin gFrontEnd )
				)
				( attribute "MATERIAL" "ALUM"
					( Origin gFrontEnd )
				)
				( attribute "PACK_TYPE" "4040LF"
					( Origin gFrontEnd )
				)
				( attribute "PART_NUMBER" "A93539-036"
					( Origin gFrontEnd )
				)
				( attribute "PHYS_PAGE" "195"
					( Origin gFrontEnd )
				)
				( attribute "ROT" "0"
					( Origin gFrontEnd )
				)
				( attribute "SEC" "1"
					( Origin gPackager )
				)
				( attribute "TOLERANCE" "20%"
					( Origin gFrontEnd )
				)
				( attribute "VALUE" "470UF"
					( Origin gFrontEnd )
				)
				( attribute "VER" "1"
					( Origin gFrontEnd )
				)
				( attribute "VOLTAGE" "16V"
					( Units "uVoltage" "V" 1.000000)
					( Origin gFrontEnd )
				)
				( attribute "XY" "(-5650,2900)"
					( Origin gFrontEnd )
				)
				( attribute "CHIPS_PART_NAME" "CAPP"
					( Origin gPackager )
				)
				( attribute "CDS_PART_NAME" "CAPP_4040LF-470UF,16V,20%,ALUMA"
					( Origin gPackager )
				)
				( objectStatus "C1F7" )
				( pin "a"
					( attribute "PN" "1"
						( Origin gPackager )
					)
					( objectStatus "C1F7.1" )
				)
				( pin "b"
					( attribute "PN" "2"
						( Origin gPackager )
					)
					( objectStatus "C1F7.2" )
				)
			)
			( gate "@baseboard_fab2_lib.baseboard_fab2(sch_1):page195_i96"
				( attribute "CDS_LIB" "mstr_discrete"
					( Origin gPackager )
				)
				( attribute "CDS_LOCATION" "C4F5"
					( Origin gPackager )
				)
				( attribute "CDS_SEC" "1"
					( Origin gPackager )
				)
				( attribute "LOCATION" "C4F5"
					( Origin gFrontEnd )
				)
				( attribute "MATERIAL" "TANT"
					( Origin gFrontEnd )
				)
				( attribute "PACK_TYPE" "3018"
					( Origin gFrontEnd )
				)
				( attribute "PART_NUMBER" "724613-112"
					( Origin gFrontEnd )
				)
				( attribute "PHYS_PAGE" "195"
					( Origin gFrontEnd )
				)
				( attribute "ROT" "0"
					( Origin gFrontEnd )
				)
				( attribute "SEC" "1"
					( Origin gPackager )
				)
				( attribute "TOLERANCE" "20%"
					( Origin gFrontEnd )
				)
				( attribute "VALUE" "68UF"
					( Origin gFrontEnd )
				)
				( attribute "VER" "1"
					( Origin gFrontEnd )
				)
				( attribute "VOLTAGE" "16V"
					( Units "uVoltage" "V" 1.000000)
					( Origin gFrontEnd )
				)
				( attribute "XY" "(-7275,775)"
					( Origin gFrontEnd )
				)
				( attribute "CHIPS_PART_NAME" "CAPP"
					( Origin gPackager )
				)
				( attribute "CDS_PART_NAME" "CAPP_3018-68UF,16V,20%,TANT,72A"
					( Origin gPackager )
				)
				( objectStatus "C4F5" )
				( pin "a"
					( attribute "PN" "1"
						( Origin gPackager )
					)
					( objectStatus "C4F5.1" )
				)
				( pin "b"
					( attribute "PN" "2"
						( Origin gPackager )
					)
					( objectStatus "C4F5.2" )
				)
			)
			( gate "@baseboard_fab2_lib.baseboard_fab2(sch_1):page195_i97"
				( attribute "CDS_LIB" "mstr_discrete"
					( Origin gPackager )
				)
				( attribute "CDS_LOCATION" "C4B14"
					( Origin gPackager )
				)
				( attribute "CDS_SEC" "1"
					( Origin gPackager )
				)
				( attribute "LOCATION" "C4B14"
					( Origin gFrontEnd )
				)
				( attribute "MATERIAL" "TANT"
					( Origin gFrontEnd )
				)
				( attribute "PACK_TYPE" "3018"
					( Origin gFrontEnd )
				)
				( attribute "PART_NUMBER" "724613-112"
					( Origin gFrontEnd )
				)
				( attribute "PHYS_PAGE" "195"
					( Origin gFrontEnd )
				)
				( attribute "ROT" "0"
					( Origin gFrontEnd )
				)
				( attribute "SEC" "1"
					( Origin gPackager )
				)
				( attribute "TOLERANCE" "20%"
					( Origin gFrontEnd )
				)
				( attribute "VALUE" "68UF"
					( Origin gFrontEnd )
				)
				( attribute "VER" "1"
					( Origin gFrontEnd )
				)
				( attribute "VOLTAGE" "16V"
					( Units "uVoltage" "V" 1.000000)
					( Origin gFrontEnd )
				)
				( attribute "XY" "(-6900,775)"
					( Origin gFrontEnd )
				)
				( attribute "CHIPS_PART_NAME" "CAPP"
					( Origin gPackager )
				)
				( attribute "CDS_PART_NAME" "CAPP_3018-68UF,16V,20%,TANT,72A"
					( Origin gPackager )
				)
				( objectStatus "C4B14" )
				( pin "a"
					( attribute "PN" "1"
						( Origin gPackager )
					)
					( objectStatus "C4B14.1" )
				)
				( pin "b"
					( attribute "PN" "2"
						( Origin gPackager )
					)
					( objectStatus "C4B14.2" )
				)
			)
			( gate "@baseboard_fab2_lib.baseboard_fab2(sch_1):page195_i98"
				( attribute "CDS_LIB" "mstr_discrete"
					( Origin gPackager )
				)
				( attribute "CDS_LOCATION" "C3T6"
					( Origin gPackager )
				)
				( attribute "CDS_SEC" "1"
					( Origin gPackager )
				)
				( attribute "LOCATION" "C3T6"
					( Origin gFrontEnd )
				)
				( attribute "MATERIAL" "TANT"
					( Origin gFrontEnd )
				)
				( attribute "PACK_TYPE" "3018"
					( Origin gFrontEnd )
				)
				( attribute "PART_NUMBER" "724613-112"
					( Origin gFrontEnd )
				)
				( attribute "PHYS_PAGE" "195"
					( Origin gFrontEnd )
				)
				( attribute "ROT" "0"
					( Origin gFrontEnd )
				)
				( attribute "SEC" "1"
					( Origin gPackager )
				)
				( attribute "TOLERANCE" "20%"
					( Origin gFrontEnd )
				)
				( attribute "VALUE" "68UF"
					( Origin gFrontEnd )
				)
				( attribute "VER" "1"
					( Origin gFrontEnd )
				)
				( attribute "VOLTAGE" "16V"
					( Units "uVoltage" "V" 1.000000)
					( Origin gFrontEnd )
				)
				( attribute "XY" "(-5300,750)"
					( Origin gFrontEnd )
				)
				( attribute "CHIPS_PART_NAME" "CAPP"
					( Origin gPackager )
				)
				( attribute "CDS_PART_NAME" "CAPP_3018-68UF,16V,20%,TANT,72A"
					( Origin gPackager )
				)
				( objectStatus "C3T6" )
				( pin "a"
					( attribute "PN" "1"
						( Origin gPackager )
					)
					( objectStatus "C3T6.1" )
				)
				( pin "b"
					( attribute "PN" "2"
						( Origin gPackager )
					)
					( objectStatus "C3T6.2" )
				)
			)
			( gate "@baseboard_fab2_lib.baseboard_fab2(sch_1):page195_i99"
				( attribute "CDS_LIB" "mstr_discrete"
					( Origin gPackager )
				)
				( attribute "CDS_LOCATION" "C9M3"
					( Origin gPackager )
				)
				( attribute "CDS_SEC" "1"
					( Origin gPackager )
				)
				( attribute "LOCATION" "C9M3"
					( Origin gFrontEnd )
				)
				( attribute "MATERIAL" "TANT"
					( Origin gFrontEnd )
				)
				( attribute "PACK_TYPE" "3018"
					( Origin gFrontEnd )
				)
				( attribute "PART_NUMBER" "724613-112"
					( Origin gFrontEnd )
				)
				( attribute "PHYS_PAGE" "195"
					( Origin gFrontEnd )
				)
				( attribute "ROT" "0"
					( Origin gFrontEnd )
				)
				( attribute "SEC" "1"
					( Origin gPackager )
				)
				( attribute "TOLERANCE" "20%"
					( Origin gFrontEnd )
				)
				( attribute "VALUE" "68UF"
					( Origin gFrontEnd )
				)
				( attribute "VER" "1"
					( Origin gFrontEnd )
				)
				( attribute "VOLTAGE" "16V"
					( Units "uVoltage" "V" 1.000000)
					( Origin gFrontEnd )
				)
				( attribute "XY" "(-5750,775)"
					( Origin gFrontEnd )
				)
				( attribute "CHIPS_PART_NAME" "CAPP"
					( Origin gPackager )
				)
				( attribute "CDS_PART_NAME" "CAPP_3018-68UF,16V,20%,TANT,72A"
					( Origin gPackager )
				)
				( objectStatus "C9M3" )
				( pin "a"
					( attribute "PN" "1"
						( Origin gPackager )
					)
					( objectStatus "C9M3.1" )
				)
				( pin "b"
					( attribute "PN" "2"
						( Origin gPackager )
					)
					( objectStatus "C9M3.2" )
				)
			)
			( gate "@baseboard_fab2_lib.baseboard_fab2(sch_1):page195_i100"
				( attribute "CDS_LIB" "mstr_discrete"
					( Origin gPackager )
				)
				( attribute "CDS_LOCATION" "C3B6"
					( Origin gPackager )
				)
				( attribute "CDS_SEC" "1"
					( Origin gPackager )
				)
				( attribute "LOCATION" "C3B6"
					( Origin gFrontEnd )
				)
				( attribute "MATERIAL" "TANT"
					( Origin gFrontEnd )
				)
				( attribute "PACK_TYPE" "3018"
					( Origin gFrontEnd )
				)
				( attribute "PART_NUMBER" "724613-112"
					( Origin gFrontEnd )
				)
				( attribute "PHYS_PAGE" "195"
					( Origin gFrontEnd )
				)
				( attribute "ROT" "0"
					( Origin gFrontEnd )
				)
				( attribute "SEC" "1"
					( Origin gPackager )
				)
				( attribute "TOLERANCE" "20%"
					( Origin gFrontEnd )
				)
				( attribute "VALUE" "68UF"
					( Origin gFrontEnd )
				)
				( attribute "VER" "1"
					( Origin gFrontEnd )
				)
				( attribute "VOLTAGE" "16V"
					( Units "uVoltage" "V" 1.000000)
					( Origin gFrontEnd )
				)
				( attribute "XY" "(-7700,775)"
					( Origin gFrontEnd )
				)
				( attribute "CHIPS_PART_NAME" "CAPP"
					( Origin gPackager )
				)
				( attribute "CDS_PART_NAME" "CAPP_3018-68UF,16V,20%,TANT,72A"
					( Origin gPackager )
				)
				( objectStatus "C3B6" )
				( pin "a"
					( attribute "PN" "1"
						( Origin gPackager )
					)
					( objectStatus "C3B6.1" )
				)
				( pin "b"
					( attribute "PN" "2"
						( Origin gPackager )
					)
					( objectStatus "C3B6.2" )
				)
			)
			( gate "@baseboard_fab2_lib.baseboard_fab2(sch_1):page195_i101"
				( attribute "CDS_LIB" "mstr_discrete"
					( Origin gPackager )
				)
				( attribute "CDS_LOCATION" "C1R23"
					( Origin gPackager )
				)
				( attribute "CDS_SEC" "1"
					( Origin gPackager )
				)
				( attribute "LOCATION" "C1R23"
					( Origin gFrontEnd )
				)
				( attribute "MATERIAL" "TANT"
					( Origin gFrontEnd )
				)
				( attribute "PACK_TYPE" "3018"
					( Origin gFrontEnd )
				)
				( attribute "PART_NUMBER" "724613-112"
					( Origin gFrontEnd )
				)
				( attribute "PHYS_PAGE" "195"
					( Origin gFrontEnd )
				)
				( attribute "ROT" "0"
					( Origin gFrontEnd )
				)
				( attribute "SEC" "1"
					( Origin gPackager )
				)
				( attribute "TOLERANCE" "20%"
					( Origin gFrontEnd )
				)
				( attribute "VALUE" "68UF"
					( Origin gFrontEnd )
				)
				( attribute "VER" "1"
					( Origin gFrontEnd )
				)
				( attribute "VOLTAGE" "16V"
					( Units "uVoltage" "V" 1.000000)
					( Origin gFrontEnd )
				)
				( attribute "XY" "(-6175,775)"
					( Origin gFrontEnd )
				)
				( attribute "CHIPS_PART_NAME" "CAPP"
					( Origin gPackager )
				)
				( attribute "CDS_PART_NAME" "CAPP_3018-68UF,16V,20%,TANT,72A"
					( Origin gPackager )
				)
				( objectStatus "C1R23" )
				( pin "a"
					( attribute "PN" "1"
						( Origin gPackager )
					)
					( objectStatus "C1R23.1" )
				)
				( pin "b"
					( attribute "PN" "2"
						( Origin gPackager )
					)
					( objectStatus "C1R23.2" )
				)
			)
			( gate "@baseboard_fab2_lib.baseboard_fab2(sch_1):page195_i102"
				( attribute "CDS_LIB" "mstr_discrete"
					( Origin gPackager )
				)
				( attribute "CDS_LOCATION" "C4M6"
					( Origin gPackager )
				)
				( attribute "CDS_SEC" "1"
					( Origin gPackager )
				)
				( attribute "LOCATION" "C4M6"
					( Origin gFrontEnd )
				)
				( attribute "MATERIAL" "TANT"
					( Origin gFrontEnd )
				)
				( attribute "PACK_TYPE" "3018"
					( Origin gFrontEnd )
				)
				( attribute "PART_NUMBER" "724613-112"
					( Origin gFrontEnd )
				)
				( attribute "PHYS_PAGE" "195"
					( Origin gFrontEnd )
				)
				( attribute "ROT" "0"
					( Origin gFrontEnd )
				)
				( attribute "SEC" "1"
					( Origin gPackager )
				)
				( attribute "TOLERANCE" "20%"
					( Origin gFrontEnd )
				)
				( attribute "VALUE" "68UF"
					( Origin gFrontEnd )
				)
				( attribute "VER" "1"
					( Origin gFrontEnd )
				)
				( attribute "VOLTAGE" "16V"
					( Units "uVoltage" "V" 1.000000)
					( Origin gFrontEnd )
				)
				( attribute "XY" "(-4875,775)"
					( Origin gFrontEnd )
				)
				( attribute "CHIPS_PART_NAME" "CAPP"
					( Origin gPackager )
				)
				( attribute "CDS_PART_NAME" "CAPP_3018-68UF,16V,20%,TANT,72A"
					( Origin gPackager )
				)
				( objectStatus "C4M6" )
				( pin "a"
					( attribute "PN" "1"
						( Origin gPackager )
					)
					( objectStatus "C4M6.1" )
				)
				( pin "b"
					( attribute "PN" "2"
						( Origin gPackager )
					)
					( objectStatus "C4M6.2" )
				)
			)
			( gate "@baseboard_fab2_lib.baseboard_fab2(sch_1):page195_i103"
				( attribute "CDS_LIB" "mstr_discrete"
					( Origin gPackager )
				)
				( attribute "CDS_LOCATION" "C1M5"
					( Origin gPackager )
				)
				( attribute "CDS_SEC" "1"
					( Origin gPackager )
				)
				( attribute "LOCATION" "C1M5"
					( Origin gFrontEnd )
				)
				( attribute "MATERIAL" "TANT"
					( Origin gFrontEnd )
				)
				( attribute "PACK_TYPE" "3018"
					( Origin gFrontEnd )
				)
				( attribute "PART_NUMBER" "724613-112"
					( Origin gFrontEnd )
				)
				( attribute "PHYS_PAGE" "195"
					( Origin gFrontEnd )
				)
				( attribute "ROT" "0"
					( Origin gFrontEnd )
				)
				( attribute "SEC" "1"
					( Origin gPackager )
				)
				( attribute "TOLERANCE" "20%"
					( Origin gFrontEnd )
				)
				( attribute "VALUE" "68UF"
					( Origin gFrontEnd )
				)
				( attribute "VER" "1"
					( Origin gFrontEnd )
				)
				( attribute "VOLTAGE" "16V"
					( Units "uVoltage" "V" 1.000000)
					( Origin gFrontEnd )
				)
				( attribute "XY" "(-6550,775)"
					( Origin gFrontEnd )
				)
				( attribute "CHIPS_PART_NAME" "CAPP"
					( Origin gPackager )
				)
				( attribute "CDS_PART_NAME" "CAPP_3018-68UF,16V,20%,TANT,72A"
					( Origin gPackager )
				)
				( objectStatus "C1M5" )
				( pin "a"
					( attribute "PN" "1"
						( Origin gPackager )
					)
					( objectStatus "C1M5.1" )
				)
				( pin "b"
					( attribute "PN" "2"
						( Origin gPackager )
					)
					( objectStatus "C1M5.2" )
				)
			)
			( gate "@baseboard_fab2_lib.baseboard_fab2(sch_1):page195_i104"
				( attribute "CDS_LIB" "mstr_discrete"
					( Origin gPackager )
				)
				( attribute "CDS_LOCATION" "C3T13"
					( Origin gPackager )
				)
				( attribute "CDS_SEC" "1"
					( Origin gPackager )
				)
				( attribute "LOCATION" "C3T13"
					( Origin gFrontEnd )
				)
				( attribute "MATERIAL" "TANT"
					( Origin gFrontEnd )
				)
				( attribute "PACK_TYPE" "3018"
					( Origin gFrontEnd )
				)
				( attribute "PART_NUMBER" "724613-112"
					( Origin gFrontEnd )
				)
				( attribute "PHYS_PAGE" "195"
					( Origin gFrontEnd )
				)
				( attribute "ROT" "0"
					( Origin gFrontEnd )
				)
				( attribute "SEC" "1"
					( Origin gPackager )
				)
				( attribute "TOLERANCE" "20%"
					( Origin gFrontEnd )
				)
				( attribute "VALUE" "68UF"
					( Origin gFrontEnd )
				)
				( attribute "VER" "1"
					( Origin gFrontEnd )
				)
				( attribute "VOLTAGE" "16V"
					( Units "uVoltage" "V" 1.000000)
					( Origin gFrontEnd )
				)
				( attribute "XY" "(-5725,1950)"
					( Origin gFrontEnd )
				)
				( attribute "CHIPS_PART_NAME" "CAPP"
					( Origin gPackager )
				)
				( attribute "CDS_PART_NAME" "CAPP_3018-68UF,16V,20%,TANT,72A"
					( Origin gPackager )
				)
				( objectStatus "C3T13" )
				( pin "a"
					( attribute "PN" "1"
						( Origin gPackager )
					)
					( objectStatus "C3T13.1" )
				)
				( pin "b"
					( attribute "PN" "2"
						( Origin gPackager )
					)
					( objectStatus "C3T13.2" )
				)
			)
			( gate "@baseboard_fab2_lib.baseboard_fab2(sch_1):page195_i105"
				( attribute "CDS_LIB" "mstr_discrete"
					( Origin gPackager )
				)
				( attribute "CDS_LOCATION" "C4M7"
					( Origin gPackager )
				)
				( attribute "CDS_SEC" "1"
					( Origin gPackager )
				)
				( attribute "LOCATION" "C4M7"
					( Origin gFrontEnd )
				)
				( attribute "MATERIAL" "TANT"
					( Origin gFrontEnd )
				)
				( attribute "PACK_TYPE" "3018"
					( Origin gFrontEnd )
				)
				( attribute "PART_NUMBER" "724613-112"
					( Origin gFrontEnd )
				)
				( attribute "PHYS_PAGE" "195"
					( Origin gFrontEnd )
				)
				( attribute "ROT" "0"
					( Origin gFrontEnd )
				)
				( attribute "SEC" "1"
					( Origin gPackager )
				)
				( attribute "TOLERANCE" "20%"
					( Origin gFrontEnd )
				)
				( attribute "VALUE" "68UF"
					( Origin gFrontEnd )
				)
				( attribute "VER" "1"
					( Origin gFrontEnd )
				)
				( attribute "VOLTAGE" "16V"
					( Units "uVoltage" "V" 1.000000)
					( Origin gFrontEnd )
				)
				( attribute "XY" "(-4850,1950)"
					( Origin gFrontEnd )
				)
				( attribute "CHIPS_PART_NAME" "CAPP"
					( Origin gPackager )
				)
				( attribute "CDS_PART_NAME" "CAPP_3018-68UF,16V,20%,TANT,72A"
					( Origin gPackager )
				)
				( objectStatus "C4M7" )
				( pin "a"
					( attribute "PN" "1"
						( Origin gPackager )
					)
					( objectStatus "C4M7.1" )
				)
				( pin "b"
					( attribute "PN" "2"
						( Origin gPackager )
					)
					( objectStatus "C4M7.2" )
				)
			)
			( gate "@baseboard_fab2_lib.baseboard_fab2(sch_1):page195_i106"
				( attribute "CDS_LIB" "mstr_discrete"
					( Origin gPackager )
				)
				( attribute "CDS_LOCATION" "C3T15"
					( Origin gPackager )
				)
				( attribute "CDS_SEC" "1"
					( Origin gPackager )
				)
				( attribute "LOCATION" "C3T15"
					( Origin gFrontEnd )
				)
				( attribute "MATERIAL" "TANT"
					( Origin gFrontEnd )
				)
				( attribute "PACK_TYPE" "3018"
					( Origin gFrontEnd )
				)
				( attribute "PART_NUMBER" "724613-112"
					( Origin gFrontEnd )
				)
				( attribute "PHYS_PAGE" "195"
					( Origin gFrontEnd )
				)
				( attribute "ROT" "0"
					( Origin gFrontEnd )
				)
				( attribute "SEC" "1"
					( Origin gPackager )
				)
				( attribute "TOLERANCE" "20%"
					( Origin gFrontEnd )
				)
				( attribute "VALUE" "68UF"
					( Origin gFrontEnd )
				)
				( attribute "VER" "1"
					( Origin gFrontEnd )
				)
				( attribute "VOLTAGE" "16V"
					( Units "uVoltage" "V" 1.000000)
					( Origin gFrontEnd )
				)
				( attribute "XY" "(-5275,1925)"
					( Origin gFrontEnd )
				)
				( attribute "CHIPS_PART_NAME" "CAPP"
					( Origin gPackager )
				)
				( attribute "CDS_PART_NAME" "CAPP_3018-68UF,16V,20%,TANT,72A"
					( Origin gPackager )
				)
				( objectStatus "C3T15" )
				( pin "a"
					( attribute "PN" "1"
						( Origin gPackager )
					)
					( objectStatus "C3T15.1" )
				)
				( pin "b"
					( attribute "PN" "2"
						( Origin gPackager )
					)
					( objectStatus "C3T15.2" )
				)
			)
			( gate "@baseboard_fab2_lib.baseboard_fab2(sch_1):page195_i108"
				( attribute "CDS_LIB" "mstr_discrete"
					( Origin gPackager )
				)
				( attribute "CDS_LOCATION" "C7M6"
					( Origin gPackager )
				)
				( attribute "CDS_SEC" "1"
					( Origin gPackager )
				)
				( attribute "LOCATION" "C7M6"
					( Origin gFrontEnd )
				)
				( attribute "MATERIAL" "TANT"
					( Origin gFrontEnd )
				)
				( attribute "PACK_TYPE" "3018"
					( Origin gFrontEnd )
				)
				( attribute "PART_NUMBER" "724613-112"
					( Origin gFrontEnd )
				)
				( attribute "PHYS_PAGE" "195"
					( Origin gFrontEnd )
				)
				( attribute "ROT" "0"
					( Origin gFrontEnd )
				)
				( attribute "SEC" "1"
					( Origin gPackager )
				)
				( attribute "TOLERANCE" "20%"
					( Origin gFrontEnd )
				)
				( attribute "VALUE" "68UF"
					( Origin gFrontEnd )
				)
				( attribute "VER" "1"
					( Origin gFrontEnd )
				)
				( attribute "VOLTAGE" "16V"
					( Units "uVoltage" "V" 1.000000)
					( Origin gFrontEnd )
				)
				( attribute "XY" "(-6150,1950)"
					( Origin gFrontEnd )
				)
				( attribute "CHIPS_PART_NAME" "CAPP"
					( Origin gPackager )
				)
				( attribute "CDS_PART_NAME" "CAPP_3018-68UF,16V,20%,TANT,72A"
					( Origin gPackager )
				)
				( objectStatus "C7M6" )
				( pin "a"
					( attribute "PN" "1"
						( Origin gPackager )
					)
					( objectStatus "C7M6.1" )
				)
				( pin "b"
					( attribute "PN" "2"
						( Origin gPackager )
					)
					( objectStatus "C7M6.2" )
				)
			)
			( gate "@baseboard_fab2_lib.baseboard_fab2(sch_1):page195_i109"
				( attribute "CDS_LIB" "mstr_discrete"
					( Origin gPackager )
				)
				( attribute "CDS_LOCATION" "C6N5"
					( Origin gPackager )
				)
				( attribute "CDS_SEC" "1"
					( Origin gPackager )
				)
				( attribute "LOCATION" "C6N5"
					( Origin gFrontEnd )
				)
				( attribute "MATERIAL" "TANT"
					( Origin gFrontEnd )
				)
				( attribute "PACK_TYPE" "3018"
					( Origin gFrontEnd )
				)
				( attribute "PART_NUMBER" "724613-112"
					( Origin gFrontEnd )
				)
				( attribute "PHYS_PAGE" "195"
					( Origin gFrontEnd )
				)
				( attribute "ROT" "0"
					( Origin gFrontEnd )
				)
				( attribute "SEC" "1"
					( Origin gPackager )
				)
				( attribute "TOLERANCE" "20%"
					( Origin gFrontEnd )
				)
				( attribute "VALUE" "68UF"
					( Origin gFrontEnd )
				)
				( attribute "VER" "1"
					( Origin gFrontEnd )
				)
				( attribute "VOLTAGE" "16V"
					( Units "uVoltage" "V" 1.000000)
					( Origin gFrontEnd )
				)
				( attribute "XY" "(-6525,1950)"
					( Origin gFrontEnd )
				)
				( attribute "CHIPS_PART_NAME" "CAPP"
					( Origin gPackager )
				)
				( attribute "CDS_PART_NAME" "CAPP_3018-68UF,16V,20%,TANT,72A"
					( Origin gPackager )
				)
				( objectStatus "C6N5" )
				( pin "a"
					( attribute "PN" "1"
						( Origin gPackager )
					)
					( objectStatus "C6N5.1" )
				)
				( pin "b"
					( attribute "PN" "2"
						( Origin gPackager )
					)
					( objectStatus "C6N5.2" )
				)
			)
			( gate "@baseboard_fab2_lib.baseboard_fab2(sch_1):page195_i111"
				( attribute "CDS_LIB" "mstr_discrete"
					( Origin gPackager )
				)
				( attribute "CDS_LOCATION" "C9T3"
					( Origin gPackager )
				)
				( attribute "CDS_SEC" "1"
					( Origin gPackager )
				)
				( attribute "LOCATION" "C9T3"
					( Origin gFrontEnd )
				)
				( attribute "MATERIAL" "TANT"
					( Origin gFrontEnd )
				)
				( attribute "PACK_TYPE" "3018"
					( Origin gFrontEnd )
				)
				( attribute "PART_NUMBER" "724613-112"
					( Origin gFrontEnd )
				)
				( attribute "PHYS_PAGE" "195"
					( Origin gFrontEnd )
				)
				( attribute "ROT" "0"
					( Origin gFrontEnd )
				)
				( attribute "SEC" "1"
					( Origin gPackager )
				)
				( attribute "TOLERANCE" "20%"
					( Origin gFrontEnd )
				)
				( attribute "VALUE" "68UF"
					( Origin gFrontEnd )
				)
				( attribute "VER" "1"
					( Origin gFrontEnd )
				)
				( attribute "VOLTAGE" "16V"
					( Units "uVoltage" "V" 1.000000)
					( Origin gFrontEnd )
				)
				( attribute "XY" "(-6875,1950)"
					( Origin gFrontEnd )
				)
				( attribute "CHIPS_PART_NAME" "CAPP"
					( Origin gPackager )
				)
				( attribute "CDS_PART_NAME" "CAPP_3018-68UF,16V,20%,TANT,72A"
					( Origin gPackager )
				)
				( objectStatus "C9T3" )
				( pin "a"
					( attribute "PN" "1"
						( Origin gPackager )
					)
					( objectStatus "C9T3.1" )
				)
				( pin "b"
					( attribute "PN" "2"
						( Origin gPackager )
					)
					( objectStatus "C9T3.2" )
				)
			)
			( gate "@baseboard_fab2_lib.baseboard_fab2(sch_1):page195_i112"
				( attribute "CDS_LIB" "mstr_discrete"
					( Origin gPackager )
				)
				( attribute "CDS_LOCATION" "C4F4"
					( Origin gPackager )
				)
				( attribute "CDS_SEC" "1"
					( Origin gPackager )
				)
				( attribute "LOCATION" "C4F4"
					( Origin gFrontEnd )
				)
				( attribute "MATERIAL" "TANT"
					( Origin gFrontEnd )
				)
				( attribute "PACK_TYPE" "3018"
					( Origin gFrontEnd )
				)
				( attribute "PART_NUMBER" "724613-112"
					( Origin gFrontEnd )
				)
				( attribute "PHYS_PAGE" "195"
					( Origin gFrontEnd )
				)
				( attribute "ROT" "0"
					( Origin gFrontEnd )
				)
				( attribute "SEC" "1"
					( Origin gPackager )
				)
				( attribute "TOLERANCE" "20%"
					( Origin gFrontEnd )
				)
				( attribute "VALUE" "68UF"
					( Origin gFrontEnd )
				)
				( attribute "VER" "1"
					( Origin gFrontEnd )
				)
				( attribute "VOLTAGE" "16V"
					( Units "uVoltage" "V" 1.000000)
					( Origin gFrontEnd )
				)
				( attribute "XY" "(-7250,1950)"
					( Origin gFrontEnd )
				)
				( attribute "CHIPS_PART_NAME" "CAPP"
					( Origin gPackager )
				)
				( attribute "CDS_PART_NAME" "CAPP_3018-68UF,16V,20%,TANT,72A"
					( Origin gPackager )
				)
				( objectStatus "C4F4" )
				( pin "a"
					( attribute "PN" "1"
						( Origin gPackager )
					)
					( objectStatus "C4F4.1" )
				)
				( pin "b"
					( attribute "PN" "2"
						( Origin gPackager )
					)
					( objectStatus "C4F4.2" )
				)
			)
			( gate "@baseboard_fab2_lib.baseboard_fab2(sch_1):page195_i113"
				( attribute "CDS_LIB" "mstr_discrete"
					( Origin gPackager )
				)
				( attribute "CDS_LOCATION" "C3T3"
					( Origin gPackager )
				)
				( attribute "CDS_SEC" "1"
					( Origin gPackager )
				)
				( attribute "LOCATION" "C3T3"
					( Origin gFrontEnd )
				)
				( attribute "MATERIAL" "TANT"
					( Origin gFrontEnd )
				)
				( attribute "PACK_TYPE" "3018"
					( Origin gFrontEnd )
				)
				( attribute "PART_NUMBER" "724613-112"
					( Origin gFrontEnd )
				)
				( attribute "PHYS_PAGE" "195"
					( Origin gFrontEnd )
				)
				( attribute "ROT" "0"
					( Origin gFrontEnd )
				)
				( attribute "SEC" "1"
					( Origin gPackager )
				)
				( attribute "TOLERANCE" "20%"
					( Origin gFrontEnd )
				)
				( attribute "VALUE" "68UF"
					( Origin gFrontEnd )
				)
				( attribute "VER" "1"
					( Origin gFrontEnd )
				)
				( attribute "VOLTAGE" "16V"
					( Units "uVoltage" "V" 1.000000)
					( Origin gFrontEnd )
				)
				( attribute "XY" "(-7675,1950)"
					( Origin gFrontEnd )
				)
				( attribute "CHIPS_PART_NAME" "CAPP"
					( Origin gPackager )
				)
				( attribute "CDS_PART_NAME" "CAPP_3018-68UF,16V,20%,TANT,72A"
					( Origin gPackager )
				)
				( objectStatus "C3T3" )
				( pin "a"
					( attribute "PN" "1"
						( Origin gPackager )
					)
					( objectStatus "C3T3.1" )
				)
				( pin "b"
					( attribute "PN" "2"
						( Origin gPackager )
					)
					( objectStatus "C3T3.2" )
				)
			)
			( gate "@baseboard_fab2_lib.baseboard_fab2(sch_1):page196_i46"
				( attribute "BOM_COST" "SB"
					( Origin gFrontEnd )
				)
				( attribute "CDS_LIB" "mstr_discrete"
					( Origin gPackager )
				)
				( attribute "CDS_LOCATION" "R2U43"
					( Origin gPackager )
				)
				( attribute "CDS_SEC" "1"
					( Origin gPackager )
				)
				( attribute "LOCATION" "R2U43"
					( Origin gFrontEnd )
				)
				( attribute "MATERIAL" "CHIP"
					( Origin gFrontEnd )
				)
				( attribute "PACK_TYPE" "0402"
					( Origin gFrontEnd )
				)
				( attribute "PART_NUMBER" "G21796-026"
					( Origin gFrontEnd )
				)
				( attribute "PHYS_PAGE" "196"
					( Origin gFrontEnd )
				)
				( attribute "ROOM" "SB_VRD"
					( Origin gFrontEnd )
				)
				( attribute "ROT" "0"
					( Origin gFrontEnd )
				)
				( attribute "SEC" "1"
					( Origin gFrontEnd )
				)
				( attribute "SEC_TYPE" "0402"
					( Origin gFrontEnd )
				)
				( attribute "TOLERANCE" "1%"
					( Origin gFrontEnd )
				)
				( attribute "VALUE" "1.00K"
					( Origin gFrontEnd )
				)
				( attribute "VER" "1"
					( Origin gFrontEnd )
				)
				( attribute "WATTAGE" "1/16W"
					( Origin gFrontEnd )
				)
				( attribute "XY" "(-3650,4550)"
					( Origin gFrontEnd )
				)
				( attribute "CHIPS_PART_NAME" "RES"
					( Origin gPackager )
				)
				( attribute "CDS_PART_NAME" "RES_0402-1.00K,1%,1/16W,CHIP,GA"
					( Origin gPackager )
				)
				( objectStatus "R2U43" )
				( pin "a"
					( attribute "PN" "1"
						( Origin gPackager )
					)
					( objectStatus "R2U43.1" )
				)
				( pin "b"
					( attribute "PN" "2"
						( Origin gPackager )
					)
					( objectStatus "R2U43.2" )
				)
			)
			( gate "@baseboard_fab2_lib.baseboard_fab2(sch_1):page196_i47"
				( attribute "BOM_COST" "SB"
					( Origin gFrontEnd )
				)
				( attribute "CDS_LIB" "mstr_misc"
					( Origin gPackager )
				)
				( attribute "CDS_LOCATION" "BT8G1"
					( Origin gPackager )
				)
				( attribute "LOCATION" "BT8G1"
					( Origin gFrontEnd )
				)
				( attribute "PACK_TYPE" "PLCLF"
					( Origin gFrontEnd )
				)
				( attribute "PART_NUMBER" "202168-001"
					( Origin gFrontEnd )
				)
				( attribute "PHYS_PAGE" "196"
					( Origin gFrontEnd )
				)
				( attribute "ROOM" "SB_VRD"
					( Origin gFrontEnd )
				)
				( attribute "ROT" "0"
					( Origin gFrontEnd )
				)
				( attribute "VER" "1"
					( Origin gFrontEnd )
				)
				( attribute "XY" "(-4375,4200)"
					( Origin gFrontEnd )
				)
				( attribute "CHIPS_PART_NAME" "BATTERY"
					( Origin gPackager )
				)
				( attribute "CDS_PART_NAME" "BATTERY_PLCLF-202168-001"
					( Origin gPackager )
				)
				( objectStatus "BT8G1" )
			)
			( gate "@baseboard_fab2_lib.baseboard_fab2(sch_1):page196_i51"
				( attribute "CDS_LIB" "mstr_discrete"
					( Origin gPackager )
				)
				( attribute "CDS_LOCATION" "XBT8G1"
					( Origin gPackager )
				)
				( attribute "CDS_SEC" "1"
					( Origin gPackager )
				)
				( attribute "LOCATION" "XBT8G1"
					( Origin gFrontEnd )
				)
				( attribute "MATERIAL" "3PVERT"
					( Origin gFrontEnd )
				)
				( attribute "PACK_TYPE" "PIP"
					( Origin gFrontEnd )
				)
				( attribute "PART_NUMBER" "C68619-005"
					( Origin gFrontEnd )
				)
				( attribute "PHYS_PAGE" "196"
					( Origin gFrontEnd )
				)
				( attribute "ROOM" "SB_VRD"
					( Origin gFrontEnd )
				)
				( attribute "ROT" "0"
					( Origin gFrontEnd )
				)
				( attribute "SEC" "1"
					( Origin gFrontEnd )
				)
				( attribute "SEC_TYPE" "PIP"
					( Origin gFrontEnd )
				)
				( attribute "VER" "1"
					( Origin gFrontEnd )
				)
				( attribute "XY" "(-4800,4550)"
					( Origin gFrontEnd )
				)
				( attribute "CHIPS_PART_NAME" "VERT_BATT_3PIN"
					( Origin gPackager )
				)
				( attribute "CDS_PART_NAME" "VERT_BATT_3PIN_PIP-3PVERT,C686A"
					( Origin gPackager )
				)
				( objectStatus "XBT8G1" )
				( pin "n"
					( attribute "PN" "3"
						( Origin gPackager )
					)
					( objectStatus "XBT8G1.3" )
				)
				( pin "p1"
					( attribute "PN" "1"
						( Origin gPackager )
					)
					( objectStatus "XBT8G1.1" )
				)
				( pin "p2"
					( attribute "PN" "2"
						( Origin gPackager )
					)
					( objectStatus "XBT8G1.2" )
				)
			)
			( gate "@baseboard_fab2_lib.baseboard_fab2(sch_1):page196_i53"
				( attribute "CDS_LIB" "mstr_discrete"
					( Origin gPackager )
				)
				( attribute "CDS_LOCATION" "CR2U1"
					( Origin gPackager )
				)
				( attribute "CDS_SEC" "1"
					( Origin gPackager )
				)
				( attribute "LOCATION" "CR2U1"
					( Origin gFrontEnd )
				)
				( attribute "MATERIAL" "DIO"
					( Origin gFrontEnd )
				)
				( attribute "PACK_TYPE" "SMLF"
					( Origin gFrontEnd )
				)
				( attribute "PART_NUMBER" "C90169-001"
					( Origin gFrontEnd )
				)
				( attribute "PHYS_PAGE" "196"
					( Origin gFrontEnd )
				)
				( attribute "ROOM" "SB_VRD"
					( Origin gFrontEnd )
				)
				( attribute "ROT" "0"
					( Origin gFrontEnd )
				)
				( attribute "SEC" "1"
					( Origin gFrontEnd )
				)
				( attribute "SEC_TYPE" "SMLF"
					( Origin gFrontEnd )
				)
				( attribute "VALUE" "BAS70-05"
					( Origin gFrontEnd )
				)
				( attribute "VER" "1"
					( Origin gFrontEnd )
				)
				( attribute "XY" "(-2700,4650)"
					( Origin gFrontEnd )
				)
				( attribute "CHIPS_PART_NAME" "DIODE2A_DUAL"
					( Origin gPackager )
				)
				( attribute "CDS_PART_NAME" "DIODE2A_DUAL_SMLF-BAS70-05,DIOA"
					( Origin gPackager )
				)
				( objectStatus "CR2U1" )
				( pin "a1"
					( attribute "PN" "1"
						( Origin gPackager )
					)
					( objectStatus "CR2U1.1" )
				)
				( pin "a2"
					( attribute "PN" "2"
						( Origin gPackager )
					)
					( objectStatus "CR2U1.2" )
				)
				( pin "c"
					( attribute "PN" "3"
						( Origin gPackager )
					)
					( objectStatus "CR2U1.3" )
				)
			)
			( gate "@baseboard_fab2_lib.baseboard_fab2(sch_1):page196_i59"
				( attribute "CDS_LIB" "mstr_discrete"
					( Origin gPackager )
				)
				( attribute "CDS_LOCATION" "R3P44"
					( Origin gPackager )
				)
				( attribute "CDS_SEC" "1"
					( Origin gPackager )
				)
				( attribute "LOCATION" "R3P44"
					( Origin gFrontEnd )
				)
				( attribute "MATERIAL" "CHIP"
					( Origin gFrontEnd )
				)
				( attribute "PACK_TYPE" "0402"
					( Origin gFrontEnd )
				)
				( attribute "PART_NUMBER" "G21796-072"
					( Origin gFrontEnd )
				)
				( attribute "PHYS_PAGE" "196"
					( Origin gFrontEnd )
				)
				( attribute "ROOM" "V_SUPER"
					( Origin gFrontEnd )
				)
				( attribute "ROT" "0"
					( Origin gFrontEnd )
				)
				( attribute "SEC" "1"
					( Origin gFrontEnd )
				)
				( attribute "SEC_TYPE" "0402"
					( Origin gFrontEnd )
				)
				( attribute "TOLERANCE" "1%"
					( Origin gFrontEnd )
				)
				( attribute "VALUE" "4.75K"
					( Origin gFrontEnd )
				)
				( attribute "VER" "2"
					( Origin gFrontEnd )
				)
				( attribute "WATTAGE" "1/16W"
					( Origin gFrontEnd )
				)
				( attribute "XY" "(1325,4650)"
					( Origin gFrontEnd )
				)
				( attribute "CHIPS_PART_NAME" "RES"
					( Origin gPackager )
				)
				( attribute "CDS_PART_NAME" "RES_0402-4.75K,1%,1/16W,CHIP,GA"
					( Origin gPackager )
				)
				( objectStatus "R3P44" )
				( pin "a"
					( attribute "PN" "1"
						( Origin gPackager )
					)
					( objectStatus "R3P44.1" )
				)
				( pin "b"
					( attribute "PN" "2"
						( Origin gPackager )
					)
					( objectStatus "R3P44.2" )
				)
			)
			( gate "@baseboard_fab2_lib.baseboard_fab2(sch_1):page196_i60"
				( attribute "CDS_LIB" "mstr_discrete"
					( Origin gPackager )
				)
				( attribute "CDS_LOCATION" "C3P45"
					( Origin gPackager )
				)
				( attribute "CDS_SEC" "1"
					( Origin gPackager )
				)
				( attribute "LOCATION" "C3P45"
					( Origin gFrontEnd )
				)
				( attribute "MATERIAL" "X7R"
					( Origin gFrontEnd )
				)
				( attribute "PACK_TYPE" "0402"
					( Origin gFrontEnd )
				)
				( attribute "PART_NUMBER" "A36096-090"
					( Origin gFrontEnd )
				)
				( attribute "PHYS_PAGE" "196"
					( Origin gFrontEnd )
				)
				( attribute "ROOM" "V_SUPER"
					( Origin gFrontEnd )
				)
				( attribute "ROT" "0"
					( Origin gFrontEnd )
				)
				( attribute "SEC" "1"
					( Origin gFrontEnd )
				)
				( attribute "SEC_TYPE" "0402"
					( Origin gFrontEnd )
				)
				( attribute "TOLERANCE" "10%"
					( Origin gFrontEnd )
				)
				( attribute "VALUE" "0.047UF"
					( Origin gFrontEnd )
				)
				( attribute "VER" "1"
					( Origin gFrontEnd )
				)
				( attribute "VOLTAGE" "25V"
					( Units "uVoltage" "V" 1.000000)
					( Origin gFrontEnd )
				)
				( attribute "XY" "(1225,4050)"
					( Origin gFrontEnd )
				)
				( attribute "CHIPS_PART_NAME" "CAP"
					( Origin gPackager )
				)
				( attribute "CDS_PART_NAME" "CAP_0402-0.047UF,25V,10%,X7R,AA"
					( Origin gPackager )
				)
				( objectStatus "C3P45" )
				( pin "a"
					( attribute "PN" "1"
						( Origin gPackager )
					)
					( objectStatus "C3P45.1" )
				)
				( pin "b"
					( attribute "PN" "2"
						( Origin gPackager )
					)
					( objectStatus "C3P45.2" )
				)
			)
			( gate "@baseboard_fab2_lib.baseboard_fab2(sch_1):page196_i65"
				( attribute "CDS_LIB" "mstr_discrete"
					( Origin gPackager )
				)
				( attribute "CDS_LOCATION" "R2P20"
					( Origin gPackager )
				)
				( attribute "CDS_SEC" "1"
					( Origin gPackager )
				)
				( attribute "LOCATION" "R2P20"
					( Origin gFrontEnd )
				)
				( attribute "MATERIAL" "CHIP"
					( Origin gFrontEnd )
				)
				( attribute "PACK_TYPE" "0402"
					( Origin gFrontEnd )
				)
				( attribute "PART_NUMBER" "G21796-017"
					( Origin gFrontEnd )
				)
				( attribute "PHYS_PAGE" "196"
					( Origin gFrontEnd )
				)
				( attribute "ROOM" "V_SUPER"
					( Origin gFrontEnd )
				)
				( attribute "ROT" "0"
					( Origin gFrontEnd )
				)
				( attribute "SEC" "1"
					( Origin gFrontEnd )
				)
				( attribute "SEC_TYPE" "0402"
					( Origin gFrontEnd )
				)
				( attribute "TOLERANCE" "1%"
					( Origin gFrontEnd )
				)
				( attribute "VALUE" "100.0"
					( Origin gFrontEnd )
				)
				( attribute "VER" "1"
					( Origin gFrontEnd )
				)
				( attribute "WATTAGE" "1/16W"
					( Origin gFrontEnd )
				)
				( attribute "XY" "(1350,2000)"
					( Origin gFrontEnd )
				)
				( attribute "CHIPS_PART_NAME" "RES"
					( Origin gPackager )
				)
				( attribute "CDS_PART_NAME" "RES_0402-100.0,1%,1/16W,CHIP,GA"
					( Origin gPackager )
				)
				( objectStatus "R2P20" )
				( pin "a"
					( attribute "PN" "1"
						( Origin gPackager )
					)
					( objectStatus "R2P20.1" )
				)
				( pin "b"
					( attribute "PN" "2"
						( Origin gPackager )
					)
					( objectStatus "R2P20.2" )
				)
			)
			( gate "@baseboard_fab2_lib.baseboard_fab2(sch_1):page196_i68"
				( attribute "CDS_LIB" "mstr_discrete"
					( Origin gPackager )
				)
				( attribute "CDS_LOCATION" "R1L16"
					( Origin gPackager )
				)
				( attribute "CDS_SEC" "1"
					( Origin gPackager )
				)
				( attribute "LOCATION" "R1L16"
					( Origin gFrontEnd )
				)
				( attribute "MATERIAL" "CHIP"
					( Origin gFrontEnd )
				)
				( attribute "PACK_TYPE" "0402"
					( Origin gFrontEnd )
				)
				( attribute "PART_NUMBER" "G21796-047"
					( Origin gFrontEnd )
				)
				( attribute "PHYS_PAGE" "196"
					( Origin gFrontEnd )
				)
				( attribute "ROOM" "V_SUPER"
					( Origin gFrontEnd )
				)
				( attribute "ROT" "0"
					( Origin gFrontEnd )
				)
				( attribute "SEC" "1"
					( Origin gFrontEnd )
				)
				( attribute "SEC_TYPE" "0402"
					( Origin gFrontEnd )
				)
				( attribute "TOLERANCE" "1%"
					( Origin gFrontEnd )
				)
				( attribute "VALUE" "49.9"
					( Origin gFrontEnd )
				)
				( attribute "VER" "1"
					( Origin gFrontEnd )
				)
				( attribute "WATTAGE" "1/16W"
					( Origin gFrontEnd )
				)
				( attribute "XY" "(1300,1250)"
					( Origin gFrontEnd )
				)
				( attribute "CHIPS_PART_NAME" "RES"
					( Origin gPackager )
				)
				( attribute "CDS_PART_NAME" "RES_0402-49.9,1%,1/16W,CHIP,G2A"
					( Origin gPackager )
				)
				( objectStatus "R1L16" )
				( pin "a"
					( attribute "PN" "1"
						( Origin gPackager )
					)
					( objectStatus "R1L16.1" )
				)
				( pin "b"
					( attribute "PN" "2"
						( Origin gPackager )
					)
					( objectStatus "R1L16.2" )
				)
			)
			( gate "@baseboard_fab2_lib.baseboard_fab2(sch_1):page196_i70"
				( attribute "CDS_LIB" "mstr_analog"
					( Origin gPackager )
				)
				( attribute "CDS_LOCATION" "U7D3"
					( Origin gPackager )
				)
				( attribute "CDS_SEC" "1"
					( Origin gPackager )
				)
				( attribute "LOCATION" "U7D3"
					( Origin gFrontEnd )
				)
				( attribute "MATERIAL" "IC"
					( Origin gFrontEnd )
				)
				( attribute "PACK_TYPE" "SMT"
					( Origin gFrontEnd )
				)
				( attribute "PART_NUMBER" "H46130-001"
					( Origin gFrontEnd )
				)
				( attribute "PHYS_PAGE" "196"
					( Origin gFrontEnd )
				)
				( attribute "ROOM" "V_SUPER"
					( Origin gFrontEnd )
				)
				( attribute "ROT" "0"
					( Origin gFrontEnd )
				)
				( attribute "SEC" "1"
					( Origin gFrontEnd )
				)
				( attribute "SEC_TYPE" "SMT"
					( Origin gFrontEnd )
				)
				( attribute "VER" "1"
					( Origin gFrontEnd )
				)
				( attribute "XY" "(725,4400)"
					( Origin gFrontEnd )
				)
				( attribute "CHIPS_PART_NAME" "ADM1085"
					( Origin gPackager )
				)
				( attribute "CDS_PART_NAME" "ADM1085_SMT-IC,H46130-001"
					( Origin gPackager )
				)
				( objectStatus "U7D3" )
				( pin "cext"
					( attribute "PN" "5"
						( Origin gPackager )
					)
					( objectStatus "U7D3.5" )
				)
				( pin "enin"
					( attribute "PN" "1"
						( Origin gPackager )
					)
					( objectStatus "U7D3.1" )
				)
				( pin "enout"
					( attribute "PN" "4"
						( Origin gPackager )
					)
					( objectStatus "U7D3.4" )
				)
				( pin "gnd"
					( attribute "PN" "2"
						( Origin gPackager )
					)
					( objectStatus "U7D3.2" )
				)
				( pin "vcc"
					( attribute "PN" "6"
						( Origin gPackager )
					)
					( objectStatus "U7D3.6" )
				)
				( pin "vin"
					( attribute "PN" "3"
						( Origin gPackager )
					)
					( objectStatus "U7D3.3" )
				)
			)
			( gate "@baseboard_fab2_lib.baseboard_fab2(sch_1):page196_i71"
				( attribute "CDS_LIB" "mstr_discrete"
					( Origin gPackager )
				)
				( attribute "CDS_LOCATION" "R3P50"
					( Origin gPackager )
				)
				( attribute "CDS_SEC" "1"
					( Origin gPackager )
				)
				( attribute "LOCATION" "R3P50"
					( Origin gFrontEnd )
				)
				( attribute "MATERIAL" "EMPTY"
					( Origin gFrontEnd )
				)
				( attribute "PACK_TYPE" "0402"
					( Origin gFrontEnd )
				)
				( attribute "PART_NUMBER" "G21796-016"
					( Origin gFrontEnd )
				)
				( attribute "PHYS_PAGE" "196"
					( Origin gFrontEnd )
				)
				( attribute "ROOM" "V_SUPER"
					( Origin gFrontEnd )
				)
				( attribute "ROT" "0"
					( Origin gFrontEnd )
				)
				( attribute "SEC" "1"
					( Origin gFrontEnd )
				)
				( attribute "SEC_TYPE" "0402"
					( Origin gFrontEnd )
				)
				( attribute "TOLERANCE" "1%"
					( Origin gFrontEnd )
				)
				( attribute "VALUE" "10.0K"
					( Origin gFrontEnd )
				)
				( attribute "VER" "2"
					( Origin gFrontEnd )
				)
				( attribute "WATTAGE" "1/16W"
					( Origin gFrontEnd )
				)
				( attribute "XY" "(-25,4750)"
					( Origin gFrontEnd )
				)
				( attribute "CHIPS_PART_NAME" "RES"
					( Origin gPackager )
				)
				( attribute "CDS_PART_NAME" "RES_0402-10.0K,1%,1/16W,EMPTY,A"
					( Origin gPackager )
				)
				( objectStatus "R3P50" )
				( pin "a"
					( attribute "PN" "1"
						( Origin gPackager )
					)
					( objectStatus "R3P50.1" )
				)
				( pin "b"
					( attribute "PN" "2"
						( Origin gPackager )
					)
					( objectStatus "R3P50.2" )
				)
			)
			( gate "@baseboard_fab2_lib.baseboard_fab2(sch_1):page196_i72"
				( attribute "CDS_LIB" "dev_discrete"
					( Origin gPackager )
				)
				( attribute "CDS_LOCATION" "C3P46"
					( Origin gPackager )
				)
				( attribute "CDS_SEC" "1"
					( Origin gPackager )
				)
				( attribute "LOCATION" "C3P46"
					( Origin gFrontEnd )
				)
				( attribute "MATERIAL" "X7R"
					( Origin gFrontEnd )
				)
				( attribute "PACK_TYPE" "0402V"
					( Origin gFrontEnd )
				)
				( attribute "PART_NUMBER" "A36096-030"
					( Origin gFrontEnd )
				)
				( attribute "PHYS_PAGE" "196"
					( Origin gFrontEnd )
				)
				( attribute "ROOM" "V_SUPER"
					( Origin gFrontEnd )
				)
				( attribute "ROT" "0"
					( Origin gFrontEnd )
				)
				( attribute "SEC" "1"
					( Origin gFrontEnd )
				)
				( attribute "SEC_TYPE" "0402V"
					( Origin gFrontEnd )
				)
				( attribute "TOLERANCE" "10%"
					( Origin gFrontEnd )
				)
				( attribute "VALUE" "0.1UF"
					( Origin gFrontEnd )
				)
				( attribute "VER" "1"
					( Origin gFrontEnd )
				)
				( attribute "VOLTAGE" "16V"
					( Units "uVoltage" "V" 1.000000)
					( Origin gFrontEnd )
				)
				( attribute "XY" "(275,3950)"
					( Origin gFrontEnd )
				)
				( attribute "CHIPS_PART_NAME" "CAP_A"
					( Origin gPackager )
				)
				( attribute "CDS_PART_NAME" "CAP_A_0402V-0.1UF,16V,10%,X7R,A"
					( Origin gPackager )
				)
				( objectStatus "C3P46" )
				( pin "a"
					( attribute "PN" "1"
						( Origin gPackager )
					)
					( objectStatus "C3P46.1" )
				)
				( pin "b"
					( attribute "PN" "2"
						( Origin gPackager )
					)
					( objectStatus "C3P46.2" )
				)
			)
			( gate "@baseboard_fab2_lib.baseboard_fab2(sch_1):page196_i74"
				( attribute "CDS_LIB" "mstr_discrete"
					( Origin gPackager )
				)
				( attribute "CDS_LOCATION" "R3P48"
					( Origin gPackager )
				)
				( attribute "CDS_SEC" "1"
					( Origin gPackager )
				)
				( attribute "LOCATION" "R3P48"
					( Origin gFrontEnd )
				)
				( attribute "MATERIAL" "CHIP"
					( Origin gFrontEnd )
				)
				( attribute "PACK_TYPE" "0402"
					( Origin gFrontEnd )
				)
				( attribute "PART_NUMBER" "G21796-058"
					( Origin gFrontEnd )
				)
				( attribute "PHYS_PAGE" "196"
					( Origin gFrontEnd )
				)
				( attribute "ROOM" "V_SUPER"
					( Origin gFrontEnd )
				)
				( attribute "ROT" "0"
					( Origin gFrontEnd )
				)
				( attribute "SEC" "1"
					( Origin gFrontEnd )
				)
				( attribute "SEC_TYPE" "0402"
					( Origin gFrontEnd )
				)
				( attribute "TOLERANCE" "1%"
					( Origin gFrontEnd )
				)
				( attribute "VALUE" "90.9K"
					( Origin gFrontEnd )
				)
				( attribute "VER" "2"
					( Origin gFrontEnd )
				)
				( attribute "WATTAGE" "1/16W"
					( Origin gFrontEnd )
				)
				( attribute "XY" "(-525,4750)"
					( Origin gFrontEnd )
				)
				( attribute "CHIPS_PART_NAME" "RES"
					( Origin gPackager )
				)
				( attribute "CDS_PART_NAME" "RES_0402-90.9K,1%,1/16W,CHIP,GA"
					( Origin gPackager )
				)
				( objectStatus "R3P48" )
				( pin "a"
					( attribute "PN" "1"
						( Origin gPackager )
					)
					( objectStatus "R3P48.1" )
				)
				( pin "b"
					( attribute "PN" "2"
						( Origin gPackager )
					)
					( objectStatus "R3P48.2" )
				)
			)
			( gate "@baseboard_fab2_lib.baseboard_fab2(sch_1):page196_i75"
				( attribute "CDS_LIB" "mstr_discrete"
					( Origin gPackager )
				)
				( attribute "CDS_LOCATION" "R3P51"
					( Origin gPackager )
				)
				( attribute "CDS_SEC" "1"
					( Origin gPackager )
				)
				( attribute "LOCATION" "R3P51"
					( Origin gFrontEnd )
				)
				( attribute "MATERIAL" "CHIP"
					( Origin gFrontEnd )
				)
				( attribute "PACK_TYPE" "0402"
					( Origin gFrontEnd )
				)
				( attribute "PART_NUMBER" "G21796-146"
					( Origin gFrontEnd )
				)
				( attribute "PHYS_PAGE" "196"
					( Origin gFrontEnd )
				)
				( attribute "ROOM" "V_SUPER"
					( Origin gFrontEnd )
				)
				( attribute "ROT" "0"
					( Origin gFrontEnd )
				)
				( attribute "SEC" "1"
					( Origin gFrontEnd )
				)
				( attribute "SEC_TYPE" "0402"
					( Origin gFrontEnd )
				)
				( attribute "TOLERANCE" "1%"
					( Origin gFrontEnd )
				)
				( attribute "VALUE" "6.34K"
					( Origin gFrontEnd )
				)
				( attribute "VER" "2"
					( Origin gFrontEnd )
				)
				( attribute "WATTAGE" "1/16W"
					( Origin gFrontEnd )
				)
				( attribute "XY" "(-525,4250)"
					( Origin gFrontEnd )
				)
				( attribute "CHIPS_PART_NAME" "RES"
					( Origin gPackager )
				)
				( attribute "CDS_PART_NAME" "RES_0402-6.34K,1%,1/16W,CHIP,GA"
					( Origin gPackager )
				)
				( objectStatus "R3P51" )
				( pin "a"
					( attribute "PN" "1"
						( Origin gPackager )
					)
					( objectStatus "R3P51.1" )
				)
				( pin "b"
					( attribute "PN" "2"
						( Origin gPackager )
					)
					( objectStatus "R3P51.2" )
				)
			)
			( gate "@baseboard_fab2_lib.baseboard_fab2(sch_1):page196_i80"
				( attribute "CDS_LIB" "mstr_analog"
					( Origin gPackager )
				)
				( attribute "CDS_LOCATION" "U1L3"
					( Origin gPackager )
				)
				( attribute "CDS_SEC" "1"
					( Origin gPackager )
				)
				( attribute "LOCATION" "U1L3"
					( Origin gFrontEnd )
				)
				( attribute "MATERIAL" "IC"
					( Origin gFrontEnd )
				)
				( attribute "PACK_TYPE" "SMLF"
					( Origin gFrontEnd )
				)
				( attribute "PART_NUMBER" "D23047-001"
					( Origin gFrontEnd )
				)
				( attribute "PHYS_PAGE" "196"
					( Origin gFrontEnd )
				)
				( attribute "ROOM" "V_SUPER"
					( Origin gFrontEnd )
				)
				( attribute "ROT" "0"
					( Origin gFrontEnd )
				)
				( attribute "SEC" "1"
					( Origin gPackager )
				)
				( attribute "VER" "1"
					( Origin gFrontEnd )
				)
				( attribute "XY" "(200,1350)"
					( Origin gFrontEnd )
				)
				( attribute "CHIPS_PART_NAME" "ADM809"
					( Origin gPackager )
				)
				( attribute "CDS_PART_NAME" "ADM809_SMLF-IC,D23047-001"
					( Origin gPackager )
				)
				( objectStatus "U1L3" )
				( pin "reset_n"
					( attribute "PN" "2"
						( Origin gPackager )
					)
					( objectStatus "U1L3.2" )
				)
				( pin "vcc"
					( attribute "PN" "3"
						( Origin gPackager )
					)
					( objectStatus "U1L3.3" )
				)
			)
			( gate "@baseboard_fab2_lib.baseboard_fab2(sch_1):page196_i81"
				( attribute "CDS_LIB" "dev_discrete"
					( Origin gPackager )
				)
				( attribute "CDS_LOCATION" "C1L16"
					( Origin gPackager )
				)
				( attribute "CDS_SEC" "1"
					( Origin gPackager )
				)
				( attribute "LOCATION" "C1L16"
					( Origin gFrontEnd )
				)
				( attribute "MATERIAL" "X7R"
					( Origin gFrontEnd )
				)
				( attribute "PACK_TYPE" "0402V"
					( Origin gFrontEnd )
				)
				( attribute "PART_NUMBER" "A36096-030"
					( Origin gFrontEnd )
				)
				( attribute "PHYS_PAGE" "196"
					( Origin gFrontEnd )
				)
				( attribute "ROOM" "V_SUPER"
					( Origin gFrontEnd )
				)
				( attribute "ROT" "0"
					( Origin gFrontEnd )
				)
				( attribute "SEC" "1"
					( Origin gPackager )
				)
				( attribute "TOLERANCE" "10%"
					( Origin gFrontEnd )
				)
				( attribute "VALUE" "0.1UF"
					( Origin gFrontEnd )
				)
				( attribute "VER" "1"
					( Origin gFrontEnd )
				)
				( attribute "VOLTAGE" "16V"
					( Units "uVoltage" "V" 1.000000)
					( Origin gFrontEnd )
				)
				( attribute "XY" "(-300,1250)"
					( Origin gFrontEnd )
				)
				( attribute "CHIPS_PART_NAME" "CAP_A"
					( Origin gPackager )
				)
				( attribute "CDS_PART_NAME" "CAP_A_0402V-0.1UF,16V,10%,X7R,A"
					( Origin gPackager )
				)
				( objectStatus "C1L16" )
				( pin "a"
					( attribute "PN" "1"
						( Origin gPackager )
					)
					( objectStatus "C1L16.1" )
				)
				( pin "b"
					( attribute "PN" "2"
						( Origin gPackager )
					)
					( objectStatus "C1L16.2" )
				)
			)
			( gate "@baseboard_fab2_lib.baseboard_fab2(sch_1):page196_i89"
				( attribute "CDS_LIB" "mstr_analog"
					( Origin gPackager )
				)
				( attribute "CDS_LOCATION" "U8E2"
					( Origin gPackager )
				)
				( attribute "CDS_SEC" "1"
					( Origin gPackager )
				)
				( attribute "LOCATION" "U8E2"
					( Origin gFrontEnd )
				)
				( attribute "MATERIAL" "IC"
					( Origin gFrontEnd )
				)
				( attribute "PACK_TYPE" "SMLF"
					( Origin gFrontEnd )
				)
				( attribute "PART_NUMBER" "D23047-001"
					( Origin gFrontEnd )
				)
				( attribute "PHYS_PAGE" "196"
					( Origin gFrontEnd )
				)
				( attribute "ROOM" "V_SUPER"
					( Origin gFrontEnd )
				)
				( attribute "ROT" "0"
					( Origin gFrontEnd )
				)
				( attribute "SEC" "1"
					( Origin gPackager )
				)
				( attribute "VER" "1"
					( Origin gFrontEnd )
				)
				( attribute "XY" "(400,3100)"
					( Origin gFrontEnd )
				)
				( attribute "CHIPS_PART_NAME" "ADM809"
					( Origin gPackager )
				)
				( attribute "CDS_PART_NAME" "ADM809_SMLF-IC,D23047-001"
					( Origin gPackager )
				)
				( objectStatus "U8E2" )
				( pin "reset_n"
					( attribute "PN" "2"
						( Origin gPackager )
					)
					( objectStatus "U8E2.2" )
				)
				( pin "vcc"
					( attribute "PN" "3"
						( Origin gPackager )
					)
					( objectStatus "U8E2.3" )
				)
			)
			( gate "@baseboard_fab2_lib.baseboard_fab2(sch_1):page196_i90"
				( attribute "CDS_LIB" "mstr_discrete"
					( Origin gPackager )
				)
				( attribute "CDS_LOCATION" "R8E7"
					( Origin gPackager )
				)
				( attribute "CDS_SEC" "1"
					( Origin gPackager )
				)
				( attribute "LOCATION" "R8E7"
					( Origin gFrontEnd )
				)
				( attribute "MATERIAL" "CHIP"
					( Origin gFrontEnd )
				)
				( attribute "PACK_TYPE" "0402"
					( Origin gFrontEnd )
				)
				( attribute "PART_NUMBER" "G21796-250"
					( Origin gFrontEnd )
				)
				( attribute "PHYS_PAGE" "196"
					( Origin gFrontEnd )
				)
				( attribute "ROOM" "V_SUPER"
					( Origin gFrontEnd )
				)
				( attribute "ROT" "0"
					( Origin gFrontEnd )
				)
				( attribute "SEC" "1"
					( Origin gFrontEnd )
				)
				( attribute "SEC_TYPE" "0402"
					( Origin gFrontEnd )
				)
				( attribute "TOLERANCE" "1.0%"
					( Origin gFrontEnd )
				)
				( attribute "VALUE" "22.1"
					( Origin gFrontEnd )
				)
				( attribute "VER" "1"
					( Origin gFrontEnd )
				)
				( attribute "WATTAGE" "1/16W"
					( Origin gFrontEnd )
				)
				( attribute "XY" "(1200,3000)"
					( Origin gFrontEnd )
				)
				( attribute "CHIPS_PART_NAME" "RES"
					( Origin gPackager )
				)
				( attribute "CDS_PART_NAME" "RES_0402-22.1,1.0%,1/16W,CHIP,A"
					( Origin gPackager )
				)
				( objectStatus "R8E7" )
				( pin "a"
					( attribute "PN" "1"
						( Origin gPackager )
					)
					( objectStatus "R8E7.1" )
				)
				( pin "b"
					( attribute "PN" "2"
						( Origin gPackager )
					)
					( objectStatus "R8E7.2" )
				)
			)
			( gate "@baseboard_fab2_lib.baseboard_fab2(sch_1):page196_i94"
				( attribute "CDS_LIB" "dev_discrete"
					( Origin gPackager )
				)
				( attribute "CDS_LOCATION" "C8E3"
					( Origin gPackager )
				)
				( attribute "CDS_SEC" "1"
					( Origin gPackager )
				)
				( attribute "LOCATION" "C8E3"
					( Origin gFrontEnd )
				)
				( attribute "MATERIAL" "X7R"
					( Origin gFrontEnd )
				)
				( attribute "PACK_TYPE" "0402V"
					( Origin gFrontEnd )
				)
				( attribute "PART_NUMBER" "A36096-030"
					( Origin gFrontEnd )
				)
				( attribute "PHYS_PAGE" "196"
					( Origin gFrontEnd )
				)
				( attribute "ROOM" "V_SUPER"
					( Origin gFrontEnd )
				)
				( attribute "ROT" "0"
					( Origin gFrontEnd )
				)
				( attribute "SEC" "1"
					( Origin gFrontEnd )
				)
				( attribute "SEC_TYPE" "0402V"
					( Origin gFrontEnd )
				)
				( attribute "TOLERANCE" "10%"
					( Origin gFrontEnd )
				)
				( attribute "VALUE" "0.1UF"
					( Origin gFrontEnd )
				)
				( attribute "VER" "1"
					( Origin gFrontEnd )
				)
				( attribute "VOLTAGE" "16V"
					( Units "uVoltage" "V" 1.000000)
					( Origin gFrontEnd )
				)
				( attribute "XY" "(-300,2950)"
					( Origin gFrontEnd )
				)
				( attribute "CHIPS_PART_NAME" "CAP_A"
					( Origin gPackager )
				)
				( attribute "CDS_PART_NAME" "CAP_A_0402V-0.1UF,16V,10%,X7R,A"
					( Origin gPackager )
				)
				( objectStatus "C8E3" )
				( pin "a"
					( attribute "PN" "1"
						( Origin gPackager )
					)
					( objectStatus "C8E3.1" )
				)
				( pin "b"
					( attribute "PN" "2"
						( Origin gPackager )
					)
					( objectStatus "C8E3.2" )
				)
			)
			( gate "@baseboard_fab2_lib.baseboard_fab2(sch_1):page196_i102"
				( attribute "BOM_COST" "SB"
					( Origin gFrontEnd )
				)
				( attribute "CDS_LIB" "dev_discrete"
					( Origin gPackager )
				)
				( attribute "CDS_LOCATION" "C2U26"
					( Origin gPackager )
				)
				( attribute "CDS_SEC" "1"
					( Origin gPackager )
				)
				( attribute "LOCATION" "C2U26"
					( Origin gFrontEnd )
				)
				( attribute "MATERIAL" "X6S"
					( Origin gFrontEnd )
				)
				( attribute "NO_XNET_CONNECTION" "1"
					( Origin gFrontEnd )
				)
				( attribute "PACK_TYPE" "0402V"
					( Origin gFrontEnd )
				)
				( attribute "PART_NUMBER" "D97712-004"
					( Origin gFrontEnd )
				)
				( attribute "PHYS_PAGE" "196"
					( Origin gFrontEnd )
				)
				( attribute "ROOM" "SB_VRD"
					( Origin gFrontEnd )
				)
				( attribute "ROT" "0"
					( Origin gFrontEnd )
				)
				( attribute "SEC" "1"
					( Origin gFrontEnd )
				)
				( attribute "SEC_TYPE" "0402V"
					( Origin gFrontEnd )
				)
				( attribute "TOLERANCE" "10%"
					( Origin gFrontEnd )
				)
				( attribute "VALUE" "1.0UF"
					( Origin gFrontEnd )
				)
				( attribute "VER" "1"
					( Origin gFrontEnd )
				)
				( attribute "VOLTAGE" "6.3V"
					( Units "uVoltage" "V" 1.000000)
					( Origin gFrontEnd )
				)
				( attribute "XY" "(-2200,4500)"
					( Origin gFrontEnd )
				)
				( attribute "CHIPS_PART_NAME" "CAP_A"
					( Origin gPackager )
				)
				( attribute "CDS_PART_NAME" "CAP_A_0402V-1.0UF,6.3V,10%,X6SA"
					( Origin gPackager )
				)
				( objectStatus "C2U26" )
				( pin "a"
					( attribute "PN" "1"
						( Origin gPackager )
					)
					( objectStatus "C2U26.1" )
				)
				( pin "b"
					( attribute "PN" "2"
						( Origin gPackager )
					)
					( objectStatus "C2U26.2" )
				)
			)
			( gate "@baseboard_fab2_lib.baseboard_fab2(sch_1):page196_i103"
				( attribute "CDS_LIB" "mstr_discrete"
					( Origin gPackager )
				)
				( attribute "CDS_LOCATION" "CR7E1"
					( Origin gPackager )
				)
				( attribute "CDS_SEC" "1"
					( Origin gPackager )
				)
				( attribute "LOCATION" "CR7E1"
					( Origin gFrontEnd )
				)
				( attribute "MATERIAL" "IC"
					( Origin gFrontEnd )
				)
				( attribute "PACK_TYPE" "SMLF"
					( Origin gFrontEnd )
				)
				( attribute "PART_NUMBER" "C73510-001"
					( Origin gFrontEnd )
				)
				( attribute "PHYS_PAGE" "196"
					( Origin gFrontEnd )
				)
				( attribute "ROT" "0"
					( Origin gFrontEnd )
				)
				( attribute "SEC" "1"
					( Origin gFrontEnd )
				)
				( attribute "SEC_TYPE" "SMLF"
					( Origin gFrontEnd )
				)
				( attribute "VALUE" "BAT54WS"
					( Origin gFrontEnd )
				)
				( attribute "VER" "3"
					( Origin gFrontEnd )
				)
				( attribute "XY" "(825,3650)"
					( Origin gFrontEnd )
				)
				( attribute "CHIPS_PART_NAME" "DIODE"
					( Origin gPackager )
				)
				( attribute "CDS_PART_NAME" "DIODE_SMLF-BAT54WS,IC,C73510-0A"
					( Origin gPackager )
				)
				( objectStatus "CR7E1" )
				( pin "a"
					( attribute "PN" "2"
						( Origin gPackager )
					)
					( objectStatus "CR7E1.2" )
				)
				( pin "c"
					( attribute "PN" "1"
						( Origin gPackager )
					)
					( objectStatus "CR7E1.1" )
				)
			)
			( gate "@baseboard_fab2_lib.baseboard_fab2(sch_1):page196_i104"
				( attribute "CDS_LIB" "mstr_vreg"
					( Origin gPackager )
				)
				( attribute "CDS_LMAN_SYM_OUTLINE" "-250,200,250,-200"
					( Origin gPackager )
				)
				( attribute "CDS_LOCATION" "U8D8"
					( Origin gPackager )
				)
				( attribute "CDS_SEC" "1"
					( Origin gPackager )
				)
				( attribute "LOCATION" "U8D8"
					( Origin gFrontEnd )
				)
				( attribute "MATERIAL" "IC"
					( Origin gFrontEnd )
				)
				( attribute "PACK_TYPE" "SM"
					( Origin gFrontEnd )
				)
				( attribute "PART_NUMBER" "H69492-001"
					( Origin gFrontEnd )
				)
				( attribute "PHYS_PAGE" "196"
					( Origin gFrontEnd )
				)
				( attribute "ROOM" "V_SUPER"
					( Origin gFrontEnd )
				)
				( attribute "ROT" "0"
					( Origin gFrontEnd )
				)
				( attribute "SEC" "1"
					( Origin gPackager )
				)
				( attribute "VER" "1"
					( Origin gFrontEnd )
				)
				( attribute "XY" "(-500,2300)"
					( Origin gFrontEnd )
				)
				( attribute "CHIPS_PART_NAME" "TPS3700"
					( Origin gPackager )
				)
				( attribute "CDS_PART_NAME" "TPS3700_SM-IC,H69492-001"
					( Origin gPackager )
				)
				( objectStatus "U8D8" )
				( pin "gnd"
					( attribute "PN" "5"
						( Origin gPackager )
					)
					( objectStatus "U8D8.5" )
				)
				( pin "inap"
					( attribute "PN" "4"
						( Origin gPackager )
					)
					( objectStatus "U8D8.4" )
				)
				( pin "inbn"
					( attribute "PN" "3"
						( Origin gPackager )
					)
					( objectStatus "U8D8.3" )
				)
				( pin "outa"
					( attribute "PN" "6"
						( Origin gPackager )
					)
					( objectStatus "U8D8.6" )
				)
				( pin "outb"
					( attribute "PN" "1"
						( Origin gPackager )
					)
					( objectStatus "U8D8.1" )
				)
				( pin "vdd"
					( attribute "PN" "2"
						( Origin gPackager )
					)
					( objectStatus "U8D8.2" )
				)
			)
			( gate "@baseboard_fab2_lib.baseboard_fab2(sch_1):page196_i105"
				( attribute "CDS_LIB" "dev_discrete"
					( Origin gPackager )
				)
				( attribute "CDS_LOCATION" "C8D4"
					( Origin gPackager )
				)
				( attribute "CDS_SEC" "1"
					( Origin gPackager )
				)
				( attribute "LOCATION" "C8D4"
					( Origin gFrontEnd )
				)
				( attribute "MATERIAL" "X7R"
					( Origin gFrontEnd )
				)
				( attribute "PACK_TYPE" "0402V"
					( Origin gFrontEnd )
				)
				( attribute "PART_NUMBER" "A36096-030"
					( Origin gFrontEnd )
				)
				( attribute "PHYS_PAGE" "196"
					( Origin gFrontEnd )
				)
				( attribute "ROOM" "V_SUPER"
					( Origin gFrontEnd )
				)
				( attribute "ROT" "0"
					( Origin gFrontEnd )
				)
				( attribute "SEC" "1"
					( Origin gPackager )
				)
				( attribute "TOLERANCE" "10%"
					( Origin gFrontEnd )
				)
				( attribute "VALUE" "0.1UF"
					( Origin gFrontEnd )
				)
				( attribute "VER" "1"
					( Origin gFrontEnd )
				)
				( attribute "VOLTAGE" "16V"
					( Units "uVoltage" "V" 1.000000)
					( Origin gFrontEnd )
				)
				( attribute "XY" "(-1000,1950)"
					( Origin gFrontEnd )
				)
				( attribute "CHIPS_PART_NAME" "CAP_A"
					( Origin gPackager )
				)
				( attribute "CDS_PART_NAME" "CAP_A_0402V-0.1UF,16V,10%,X7R,A"
					( Origin gPackager )
				)
				( objectStatus "C8D4" )
				( pin "a"
					( attribute "PN" "1"
						( Origin gPackager )
					)
					( objectStatus "C8D4.1" )
				)
				( pin "b"
					( attribute "PN" "2"
						( Origin gPackager )
					)
					( objectStatus "C8D4.2" )
				)
			)
			( gate "@baseboard_fab2_lib.baseboard_fab2(sch_1):page196_i106"
				( attribute "CDS_LIB" "mstr_discrete"
					( Origin gPackager )
				)
				( attribute "CDS_LOCATION" "R8D42"
					( Origin gPackager )
				)
				( attribute "CDS_SEC" "1"
					( Origin gPackager )
				)
				( attribute "LOCATION" "R8D42"
					( Origin gFrontEnd )
				)
				( attribute "MATERIAL" "CHIP"
					( Origin gFrontEnd )
				)
				( attribute "PACK_TYPE" "0402"
					( Origin gFrontEnd )
				)
				( attribute "PART_NUMBER" "G21796-017"
					( Origin gFrontEnd )
				)
				( attribute "PHYS_PAGE" "196"
					( Origin gFrontEnd )
				)
				( attribute "ROOM" "V_SUPER"
					( Origin gFrontEnd )
				)
				( attribute "ROT" "0"
					( Origin gFrontEnd )
				)
				( attribute "SEC" "1"
					( Origin gFrontEnd )
				)
				( attribute "SEC_TYPE" "0402"
					( Origin gFrontEnd )
				)
				( attribute "TOLERANCE" "1%"
					( Origin gFrontEnd )
				)
				( attribute "VALUE" "100.0"
					( Origin gFrontEnd )
				)
				( attribute "VER" "1"
					( Origin gFrontEnd )
				)
				( attribute "WATTAGE" "1/16W"
					( Origin gFrontEnd )
				)
				( attribute "XY" "(1350,2400)"
					( Origin gFrontEnd )
				)
				( attribute "CHIPS_PART_NAME" "RES"
					( Origin gPackager )
				)
				( attribute "CDS_PART_NAME" "RES_0402-100.0,1%,1/16W,CHIP,GA"
					( Origin gPackager )
				)
				( objectStatus "R8D42" )
				( pin "a"
					( attribute "PN" "1"
						( Origin gPackager )
					)
					( objectStatus "R8D42.1" )
				)
				( pin "b"
					( attribute "PN" "2"
						( Origin gPackager )
					)
					( objectStatus "R8D42.2" )
				)
			)
			( gate "@baseboard_fab2_lib.baseboard_fab2(sch_1):page196_i112"
				( attribute "CDS_LIB" "mstr_discrete"
					( Origin gPackager )
				)
				( attribute "CDS_LOCATION" "R8D38"
					( Origin gPackager )
				)
				( attribute "CDS_SEC" "1"
					( Origin gPackager )
				)
				( attribute "LOCATION" "R8D38"
					( Origin gFrontEnd )
				)
				( attribute "MATERIAL" "CHIP"
					( Origin gFrontEnd )
				)
				( attribute "PACK_TYPE" "0402"
					( Origin gFrontEnd )
				)
				( attribute "PART_NUMBER" "G21796-010"
					( Origin gFrontEnd )
				)
				( attribute "PHYS_PAGE" "196"
					( Origin gFrontEnd )
				)
				( attribute "ROOM" "V_SUPER"
					( Origin gFrontEnd )
				)
				( attribute "ROT" "0"
					( Origin gFrontEnd )
				)
				( attribute "SEC" "1"
					( Origin gFrontEnd )
				)
				( attribute "SEC_TYPE" "0402"
					( Origin gFrontEnd )
				)
				( attribute "TOLERANCE" "1%"
					( Origin gFrontEnd )
				)
				( attribute "VALUE" "100.0K"
					( Origin gFrontEnd )
				)
				( attribute "VER" "2"
					( Origin gFrontEnd )
				)
				( attribute "WATTAGE" "1/16W"
					( Origin gFrontEnd )
				)
				( attribute "XY" "(-1750,2800)"
					( Origin gFrontEnd )
				)
				( attribute "CHIPS_PART_NAME" "RES"
					( Origin gPackager )
				)
				( attribute "CDS_PART_NAME" "RES_0402-100.0K,1%,1/16W,CHIP,A"
					( Origin gPackager )
				)
				( objectStatus "R8D38" )
				( pin "a"
					( attribute "PN" "1"
						( Origin gPackager )
					)
					( objectStatus "R8D38.1" )
				)
				( pin "b"
					( attribute "PN" "2"
						( Origin gPackager )
					)
					( objectStatus "R8D38.2" )
				)
			)
			( gate "@baseboard_fab2_lib.baseboard_fab2(sch_1):page196_i113"
				( attribute "CDS_LIB" "mstr_discrete"
					( Origin gPackager )
				)
				( attribute "CDS_LOCATION" "R8D40"
					( Origin gPackager )
				)
				( attribute "CDS_SEC" "1"
					( Origin gPackager )
				)
				( attribute "LOCATION" "R8D40"
					( Origin gFrontEnd )
				)
				( attribute "MATERIAL" "CHIP"
					( Origin gFrontEnd )
				)
				( attribute "PACK_TYPE" "0402"
					( Origin gFrontEnd )
				)
				( attribute "PART_NUMBER" "G21796-059"
					( Origin gFrontEnd )
				)
				( attribute "PHYS_PAGE" "196"
					( Origin gFrontEnd )
				)
				( attribute "ROOM" "V_SUPER"
					( Origin gFrontEnd )
				)
				( attribute "ROT" "0"
					( Origin gFrontEnd )
				)
				( attribute "SEC" "1"
					( Origin gFrontEnd )
				)
				( attribute "SEC_TYPE" "0402"
					( Origin gFrontEnd )
				)
				( attribute "TOLERANCE" "1%"
					( Origin gFrontEnd )
				)
				( attribute "VALUE" "3.74K"
					( Origin gFrontEnd )
				)
				( attribute "VER" "2"
					( Origin gFrontEnd )
				)
				( attribute "WATTAGE" "1/16W"
					( Origin gFrontEnd )
				)
				( attribute "XY" "(-1750,2400)"
					( Origin gFrontEnd )
				)
				( attribute "CHIPS_PART_NAME" "RES"
					( Origin gPackager )
				)
				( attribute "CDS_PART_NAME" "RES_0402-3.74K,1%,1/16W,CHIP,GA"
					( Origin gPackager )
				)
				( objectStatus "R8D40" )
				( pin "a"
					( attribute "PN" "1"
						( Origin gPackager )
					)
					( objectStatus "R8D40.1" )
				)
				( pin "b"
					( attribute "PN" "2"
						( Origin gPackager )
					)
					( objectStatus "R8D40.2" )
				)
			)
			( gate "@baseboard_fab2_lib.baseboard_fab2(sch_1):page196_i114"
				( attribute "CDS_LIB" "mstr_discrete"
					( Origin gPackager )
				)
				( attribute "CDS_LOCATION" "R8D39"
					( Origin gPackager )
				)
				( attribute "CDS_SEC" "1"
					( Origin gPackager )
				)
				( attribute "LOCATION" "R8D39"
					( Origin gFrontEnd )
				)
				( attribute "MATERIAL" "CHIP"
					( Origin gFrontEnd )
				)
				( attribute "PACK_TYPE" "0402"
					( Origin gFrontEnd )
				)
				( attribute "PART_NUMBER" "G21796-048"
					( Origin gFrontEnd )
				)
				( attribute "PHYS_PAGE" "196"
					( Origin gFrontEnd )
				)
				( attribute "ROOM" "V_SUPER"
					( Origin gFrontEnd )
				)
				( attribute "ROT" "0"
					( Origin gFrontEnd )
				)
				( attribute "SEC" "1"
					( Origin gFrontEnd )
				)
				( attribute "SEC_TYPE" "0402"
					( Origin gFrontEnd )
				)
				( attribute "TOLERANCE" "1%"
					( Origin gFrontEnd )
				)
				( attribute "VALUE" "49.9K"
					( Origin gFrontEnd )
				)
				( attribute "VER" "2"
					( Origin gFrontEnd )
				)
				( attribute "WATTAGE" "1/16W"
					( Origin gFrontEnd )
				)
				( attribute "XY" "(-1750,1850)"
					( Origin gFrontEnd )
				)
				( attribute "CHIPS_PART_NAME" "RES"
					( Origin gPackager )
				)
				( attribute "CDS_PART_NAME" "RES_0402-49.9K,1%,1/16W,CHIP,GA"
					( Origin gPackager )
				)
				( objectStatus "R8D39" )
				( pin "a"
					( attribute "PN" "1"
						( Origin gPackager )
					)
					( objectStatus "R8D39.1" )
				)
				( pin "b"
					( attribute "PN" "2"
						( Origin gPackager )
					)
					( objectStatus "R8D39.2" )
				)
			)
			( gate "@baseboard_fab2_lib.baseboard_fab2(sch_1):page196_i115"
				( attribute "CDS_LIB" "mstr_discrete"
					( Origin gPackager )
				)
				( attribute "CDS_LOCATION" "R8D37"
					( Origin gPackager )
				)
				( attribute "CDS_SEC" "1"
					( Origin gPackager )
				)
				( attribute "LOCATION" "R8D37"
					( Origin gFrontEnd )
				)
				( attribute "MATERIAL" "CHIP"
					( Origin gFrontEnd )
				)
				( attribute "PACK_TYPE" "0402"
					( Origin gFrontEnd )
				)
				( attribute "PART_NUMBER" "G21796-072"
					( Origin gFrontEnd )
				)
				( attribute "PHYS_PAGE" "196"
					( Origin gFrontEnd )
				)
				( attribute "ROOM" "V_SUPER"
					( Origin gFrontEnd )
				)
				( attribute "ROT" "0"
					( Origin gFrontEnd )
				)
				( attribute "SEC" "1"
					( Origin gFrontEnd )
				)
				( attribute "SEC_TYPE" "0402"
					( Origin gFrontEnd )
				)
				( attribute "TOLERANCE" "1%"
					( Origin gFrontEnd )
				)
				( attribute "VALUE" "4.75K"
					( Origin gFrontEnd )
				)
				( attribute "VER" "2"
					( Origin gFrontEnd )
				)
				( attribute "WATTAGE" "1/16W"
					( Origin gFrontEnd )
				)
				( attribute "XY" "(-1750,1450)"
					( Origin gFrontEnd )
				)
				( attribute "CHIPS_PART_NAME" "RES"
					( Origin gPackager )
				)
				( attribute "CDS_PART_NAME" "RES_0402-4.75K,1%,1/16W,CHIP,GA"
					( Origin gPackager )
				)
				( objectStatus "R8D37" )
				( pin "a"
					( attribute "PN" "1"
						( Origin gPackager )
					)
					( objectStatus "R8D37.1" )
				)
				( pin "b"
					( attribute "PN" "2"
						( Origin gPackager )
					)
					( objectStatus "R8D37.2" )
				)
			)
			( gate "@baseboard_fab2_lib.baseboard_fab2(sch_1):page196_i120"
				( attribute "CDS_LIB" "mstr_discrete"
					( Origin gPackager )
				)
				( attribute "CDS_LOCATION" "R8D41"
					( Origin gPackager )
				)
				( attribute "CDS_SEC" "1"
					( Origin gPackager )
				)
				( attribute "LOCATION" "R8D41"
					( Origin gFrontEnd )
				)
				( attribute "MATERIAL" "CHIP"
					( Origin gFrontEnd )
				)
				( attribute "PACK_TYPE" "0402"
					( Origin gFrontEnd )
				)
				( attribute "PART_NUMBER" "G21796-016"
					( Origin gFrontEnd )
				)
				( attribute "PHYS_PAGE" "196"
					( Origin gFrontEnd )
				)
				( attribute "ROOM" "V_SUPER"
					( Origin gFrontEnd )
				)
				( attribute "ROT" "0"
					( Origin gFrontEnd )
				)
				( attribute "SEC" "1"
					( Origin gFrontEnd )
				)
				( attribute "SEC_TYPE" "0402"
					( Origin gFrontEnd )
				)
				( attribute "TOLERANCE" "1%"
					( Origin gFrontEnd )
				)
				( attribute "VALUE" "10.0K"
					( Origin gFrontEnd )
				)
				( attribute "VER" "2"
					( Origin gFrontEnd )
				)
				( attribute "WATTAGE" "1/16W"
					( Origin gFrontEnd )
				)
				( attribute "XY" "(50,2650)"
					( Origin gFrontEnd )
				)
				( attribute "CHIPS_PART_NAME" "RES"
					( Origin gPackager )
				)
				( attribute "CDS_PART_NAME" "RES_0402-10.0K,1%,1/16W,CHIP,GA"
					( Origin gPackager )
				)
				( objectStatus "R8D41" )
				( pin "a"
					( attribute "PN" "1"
						( Origin gPackager )
					)
					( objectStatus "R8D41.1" )
				)
				( pin "b"
					( attribute "PN" "2"
						( Origin gPackager )
					)
					( objectStatus "R8D41.2" )
				)
			)
			( gate "@baseboard_fab2_lib.baseboard_fab2(sch_1):page196_i121"
				( attribute "CDS_LIB" "mstr_discrete"
					( Origin gPackager )
				)
				( attribute "CDS_LOCATION" "R2P18"
					( Origin gPackager )
				)
				( attribute "CDS_SEC" "1"
					( Origin gPackager )
				)
				( attribute "LOCATION" "R2P18"
					( Origin gFrontEnd )
				)
				( attribute "MATERIAL" "CHIP"
					( Origin gFrontEnd )
				)
				( attribute "PACK_TYPE" "0402"
					( Origin gFrontEnd )
				)
				( attribute "PART_NUMBER" "G21796-016"
					( Origin gFrontEnd )
				)
				( attribute "PHYS_PAGE" "196"
					( Origin gFrontEnd )
				)
				( attribute "ROOM" "V_SUPER"
					( Origin gFrontEnd )
				)
				( attribute "ROT" "0"
					( Origin gFrontEnd )
				)
				( attribute "SEC" "1"
					( Origin gFrontEnd )
				)
				( attribute "SEC_TYPE" "0402"
					( Origin gFrontEnd )
				)
				( attribute "TOLERANCE" "1%"
					( Origin gFrontEnd )
				)
				( attribute "VALUE" "10.0K"
					( Origin gFrontEnd )
				)
				( attribute "VER" "2"
					( Origin gFrontEnd )
				)
				( attribute "WATTAGE" "1/16W"
					( Origin gFrontEnd )
				)
				( attribute "XY" "(250,2000)"
					( Origin gFrontEnd )
				)
				( attribute "CHIPS_PART_NAME" "RES"
					( Origin gPackager )
				)
				( attribute "CDS_PART_NAME" "RES_0402-10.0K,1%,1/16W,CHIP,GA"
					( Origin gPackager )
				)
				( objectStatus "R2P18" )
				( pin "a"
					( attribute "PN" "1"
						( Origin gPackager )
					)
					( objectStatus "R2P18.1" )
				)
				( pin "b"
					( attribute "PN" "2"
						( Origin gPackager )
					)
					( objectStatus "R2P18.2" )
				)
			)
			( gate "@baseboard_fab2_lib.baseboard_fab2(sch_1):page196_i122"
				( attribute "CDS_LIB" "mstr_discrete"
					( Origin gPackager )
				)
				( attribute "CDS_LOCATION" "R2P21"
					( Origin gPackager )
				)
				( attribute "CDS_SEC" "1"
					( Origin gPackager )
				)
				( attribute "LOCATION" "R2P21"
					( Origin gFrontEnd )
				)
				( attribute "MATERIAL" "CHIP"
					( Origin gFrontEnd )
				)
				( attribute "PACK_TYPE" "0402"
					( Origin gFrontEnd )
				)
				( attribute "PART_NUMBER" "G21796-016"
					( Origin gFrontEnd )
				)
				( attribute "PHYS_PAGE" "196"
					( Origin gFrontEnd )
				)
				( attribute "ROOM" "V_SUPER"
					( Origin gFrontEnd )
				)
				( attribute "ROT" "0"
					( Origin gFrontEnd )
				)
				( attribute "SEC" "1"
					( Origin gFrontEnd )
				)
				( attribute "SEC_TYPE" "0402"
					( Origin gFrontEnd )
				)
				( attribute "TOLERANCE" "1%"
					( Origin gFrontEnd )
				)
				( attribute "VALUE" "10.0K"
					( Origin gFrontEnd )
				)
				( attribute "VER" "2"
					( Origin gFrontEnd )
				)
				( attribute "WATTAGE" "1/16W"
					( Origin gFrontEnd )
				)
				( attribute "XY" "(750,2200)"
					( Origin gFrontEnd )
				)
				( attribute "CHIPS_PART_NAME" "RES"
					( Origin gPackager )
				)
				( attribute "CDS_PART_NAME" "RES_0402-10.0K,1%,1/16W,CHIP,GA"
					( Origin gPackager )
				)
				( objectStatus "R2P21" )
				( pin "a"
					( attribute "PN" "1"
						( Origin gPackager )
					)
					( objectStatus "R2P21.1" )
				)
				( pin "b"
					( attribute "PN" "2"
						( Origin gPackager )
					)
					( objectStatus "R2P21.2" )
				)
			)
			( gate "@baseboard_fab2_lib.baseboard_fab2(sch_1):page196_i124"
				( attribute "CDS_LIB" "mstr_discrete"
					( Origin gPackager )
				)
				( attribute "CDS_LOCATION" "Q2P2"
					( Origin gPackager )
				)
				( attribute "CDS_SEC" "1"
					( Origin gPackager )
				)
				( attribute "LOCATION" "Q2P2"
					( Origin gFrontEnd )
				)
				( attribute "MATERIAL" "FET"
					( Origin gFrontEnd )
				)
				( attribute "PACK_TYPE" "SOT23"
					( Origin gFrontEnd )
				)
				( attribute "PART_NUMBER" "C79254-001"
					( Origin gFrontEnd )
				)
				( attribute "PHYS_PAGE" "196"
					( Origin gFrontEnd )
				)
				( attribute "ROOM" "V_SUPER"
					( Origin gFrontEnd )
				)
				( attribute "ROT" "0"
					( Origin gFrontEnd )
				)
				( attribute "SEC" "1"
					( Origin gPackager )
				)
				( attribute "VALUE" "2N7002"
					( Origin gFrontEnd )
				)
				( attribute "VER" "8"
					( Origin gFrontEnd )
				)
				( attribute "XY" "(750,1750)"
					( Origin gFrontEnd )
				)
				( attribute "CHIPS_PART_NAME" "FET_N"
					( Origin gPackager )
				)
				( attribute "CDS_PART_NAME" "FET_N_SOT23-2N7002,FET,C79254-A"
					( Origin gPackager )
				)
				( objectStatus "Q2P2" )
				( pin "drn"
					( attribute "PN" "3"
						( Origin gPackager )
					)
					( objectStatus "Q2P2.3" )
				)
				( pin "gate"
					( attribute "PN" "1"
						( Origin gPackager )
					)
					( objectStatus "Q2P2.1" )
				)
				( pin "src"
					( attribute "PN" "2"
						( Origin gPackager )
					)
					( objectStatus "Q2P2.2" )
				)
			)
			( gate "@baseboard_fab2_lib.baseboard_fab2(sch_1):page196_i128"
				( attribute "CDS_LIB" "mstr_discrete"
					( Origin gPackager )
				)
				( attribute "CDS_LOCATION" "CR8E1"
					( Origin gPackager )
				)
				( attribute "CDS_SEC" "1"
					( Origin gPackager )
				)
				( attribute "LOCATION" "CR8E1"
					( Origin gFrontEnd )
				)
				( attribute "MATERIAL" "IC"
					( Origin gFrontEnd )
				)
				( attribute "PACK_TYPE" "SMLF"
					( Origin gFrontEnd )
				)
				( attribute "PART_NUMBER" "C73510-001"
					( Origin gFrontEnd )
				)
				( attribute "PHYS_PAGE" "196"
					( Origin gFrontEnd )
				)
				( attribute "ROT" "0"
					( Origin gFrontEnd )
				)
				( attribute "SEC" "1"
					( Origin gFrontEnd )
				)
				( attribute "SEC_TYPE" "SMLF"
					( Origin gFrontEnd )
				)
				( attribute "VALUE" "BAT54WS"
					( Origin gFrontEnd )
				)
				( attribute "VER" "3"
					( Origin gFrontEnd )
				)
				( attribute "XY" "(1050,3400)"
					( Origin gFrontEnd )
				)
				( attribute "CHIPS_PART_NAME" "DIODE"
					( Origin gPackager )
				)
				( attribute "CDS_PART_NAME" "DIODE_SMLF-BAT54WS,IC,C73510-0A"
					( Origin gPackager )
				)
				( objectStatus "CR8E1" )
				( pin "a"
					( attribute "PN" "2"
						( Origin gPackager )
					)
					( objectStatus "CR8E1.2" )
				)
				( pin "c"
					( attribute "PN" "1"
						( Origin gPackager )
					)
					( objectStatus "CR8E1.1" )
				)
			)
			( gate "@baseboard_fab2_lib.baseboard_fab2(sch_1):page197_i52"
				( attribute "CDS_LIB" "mstr_discrete"
					( Origin gPackager )
				)
				( attribute "CDS_LOCATION" "C6U18"
					( Origin gPackager )
				)
				( attribute "CDS_SEC" "1"
					( Origin gPackager )
				)
				( attribute "LOCATION" "C6U18"
					( Origin gFrontEnd )
				)
				( attribute "MATERIAL" "X7R"
					( Origin gFrontEnd )
				)
				( attribute "PACK_TYPE" "0805"
					( Origin gFrontEnd )
				)
				( attribute "PART_NUMBER" "G10601-001"
					( Origin gFrontEnd )
				)
				( attribute "PHYS_PAGE" "197"
					( Origin gFrontEnd )
				)
				( attribute "ROOM" "PVDDQ_ABC_PWR_VR"
					( Origin gFrontEnd )
				)
				( attribute "ROT" "0"
					( Origin gFrontEnd )
				)
				( attribute "SEC" "1"
					( Origin gPackager )
				)
				( attribute "TOLERANCE" "10%"
					( Origin gFrontEnd )
				)
				( attribute "VALUE" "10UF"
					( Origin gFrontEnd )
				)
				( attribute "VER" "1"
					( Origin gFrontEnd )
				)
				( attribute "VOLTAGE" "16V"
					( Units "uVoltage" "V" 1.000000)
					( Origin gFrontEnd )
				)
				( attribute "XY" "(-825,1625)"
					( Origin gFrontEnd )
				)
				( attribute "CHIPS_PART_NAME" "CAP"
					( Origin gPackager )
				)
				( attribute "CDS_PART_NAME" "CAP_0805-10UF,16V,10%,X7R,G106A"
					( Origin gPackager )
				)
				( objectStatus "C6U18" )
				( pin "a"
					( attribute "PN" "1"
						( Origin gPackager )
					)
					( objectStatus "C6U18.1" )
				)
				( pin "b"
					( attribute "PN" "2"
						( Origin gPackager )
					)
					( objectStatus "C6U18.2" )
				)
			)
			( gate "@baseboard_fab2_lib.baseboard_fab2(sch_1):page197_i54"
				( attribute "CDS_LIB" "mstr_discrete"
					( Origin gPackager )
				)
				( attribute "CDS_LOCATION" "C6T2"
					( Origin gPackager )
				)
				( attribute "CDS_SEC" "1"
					( Origin gPackager )
				)
				( attribute "LOCATION" "C6T2"
					( Origin gFrontEnd )
				)
				( attribute "MATERIAL" "X7R"
					( Origin gFrontEnd )
				)
				( attribute "PACK_TYPE" "0805"
					( Origin gFrontEnd )
				)
				( attribute "PART_NUMBER" "G10601-001"
					( Origin gFrontEnd )
				)
				( attribute "PHYS_PAGE" "197"
					( Origin gFrontEnd )
				)
				( attribute "ROOM" "PVDDQ_ABC_PWR_VR"
					( Origin gFrontEnd )
				)
				( attribute "ROT" "0"
					( Origin gFrontEnd )
				)
				( attribute "SEC" "1"
					( Origin gPackager )
				)
				( attribute "TOLERANCE" "10%"
					( Origin gFrontEnd )
				)
				( attribute "VALUE" "10UF"
					( Origin gFrontEnd )
				)
				( attribute "VER" "1"
					( Origin gFrontEnd )
				)
				( attribute "VOLTAGE" "16V"
					( Units "uVoltage" "V" 1.000000)
					( Origin gFrontEnd )
				)
				( attribute "XY" "(-825,2200)"
					( Origin gFrontEnd )
				)
				( attribute "CHIPS_PART_NAME" "CAP"
					( Origin gPackager )
				)
				( attribute "CDS_PART_NAME" "CAP_0805-10UF,16V,10%,X7R,G106A"
					( Origin gPackager )
				)
				( objectStatus "C6T2" )
				( pin "a"
					( attribute "PN" "1"
						( Origin gPackager )
					)
					( objectStatus "C6T2.1" )
				)
				( pin "b"
					( attribute "PN" "2"
						( Origin gPackager )
					)
					( objectStatus "C6T2.2" )
				)
			)
			( gate "@baseboard_fab2_lib.baseboard_fab2(sch_1):page197_i59"
				( attribute "CDS_LIB" "mstr_discrete"
					( Origin gPackager )
				)
				( attribute "CDS_LOCATION" "C4B11"
					( Origin gPackager )
				)
				( attribute "CDS_SEC" "1"
					( Origin gPackager )
				)
				( attribute "LOCATION" "C4B11"
					( Origin gFrontEnd )
				)
				( attribute "MATERIAL" "X7R"
					( Origin gFrontEnd )
				)
				( attribute "PACK_TYPE" "0805"
					( Origin gFrontEnd )
				)
				( attribute "PART_NUMBER" "G10601-001"
					( Origin gFrontEnd )
				)
				( attribute "PHYS_PAGE" "197"
					( Origin gFrontEnd )
				)
				( attribute "ROOM" "PVDDQ_DEF_PWR_VR"
					( Origin gFrontEnd )
				)
				( attribute "ROT" "0"
					( Origin gFrontEnd )
				)
				( attribute "SEC" "1"
					( Origin gPackager )
				)
				( attribute "TOLERANCE" "10%"
					( Origin gFrontEnd )
				)
				( attribute "VALUE" "10UF"
					( Origin gFrontEnd )
				)
				( attribute "VER" "1"
					( Origin gFrontEnd )
				)
				( attribute "VOLTAGE" "16V"
					( Units "uVoltage" "V" 1.000000)
					( Origin gFrontEnd )
				)
				( attribute "XY" "(25,1625)"
					( Origin gFrontEnd )
				)
				( attribute "CHIPS_PART_NAME" "CAP"
					( Origin gPackager )
				)
				( attribute "CDS_PART_NAME" "CAP_0805-10UF,16V,10%,X7R,G106A"
					( Origin gPackager )
				)
				( objectStatus "C4B11" )
				( pin "a"
					( attribute "PN" "1"
						( Origin gPackager )
					)
					( objectStatus "C4B11.1" )
				)
				( pin "b"
					( attribute "PN" "2"
						( Origin gPackager )
					)
					( objectStatus "C4B11.2" )
				)
			)
			( gate "@baseboard_fab2_lib.baseboard_fab2(sch_1):page197_i62"
				( attribute "CDS_LIB" "mstr_discrete"
					( Origin gPackager )
				)
				( attribute "CDS_LOCATION" "C4A4"
					( Origin gPackager )
				)
				( attribute "CDS_SEC" "1"
					( Origin gPackager )
				)
				( attribute "LOCATION" "C4A4"
					( Origin gFrontEnd )
				)
				( attribute "MATERIAL" "X7R"
					( Origin gFrontEnd )
				)
				( attribute "PACK_TYPE" "0805"
					( Origin gFrontEnd )
				)
				( attribute "PART_NUMBER" "G10601-001"
					( Origin gFrontEnd )
				)
				( attribute "PHYS_PAGE" "197"
					( Origin gFrontEnd )
				)
				( attribute "ROOM" "PVDDQ_DEF_PWR_VR"
					( Origin gFrontEnd )
				)
				( attribute "ROT" "0"
					( Origin gFrontEnd )
				)
				( attribute "SEC" "1"
					( Origin gPackager )
				)
				( attribute "TOLERANCE" "10%"
					( Origin gFrontEnd )
				)
				( attribute "VALUE" "10UF"
					( Origin gFrontEnd )
				)
				( attribute "VER" "1"
					( Origin gFrontEnd )
				)
				( attribute "VOLTAGE" "16V"
					( Units "uVoltage" "V" 1.000000)
					( Origin gFrontEnd )
				)
				( attribute "XY" "(25,2200)"
					( Origin gFrontEnd )
				)
				( attribute "CHIPS_PART_NAME" "CAP"
					( Origin gPackager )
				)
				( attribute "CDS_PART_NAME" "CAP_0805-10UF,16V,10%,X7R,G106A"
					( Origin gPackager )
				)
				( objectStatus "C4A4" )
				( pin "a"
					( attribute "PN" "1"
						( Origin gPackager )
					)
					( objectStatus "C4A4.1" )
				)
				( pin "b"
					( attribute "PN" "2"
						( Origin gPackager )
					)
					( objectStatus "C4A4.2" )
				)
			)
			( gate "@baseboard_fab2_lib.baseboard_fab2(sch_1):page197_i65"
				( attribute "CDS_LIB" "mstr_discrete"
					( Origin gPackager )
				)
				( attribute "CDS_LOCATION" "C6U10"
					( Origin gPackager )
				)
				( attribute "CDS_SEC" "1"
					( Origin gPackager )
				)
				( attribute "LOCATION" "C6U10"
					( Origin gFrontEnd )
				)
				( attribute "MATERIAL" "X7R"
					( Origin gFrontEnd )
				)
				( attribute "PACK_TYPE" "0805"
					( Origin gFrontEnd )
				)
				( attribute "PART_NUMBER" "G10601-001"
					( Origin gFrontEnd )
				)
				( attribute "PHYS_PAGE" "197"
					( Origin gFrontEnd )
				)
				( attribute "ROOM" "PVDDQ_ABC_PWR_VR"
					( Origin gFrontEnd )
				)
				( attribute "ROT" "0"
					( Origin gFrontEnd )
				)
				( attribute "SEC" "1"
					( Origin gPackager )
				)
				( attribute "TOLERANCE" "10%"
					( Origin gFrontEnd )
				)
				( attribute "VALUE" "10UF"
					( Origin gFrontEnd )
				)
				( attribute "VER" "1"
					( Origin gFrontEnd )
				)
				( attribute "VOLTAGE" "16V"
					( Units "uVoltage" "V" 1.000000)
					( Origin gFrontEnd )
				)
				( attribute "XY" "(-825,2850)"
					( Origin gFrontEnd )
				)
				( attribute "CHIPS_PART_NAME" "CAP"
					( Origin gPackager )
				)
				( attribute "CDS_PART_NAME" "CAP_0805-10UF,16V,10%,X7R,G106A"
					( Origin gPackager )
				)
				( objectStatus "C6U10" )
				( pin "a"
					( attribute "PN" "1"
						( Origin gPackager )
					)
					( objectStatus "C6U10.1" )
				)
				( pin "b"
					( attribute "PN" "2"
						( Origin gPackager )
					)
					( objectStatus "C6U10.2" )
				)
			)
			( gate "@baseboard_fab2_lib.baseboard_fab2(sch_1):page197_i67"
				( attribute "CDS_LIB" "mstr_discrete"
					( Origin gPackager )
				)
				( attribute "CDS_LOCATION" "C4A17"
					( Origin gPackager )
				)
				( attribute "CDS_SEC" "1"
					( Origin gPackager )
				)
				( attribute "LOCATION" "C4A17"
					( Origin gFrontEnd )
				)
				( attribute "MATERIAL" "X7R"
					( Origin gFrontEnd )
				)
				( attribute "PACK_TYPE" "0805"
					( Origin gFrontEnd )
				)
				( attribute "PART_NUMBER" "G10601-001"
					( Origin gFrontEnd )
				)
				( attribute "PHYS_PAGE" "197"
					( Origin gFrontEnd )
				)
				( attribute "ROOM" "PVDDQ_DEF_PWR_VR"
					( Origin gFrontEnd )
				)
				( attribute "ROT" "0"
					( Origin gFrontEnd )
				)
				( attribute "SEC" "1"
					( Origin gPackager )
				)
				( attribute "TOLERANCE" "10%"
					( Origin gFrontEnd )
				)
				( attribute "VALUE" "10UF"
					( Origin gFrontEnd )
				)
				( attribute "VER" "1"
					( Origin gFrontEnd )
				)
				( attribute "VOLTAGE" "16V"
					( Units "uVoltage" "V" 1.000000)
					( Origin gFrontEnd )
				)
				( attribute "XY" "(25,2850)"
					( Origin gFrontEnd )
				)
				( attribute "CHIPS_PART_NAME" "CAP"
					( Origin gPackager )
				)
				( attribute "CDS_PART_NAME" "CAP_0805-10UF,16V,10%,X7R,G106A"
					( Origin gPackager )
				)
				( objectStatus "C4A17" )
				( pin "a"
					( attribute "PN" "1"
						( Origin gPackager )
					)
					( objectStatus "C4A17.1" )
				)
				( pin "b"
					( attribute "PN" "2"
						( Origin gPackager )
					)
					( objectStatus "C4A17.2" )
				)
			)
			( gate "@baseboard_fab2_lib.baseboard_fab2(sch_1):page197_i70"
				( attribute "CDS_LIB" "mstr_discrete"
					( Origin gPackager )
				)
				( attribute "CDS_LOCATION" "C9T8"
					( Origin gPackager )
				)
				( attribute "CDS_SEC" "1"
					( Origin gPackager )
				)
				( attribute "LOCATION" "C9T8"
					( Origin gFrontEnd )
				)
				( attribute "MATERIAL" "X7R"
					( Origin gFrontEnd )
				)
				( attribute "PACK_TYPE" "0805"
					( Origin gFrontEnd )
				)
				( attribute "PART_NUMBER" "G10601-001"
					( Origin gFrontEnd )
				)
				( attribute "PHYS_PAGE" "197"
					( Origin gFrontEnd )
				)
				( attribute "ROOM" "PVDDQ_GHJ_PWR_VR"
					( Origin gFrontEnd )
				)
				( attribute "ROT" "0"
					( Origin gFrontEnd )
				)
				( attribute "SEC" "1"
					( Origin gPackager )
				)
				( attribute "TOLERANCE" "10%"
					( Origin gFrontEnd )
				)
				( attribute "VALUE" "10UF"
					( Origin gFrontEnd )
				)
				( attribute "VER" "1"
					( Origin gFrontEnd )
				)
				( attribute "VOLTAGE" "16V"
					( Units "uVoltage" "V" 1.000000)
					( Origin gFrontEnd )
				)
				( attribute "XY" "(850,1625)"
					( Origin gFrontEnd )
				)
				( attribute "CHIPS_PART_NAME" "CAP"
					( Origin gPackager )
				)
				( attribute "CDS_PART_NAME" "CAP_0805-10UF,16V,10%,X7R,G106A"
					( Origin gPackager )
				)
				( objectStatus "C9T8" )
				( pin "a"
					( attribute "PN" "1"
						( Origin gPackager )
					)
					( objectStatus "C9T8.1" )
				)
				( pin "b"
					( attribute "PN" "2"
						( Origin gPackager )
					)
					( objectStatus "C9T8.2" )
				)
			)
			( gate "@baseboard_fab2_lib.baseboard_fab2(sch_1):page197_i73"
				( attribute "CDS_LIB" "mstr_discrete"
					( Origin gPackager )
				)
				( attribute "CDS_LOCATION" "C9U11"
					( Origin gPackager )
				)
				( attribute "CDS_SEC" "1"
					( Origin gPackager )
				)
				( attribute "LOCATION" "C9U11"
					( Origin gFrontEnd )
				)
				( attribute "MATERIAL" "X7R"
					( Origin gFrontEnd )
				)
				( attribute "PACK_TYPE" "0805"
					( Origin gFrontEnd )
				)
				( attribute "PART_NUMBER" "G10601-001"
					( Origin gFrontEnd )
				)
				( attribute "PHYS_PAGE" "197"
					( Origin gFrontEnd )
				)
				( attribute "ROOM" "PVDDQ_GHJ_PWR_VR"
					( Origin gFrontEnd )
				)
				( attribute "ROT" "0"
					( Origin gFrontEnd )
				)
				( attribute "SEC" "1"
					( Origin gPackager )
				)
				( attribute "TOLERANCE" "10%"
					( Origin gFrontEnd )
				)
				( attribute "VALUE" "10UF"
					( Origin gFrontEnd )
				)
				( attribute "VER" "1"
					( Origin gFrontEnd )
				)
				( attribute "VOLTAGE" "16V"
					( Units "uVoltage" "V" 1.000000)
					( Origin gFrontEnd )
				)
				( attribute "XY" "(850,2200)"
					( Origin gFrontEnd )
				)
				( attribute "CHIPS_PART_NAME" "CAP"
					( Origin gPackager )
				)
				( attribute "CDS_PART_NAME" "CAP_0805-10UF,16V,10%,X7R,G106A"
					( Origin gPackager )
				)
				( objectStatus "C9U11" )
				( pin "a"
					( attribute "PN" "1"
						( Origin gPackager )
					)
					( objectStatus "C9U11.1" )
				)
				( pin "b"
					( attribute "PN" "2"
						( Origin gPackager )
					)
					( objectStatus "C9U11.2" )
				)
			)
			( gate "@baseboard_fab2_lib.baseboard_fab2(sch_1):page197_i76"
				( attribute "CDS_LIB" "mstr_discrete"
					( Origin gPackager )
				)
				( attribute "CDS_LOCATION" "C9U8"
					( Origin gPackager )
				)
				( attribute "CDS_SEC" "1"
					( Origin gPackager )
				)
				( attribute "LOCATION" "C9U8"
					( Origin gFrontEnd )
				)
				( attribute "MATERIAL" "X7R"
					( Origin gFrontEnd )
				)
				( attribute "PACK_TYPE" "0805"
					( Origin gFrontEnd )
				)
				( attribute "PART_NUMBER" "G10601-001"
					( Origin gFrontEnd )
				)
				( attribute "PHYS_PAGE" "197"
					( Origin gFrontEnd )
				)
				( attribute "ROOM" "PVDDQ_GHJ_PWR_VR"
					( Origin gFrontEnd )
				)
				( attribute "ROT" "0"
					( Origin gFrontEnd )
				)
				( attribute "SEC" "1"
					( Origin gPackager )
				)
				( attribute "TOLERANCE" "10%"
					( Origin gFrontEnd )
				)
				( attribute "VALUE" "10UF"
					( Origin gFrontEnd )
				)
				( attribute "VER" "1"
					( Origin gFrontEnd )
				)
				( attribute "VOLTAGE" "16V"
					( Units "uVoltage" "V" 1.000000)
					( Origin gFrontEnd )
				)
				( attribute "XY" "(850,2850)"
					( Origin gFrontEnd )
				)
				( attribute "CHIPS_PART_NAME" "CAP"
					( Origin gPackager )
				)
				( attribute "CDS_PART_NAME" "CAP_0805-10UF,16V,10%,X7R,G106A"
					( Origin gPackager )
				)
				( objectStatus "C9U8" )
				( pin "a"
					( attribute "PN" "1"
						( Origin gPackager )
					)
					( objectStatus "C9U8.1" )
				)
				( pin "b"
					( attribute "PN" "2"
						( Origin gPackager )
					)
					( objectStatus "C9U8.2" )
				)
			)
			( gate "@baseboard_fab2_lib.baseboard_fab2(sch_1):page197_i79"
				( attribute "CDS_LIB" "mstr_discrete"
					( Origin gPackager )
				)
				( attribute "CDS_LOCATION" "C1A4"
					( Origin gPackager )
				)
				( attribute "CDS_SEC" "1"
					( Origin gPackager )
				)
				( attribute "LOCATION" "C1A4"
					( Origin gFrontEnd )
				)
				( attribute "MATERIAL" "X7R"
					( Origin gFrontEnd )
				)
				( attribute "PACK_TYPE" "0805"
					( Origin gFrontEnd )
				)
				( attribute "PART_NUMBER" "G10601-001"
					( Origin gFrontEnd )
				)
				( attribute "PHYS_PAGE" "197"
					( Origin gFrontEnd )
				)
				( attribute "ROOM" "PVDDQ_KLM_PWR_VR"
					( Origin gFrontEnd )
				)
				( attribute "ROT" "0"
					( Origin gFrontEnd )
				)
				( attribute "SEC" "1"
					( Origin gPackager )
				)
				( attribute "TOLERANCE" "10%"
					( Origin gFrontEnd )
				)
				( attribute "VALUE" "10UF"
					( Origin gFrontEnd )
				)
				( attribute "VER" "1"
					( Origin gFrontEnd )
				)
				( attribute "VOLTAGE" "16V"
					( Units "uVoltage" "V" 1.000000)
					( Origin gFrontEnd )
				)
				( attribute "XY" "(1700,1625)"
					( Origin gFrontEnd )
				)
				( attribute "CHIPS_PART_NAME" "CAP"
					( Origin gPackager )
				)
				( attribute "CDS_PART_NAME" "CAP_0805-10UF,16V,10%,X7R,G106A"
					( Origin gPackager )
				)
				( objectStatus "C1A4" )
				( pin "a"
					( attribute "PN" "1"
						( Origin gPackager )
					)
					( objectStatus "C1A4.1" )
				)
				( pin "b"
					( attribute "PN" "2"
						( Origin gPackager )
					)
					( objectStatus "C1A4.2" )
				)
			)
			( gate "@baseboard_fab2_lib.baseboard_fab2(sch_1):page197_i82"
				( attribute "CDS_LIB" "mstr_discrete"
					( Origin gPackager )
				)
				( attribute "CDS_LOCATION" "C1B7"
					( Origin gPackager )
				)
				( attribute "CDS_SEC" "1"
					( Origin gPackager )
				)
				( attribute "LOCATION" "C1B7"
					( Origin gFrontEnd )
				)
				( attribute "MATERIAL" "X7R"
					( Origin gFrontEnd )
				)
				( attribute "PACK_TYPE" "0805"
					( Origin gFrontEnd )
				)
				( attribute "PART_NUMBER" "G10601-001"
					( Origin gFrontEnd )
				)
				( attribute "PHYS_PAGE" "197"
					( Origin gFrontEnd )
				)
				( attribute "ROOM" "PVDDQ_KLM_PWR_VR"
					( Origin gFrontEnd )
				)
				( attribute "ROT" "0"
					( Origin gFrontEnd )
				)
				( attribute "SEC" "1"
					( Origin gPackager )
				)
				( attribute "TOLERANCE" "10%"
					( Origin gFrontEnd )
				)
				( attribute "VALUE" "10UF"
					( Origin gFrontEnd )
				)
				( attribute "VER" "1"
					( Origin gFrontEnd )
				)
				( attribute "VOLTAGE" "16V"
					( Units "uVoltage" "V" 1.000000)
					( Origin gFrontEnd )
				)
				( attribute "XY" "(1700,2200)"
					( Origin gFrontEnd )
				)
				( attribute "CHIPS_PART_NAME" "CAP"
					( Origin gPackager )
				)
				( attribute "CDS_PART_NAME" "CAP_0805-10UF,16V,10%,X7R,G106A"
					( Origin gPackager )
				)
				( objectStatus "C1B7" )
				( pin "a"
					( attribute "PN" "1"
						( Origin gPackager )
					)
					( objectStatus "C1B7.1" )
				)
				( pin "b"
					( attribute "PN" "2"
						( Origin gPackager )
					)
					( objectStatus "C1B7.2" )
				)
			)
			( gate "@baseboard_fab2_lib.baseboard_fab2(sch_1):page197_i85"
				( attribute "CDS_LIB" "mstr_discrete"
					( Origin gPackager )
				)
				( attribute "CDS_LOCATION" "C1A16"
					( Origin gPackager )
				)
				( attribute "CDS_SEC" "1"
					( Origin gPackager )
				)
				( attribute "LOCATION" "C1A16"
					( Origin gFrontEnd )
				)
				( attribute "MATERIAL" "X7R"
					( Origin gFrontEnd )
				)
				( attribute "PACK_TYPE" "0805"
					( Origin gFrontEnd )
				)
				( attribute "PART_NUMBER" "G10601-001"
					( Origin gFrontEnd )
				)
				( attribute "PHYS_PAGE" "197"
					( Origin gFrontEnd )
				)
				( attribute "ROOM" "PVDDQ_KLM_PWR_VR"
					( Origin gFrontEnd )
				)
				( attribute "ROT" "0"
					( Origin gFrontEnd )
				)
				( attribute "SEC" "1"
					( Origin gPackager )
				)
				( attribute "TOLERANCE" "10%"
					( Origin gFrontEnd )
				)
				( attribute "VALUE" "10UF"
					( Origin gFrontEnd )
				)
				( attribute "VER" "1"
					( Origin gFrontEnd )
				)
				( attribute "VOLTAGE" "16V"
					( Units "uVoltage" "V" 1.000000)
					( Origin gFrontEnd )
				)
				( attribute "XY" "(1700,2850)"
					( Origin gFrontEnd )
				)
				( attribute "CHIPS_PART_NAME" "CAP"
					( Origin gPackager )
				)
				( attribute "CDS_PART_NAME" "CAP_0805-10UF,16V,10%,X7R,G106A"
					( Origin gPackager )
				)
				( objectStatus "C1A16" )
				( pin "a"
					( attribute "PN" "1"
						( Origin gPackager )
					)
					( objectStatus "C1A16.1" )
				)
				( pin "b"
					( attribute "PN" "2"
						( Origin gPackager )
					)
					( objectStatus "C1A16.2" )
				)
			)
			( gate "@baseboard_fab2_lib.baseboard_fab2(sch_1):page197_i97"
				( attribute "BOM_COST" "PVDDQ_ABC_VR"
					( Origin gFrontEnd )
				)
				( attribute "CDS_LIB" "mstr_vreg"
					( Origin gPackager )
				)
				( attribute "CDS_LOCATION" "U4F1"
					( Origin gPackager )
				)
				( attribute "CDS_SEC" "1"
					( Origin gPackager )
				)
				( attribute "LOCATION" "U4F1"
					( Origin gFrontEnd )
				)
				( attribute "MATERIAL" "IC"
					( Origin gFrontEnd )
				)
				( attribute "PACK_TYPE" "SOT"
					( Origin gFrontEnd )
				)
				( attribute "PART_NUMBER" "H35789-001"
					( Origin gFrontEnd )
				)
				( attribute "PHYS_PAGE" "197"
					( Origin gFrontEnd )
				)
				( attribute "ROOM" "PVDDQ_ABC_PWR_VR"
					( Origin gFrontEnd )
				)
				( attribute "ROT" "0"
					( Origin gFrontEnd )
				)
				( attribute "SEC" "1"
					( Origin gFrontEnd )
				)
				( attribute "SEC_TYPE" "SOT"
					( Origin gFrontEnd )
				)
				( attribute "VER" "1"
					( Origin gFrontEnd )
				)
				( attribute "XY" "(-3800,4425)"
					( Origin gFrontEnd )
				)
				( attribute "CHIPS_PART_NAME" "MAX9634"
					( Origin gPackager )
				)
				( attribute "CDS_PART_NAME" "MAX9634_SOT-IC,H35789-001"
					( Origin gPackager )
				)
				( objectStatus "U4F1" )
				( pin "gnd(0)"
					( attribute "PN" "2"
						( Origin gPackager )
					)
					( objectStatus "U4F1.2" )
				)
				( pin "gnd(1)"
					( attribute "PN" "1"
						( Origin gPackager )
					)
					( objectStatus "U4F1.1" )
				)
				( pin "\out\"
					( attribute "PN" "3"
						( Origin gPackager )
					)
					( objectStatus "U4F1.3" )
				)
				( pin "rsn"
					( attribute "PN" "4"
						( Origin gPackager )
					)
					( objectStatus "U4F1.4" )
				)
				( pin "rsp"
					( attribute "PN" "5"
						( Origin gPackager )
					)
					( objectStatus "U4F1.5" )
				)
			)
			( gate "@baseboard_fab2_lib.baseboard_fab2(sch_1):page197_i99"
				( attribute "BOM_COST" "PVDDQ_ABC_VR"
					( Origin gFrontEnd )
				)
				( attribute "CDS_LIB" "mstr_discrete"
					( Origin gPackager )
				)
				( attribute "CDS_LOCATION" "R4F2"
					( Origin gPackager )
				)
				( attribute "CDS_SEC" "1"
					( Origin gPackager )
				)
				( attribute "LOCATION" "R4F2"
					( Origin gFrontEnd )
				)
				( attribute "MATERIAL" "CHIP"
					( Origin gFrontEnd )
				)
				( attribute "PACK_TYPE" "1206"
					( Origin gFrontEnd )
				)
				( attribute "PART_NUMBER" "G52199-004"
					( Origin gFrontEnd )
				)
				( attribute "PHYS_PAGE" "197"
					( Origin gFrontEnd )
				)
				( attribute "ROOM" "PVDDQ_ABC_PWR_VR"
					( Origin gFrontEnd )
				)
				( attribute "ROT" "0"
					( Origin gFrontEnd )
				)
				( attribute "SEC" "1"
					( Origin gFrontEnd )
				)
				( attribute "SEC_TYPE" "1206"
					( Origin gFrontEnd )
				)
				( attribute "TOLERANCE" "1%"
					( Origin gFrontEnd )
				)
				( attribute "VALUE" "0.002"
					( Origin gFrontEnd )
				)
				( attribute "VER" "1"
					( Origin gFrontEnd )
				)
				( attribute "WATTAGE" "1W"
					( Origin gFrontEnd )
				)
				( attribute "XY" "(-4575,4750)"
					( Origin gFrontEnd )
				)
				( attribute "CHIPS_PART_NAME" "RES"
					( Origin gPackager )
				)
				( attribute "CDS_PART_NAME" "RES_1206-0.002,1%,1W,CHIP,G521A"
					( Origin gPackager )
				)
				( objectStatus "R4F2" )
				( pin "a"
					( attribute "PN" "1"
						( Origin gPackager )
					)
					( objectStatus "R4F2.1" )
				)
				( pin "b"
					( attribute "PN" "2"
						( Origin gPackager )
					)
					( objectStatus "R4F2.2" )
				)
			)
			( gate "@baseboard_fab2_lib.baseboard_fab2(sch_1):page197_i110"
				( attribute "BOM_COST" "PVDDQ_ABC_VR"
					( Origin gFrontEnd )
				)
				( attribute "CDS_LIB" "mstr_discrete"
					( Origin gPackager )
				)
				( attribute "CDS_LOCATION" "R4F1"
					( Origin gPackager )
				)
				( attribute "CDS_SEC" "1"
					( Origin gPackager )
				)
				( attribute "LOCATION" "R4F1"
					( Origin gFrontEnd )
				)
				( attribute "MATERIAL" "CHIP"
					( Origin gFrontEnd )
				)
				( attribute "PACK_TYPE" "0402"
					( Origin gFrontEnd )
				)
				( attribute "PART_NUMBER" "G21497-005"
					( Origin gFrontEnd )
				)
				( attribute "PHYS_PAGE" "197"
					( Origin gFrontEnd )
				)
				( attribute "ROOM" "PVDDQ_ABC_PWR_VR"
					( Origin gFrontEnd )
				)
				( attribute "ROT" "0"
					( Origin gFrontEnd )
				)
				( attribute "SEC" "1"
					( Origin gFrontEnd )
				)
				( attribute "SEC_TYPE" "0402"
					( Origin gFrontEnd )
				)
				( attribute "TOLERANCE" "5%"
					( Origin gFrontEnd )
				)
				( attribute "VALUE" "0.0"
					( Origin gFrontEnd )
				)
				( attribute "VER" "1"
					( Origin gFrontEnd )
				)
				( attribute "WATTAGE" "1/16W"
					( Origin gFrontEnd )
				)
				( attribute "XY" "(-2775,4475)"
					( Origin gFrontEnd )
				)
				( attribute "CHIPS_PART_NAME" "RES"
					( Origin gPackager )
				)
				( attribute "CDS_PART_NAME" "RES_0402-0.0,5%,1/16W,CHIP,G21A"
					( Origin gPackager )
				)
				( objectStatus "R4F1" )
				( pin "a"
					( attribute "PN" "1"
						( Origin gPackager )
					)
					( objectStatus "R4F1.1" )
				)
				( pin "b"
					( attribute "PN" "2"
						( Origin gPackager )
					)
					( objectStatus "R4F1.2" )
				)
			)
			( gate "@baseboard_fab2_lib.baseboard_fab2(sch_1):page197_i113"
				( attribute "BOM_COST" "PVDDQ_DEF_VR"
					( Origin gFrontEnd )
				)
				( attribute "CDS_LIB" "mstr_discrete"
					( Origin gPackager )
				)
				( attribute "CDS_LOCATION" "R4B11"
					( Origin gPackager )
				)
				( attribute "CDS_SEC" "1"
					( Origin gPackager )
				)
				( attribute "LOCATION" "R4B11"
					( Origin gFrontEnd )
				)
				( attribute "MATERIAL" "CHIP"
					( Origin gFrontEnd )
				)
				( attribute "PACK_TYPE" "0402"
					( Origin gFrontEnd )
				)
				( attribute "PART_NUMBER" "G21497-005"
					( Origin gFrontEnd )
				)
				( attribute "PHYS_PAGE" "197"
					( Origin gFrontEnd )
				)
				( attribute "ROOM" "PVDDQ_DEF_PWR_VR"
					( Origin gFrontEnd )
				)
				( attribute "ROT" "0"
					( Origin gFrontEnd )
				)
				( attribute "SEC" "1"
					( Origin gFrontEnd )
				)
				( attribute "SEC_TYPE" "0402"
					( Origin gFrontEnd )
				)
				( attribute "TOLERANCE" "5%"
					( Origin gFrontEnd )
				)
				( attribute "VALUE" "0.0"
					( Origin gFrontEnd )
				)
				( attribute "VER" "1"
					( Origin gFrontEnd )
				)
				( attribute "WATTAGE" "1/16W"
					( Origin gFrontEnd )
				)
				( attribute "XY" "(-2775,3025)"
					( Origin gFrontEnd )
				)
				( attribute "CHIPS_PART_NAME" "RES"
					( Origin gPackager )
				)
				( attribute "CDS_PART_NAME" "RES_0402-0.0,5%,1/16W,CHIP,G21A"
					( Origin gPackager )
				)
				( objectStatus "R4B11" )
				( pin "a"
					( attribute "PN" "1"
						( Origin gPackager )
					)
					( objectStatus "R4B11.1" )
				)
				( pin "b"
					( attribute "PN" "2"
						( Origin gPackager )
					)
					( objectStatus "R4B11.2" )
				)
			)
			( gate "@baseboard_fab2_lib.baseboard_fab2(sch_1):page197_i120"
				( attribute "BOM_COST" "PVDDQ_DEF_VR"
					( Origin gFrontEnd )
				)
				( attribute "CDS_LIB" "mstr_vreg"
					( Origin gPackager )
				)
				( attribute "CDS_LOCATION" "U4B1"
					( Origin gPackager )
				)
				( attribute "CDS_SEC" "1"
					( Origin gPackager )
				)
				( attribute "LOCATION" "U4B1"
					( Origin gFrontEnd )
				)
				( attribute "MATERIAL" "IC"
					( Origin gFrontEnd )
				)
				( attribute "PACK_TYPE" "SOT"
					( Origin gFrontEnd )
				)
				( attribute "PART_NUMBER" "H35789-001"
					( Origin gFrontEnd )
				)
				( attribute "PHYS_PAGE" "197"
					( Origin gFrontEnd )
				)
				( attribute "ROOM" "PVDDQ_DEF_PWR_VR"
					( Origin gFrontEnd )
				)
				( attribute "ROT" "0"
					( Origin gFrontEnd )
				)
				( attribute "SEC" "1"
					( Origin gFrontEnd )
				)
				( attribute "SEC_TYPE" "SOT"
					( Origin gFrontEnd )
				)
				( attribute "VER" "1"
					( Origin gFrontEnd )
				)
				( attribute "XY" "(-3800,2975)"
					( Origin gFrontEnd )
				)
				( attribute "CHIPS_PART_NAME" "MAX9634"
					( Origin gPackager )
				)
				( attribute "CDS_PART_NAME" "MAX9634_SOT-IC,H35789-001"
					( Origin gPackager )
				)
				( objectStatus "U4B1" )
				( pin "gnd(0)"
					( attribute "PN" "2"
						( Origin gPackager )
					)
					( objectStatus "U4B1.2" )
				)
				( pin "gnd(1)"
					( attribute "PN" "1"
						( Origin gPackager )
					)
					( objectStatus "U4B1.1" )
				)
				( pin "\out\"
					( attribute "PN" "3"
						( Origin gPackager )
					)
					( objectStatus "U4B1.3" )
				)
				( pin "rsn"
					( attribute "PN" "4"
						( Origin gPackager )
					)
					( objectStatus "U4B1.4" )
				)
				( pin "rsp"
					( attribute "PN" "5"
						( Origin gPackager )
					)
					( objectStatus "U4B1.5" )
				)
			)
			( gate "@baseboard_fab2_lib.baseboard_fab2(sch_1):page197_i121"
				( attribute "BOM_COST" "PVDDQ_DEF_VR"
					( Origin gFrontEnd )
				)
				( attribute "CDS_LIB" "mstr_discrete"
					( Origin gPackager )
				)
				( attribute "CDS_LOCATION" "R4B12"
					( Origin gPackager )
				)
				( attribute "CDS_SEC" "1"
					( Origin gPackager )
				)
				( attribute "LOCATION" "R4B12"
					( Origin gFrontEnd )
				)
				( attribute "MATERIAL" "CHIP"
					( Origin gFrontEnd )
				)
				( attribute "PACK_TYPE" "1206"
					( Origin gFrontEnd )
				)
				( attribute "PART_NUMBER" "G52199-004"
					( Origin gFrontEnd )
				)
				( attribute "PHYS_PAGE" "197"
					( Origin gFrontEnd )
				)
				( attribute "ROOM" "PVDDQ_DEF_PWR_VR"
					( Origin gFrontEnd )
				)
				( attribute "ROT" "0"
					( Origin gFrontEnd )
				)
				( attribute "SEC" "1"
					( Origin gFrontEnd )
				)
				( attribute "SEC_TYPE" "1206"
					( Origin gFrontEnd )
				)
				( attribute "TOLERANCE" "1%"
					( Origin gFrontEnd )
				)
				( attribute "VALUE" "0.002"
					( Origin gFrontEnd )
				)
				( attribute "VER" "1"
					( Origin gFrontEnd )
				)
				( attribute "WATTAGE" "1W"
					( Origin gFrontEnd )
				)
				( attribute "XY" "(-4575,3300)"
					( Origin gFrontEnd )
				)
				( attribute "CHIPS_PART_NAME" "RES"
					( Origin gPackager )
				)
				( attribute "CDS_PART_NAME" "RES_1206-0.002,1%,1W,CHIP,G521A"
					( Origin gPackager )
				)
				( objectStatus "R4B12" )
				( pin "a"
					( attribute "PN" "1"
						( Origin gPackager )
					)
					( objectStatus "R4B12.1" )
				)
				( pin "b"
					( attribute "PN" "2"
						( Origin gPackager )
					)
					( objectStatus "R4B12.2" )
				)
			)
			( gate "@baseboard_fab2_lib.baseboard_fab2(sch_1):page197_i126"
				( attribute "BOM_COST" "PVDDQ_GHJ_VR"
					( Origin gFrontEnd )
				)
				( attribute "CDS_LIB" "mstr_discrete"
					( Origin gPackager )
				)
				( attribute "CDS_LOCATION" "R9T4"
					( Origin gPackager )
				)
				( attribute "CDS_SEC" "1"
					( Origin gPackager )
				)
				( attribute "LOCATION" "R9T4"
					( Origin gFrontEnd )
				)
				( attribute "MATERIAL" "CHIP"
					( Origin gFrontEnd )
				)
				( attribute "PACK_TYPE" "0402"
					( Origin gFrontEnd )
				)
				( attribute "PART_NUMBER" "G21497-005"
					( Origin gFrontEnd )
				)
				( attribute "PHYS_PAGE" "197"
					( Origin gFrontEnd )
				)
				( attribute "ROOM" "PVDDQ_GHJ_PWR_VR"
					( Origin gFrontEnd )
				)
				( attribute "ROT" "0"
					( Origin gFrontEnd )
				)
				( attribute "SEC" "1"
					( Origin gFrontEnd )
				)
				( attribute "SEC_TYPE" "0402"
					( Origin gFrontEnd )
				)
				( attribute "TOLERANCE" "5%"
					( Origin gFrontEnd )
				)
				( attribute "VALUE" "0.0"
					( Origin gFrontEnd )
				)
				( attribute "VER" "1"
					( Origin gFrontEnd )
				)
				( attribute "WATTAGE" "1/16W"
					( Origin gFrontEnd )
				)
				( attribute "XY" "(-2775,1600)"
					( Origin gFrontEnd )
				)
				( attribute "CHIPS_PART_NAME" "RES"
					( Origin gPackager )
				)
				( attribute "CDS_PART_NAME" "RES_0402-0.0,5%,1/16W,CHIP,G21A"
					( Origin gPackager )
				)
				( objectStatus "R9T4" )
				( pin "a"
					( attribute "PN" "1"
						( Origin gPackager )
					)
					( objectStatus "R9T4.1" )
				)
				( pin "b"
					( attribute "PN" "2"
						( Origin gPackager )
					)
					( objectStatus "R9T4.2" )
				)
			)
			( gate "@baseboard_fab2_lib.baseboard_fab2(sch_1):page197_i131"
				( attribute "BOM_COST" "PVDDQ_GHJ_VR"
					( Origin gFrontEnd )
				)
				( attribute "CDS_LIB" "mstr_discrete"
					( Origin gPackager )
				)
				( attribute "CDS_LOCATION" "R1F3"
					( Origin gPackager )
				)
				( attribute "CDS_SEC" "1"
					( Origin gPackager )
				)
				( attribute "LOCATION" "R1F3"
					( Origin gFrontEnd )
				)
				( attribute "MATERIAL" "CHIP"
					( Origin gFrontEnd )
				)
				( attribute "PACK_TYPE" "1206"
					( Origin gFrontEnd )
				)
				( attribute "PART_NUMBER" "G52199-004"
					( Origin gFrontEnd )
				)
				( attribute "PHYS_PAGE" "197"
					( Origin gFrontEnd )
				)
				( attribute "ROOM" "PVDDQ_GHJ_PWR_VR"
					( Origin gFrontEnd )
				)
				( attribute "ROT" "0"
					( Origin gFrontEnd )
				)
				( attribute "SEC" "1"
					( Origin gFrontEnd )
				)
				( attribute "SEC_TYPE" "1206"
					( Origin gFrontEnd )
				)
				( attribute "TOLERANCE" "1%"
					( Origin gFrontEnd )
				)
				( attribute "VALUE" "0.002"
					( Origin gFrontEnd )
				)
				( attribute "VER" "1"
					( Origin gFrontEnd )
				)
				( attribute "WATTAGE" "1W"
					( Origin gFrontEnd )
				)
				( attribute "XY" "(-4575,1875)"
					( Origin gFrontEnd )
				)
				( attribute "CHIPS_PART_NAME" "RES"
					( Origin gPackager )
				)
				( attribute "CDS_PART_NAME" "RES_1206-0.002,1%,1W,CHIP,G521A"
					( Origin gPackager )
				)
				( objectStatus "R1F3" )
				( pin "a"
					( attribute "PN" "1"
						( Origin gPackager )
					)
					( objectStatus "R1F3.1" )
				)
				( pin "b"
					( attribute "PN" "2"
						( Origin gPackager )
					)
					( objectStatus "R1F3.2" )
				)
			)
			( gate "@baseboard_fab2_lib.baseboard_fab2(sch_1):page197_i133"
				( attribute "BOM_COST" "PVDDQ_GHJ_VR"
					( Origin gFrontEnd )
				)
				( attribute "CDS_LIB" "mstr_vreg"
					( Origin gPackager )
				)
				( attribute "CDS_LOCATION" "U1F1"
					( Origin gPackager )
				)
				( attribute "CDS_SEC" "1"
					( Origin gPackager )
				)
				( attribute "LOCATION" "U1F1"
					( Origin gFrontEnd )
				)
				( attribute "MATERIAL" "IC"
					( Origin gFrontEnd )
				)
				( attribute "PACK_TYPE" "SOT"
					( Origin gFrontEnd )
				)
				( attribute "PART_NUMBER" "H35789-001"
					( Origin gFrontEnd )
				)
				( attribute "PHYS_PAGE" "197"
					( Origin gFrontEnd )
				)
				( attribute "ROOM" "PVDDQ_GHJ_PWR_VR"
					( Origin gFrontEnd )
				)
				( attribute "ROT" "0"
					( Origin gFrontEnd )
				)
				( attribute "SEC" "1"
					( Origin gFrontEnd )
				)
				( attribute "SEC_TYPE" "SOT"
					( Origin gFrontEnd )
				)
				( attribute "VER" "1"
					( Origin gFrontEnd )
				)
				( attribute "XY" "(-3800,1550)"
					( Origin gFrontEnd )
				)
				( attribute "CHIPS_PART_NAME" "MAX9634"
					( Origin gPackager )
				)
				( attribute "CDS_PART_NAME" "MAX9634_SOT-IC,H35789-001"
					( Origin gPackager )
				)
				( objectStatus "U1F1" )
				( pin "gnd(0)"
					( attribute "PN" "2"
						( Origin gPackager )
					)
					( objectStatus "U1F1.2" )
				)
				( pin "gnd(1)"
					( attribute "PN" "1"
						( Origin gPackager )
					)
					( objectStatus "U1F1.1" )
				)
				( pin "\out\"
					( attribute "PN" "3"
						( Origin gPackager )
					)
					( objectStatus "U1F1.3" )
				)
				( pin "rsn"
					( attribute "PN" "4"
						( Origin gPackager )
					)
					( objectStatus "U1F1.4" )
				)
				( pin "rsp"
					( attribute "PN" "5"
						( Origin gPackager )
					)
					( objectStatus "U1F1.5" )
				)
			)
			( gate "@baseboard_fab2_lib.baseboard_fab2(sch_1):page197_i137"
				( attribute "BOM_COST" "PVDDQ_KLM_VR"
					( Origin gFrontEnd )
				)
				( attribute "CDS_LIB" "mstr_discrete"
					( Origin gPackager )
				)
				( attribute "CDS_LOCATION" "R1B14"
					( Origin gPackager )
				)
				( attribute "CDS_SEC" "1"
					( Origin gPackager )
				)
				( attribute "LOCATION" "R1B14"
					( Origin gFrontEnd )
				)
				( attribute "MATERIAL" "CHIP"
					( Origin gFrontEnd )
				)
				( attribute "PACK_TYPE" "0402"
					( Origin gFrontEnd )
				)
				( attribute "PART_NUMBER" "G21497-005"
					( Origin gFrontEnd )
				)
				( attribute "PHYS_PAGE" "197"
					( Origin gFrontEnd )
				)
				( attribute "ROOM" "PVDDQ_KLM_PWR_VR"
					( Origin gFrontEnd )
				)
				( attribute "ROT" "0"
					( Origin gFrontEnd )
				)
				( attribute "SEC" "1"
					( Origin gFrontEnd )
				)
				( attribute "SEC_TYPE" "0402"
					( Origin gFrontEnd )
				)
				( attribute "TOLERANCE" "5%"
					( Origin gFrontEnd )
				)
				( attribute "VALUE" "0.0"
					( Origin gFrontEnd )
				)
				( attribute "VER" "1"
					( Origin gFrontEnd )
				)
				( attribute "WATTAGE" "1/16W"
					( Origin gFrontEnd )
				)
				( attribute "XY" "(1050,4475)"
					( Origin gFrontEnd )
				)
				( attribute "CHIPS_PART_NAME" "RES"
					( Origin gPackager )
				)
				( attribute "CDS_PART_NAME" "RES_0402-0.0,5%,1/16W,CHIP,G21A"
					( Origin gPackager )
				)
				( objectStatus "R1B14" )
				( pin "a"
					( attribute "PN" "1"
						( Origin gPackager )
					)
					( objectStatus "R1B14.1" )
				)
				( pin "b"
					( attribute "PN" "2"
						( Origin gPackager )
					)
					( objectStatus "R1B14.2" )
				)
			)
			( gate "@baseboard_fab2_lib.baseboard_fab2(sch_1):page197_i142"
				( attribute "BOM_COST" "PVDDQ_KLM_VR"
					( Origin gFrontEnd )
				)
				( attribute "CDS_LIB" "mstr_discrete"
					( Origin gPackager )
				)
				( attribute "CDS_LOCATION" "R9M4"
					( Origin gPackager )
				)
				( attribute "CDS_SEC" "1"
					( Origin gPackager )
				)
				( attribute "LOCATION" "R9M4"
					( Origin gFrontEnd )
				)
				( attribute "MATERIAL" "CHIP"
					( Origin gFrontEnd )
				)
				( attribute "PACK_TYPE" "1206"
					( Origin gFrontEnd )
				)
				( attribute "PART_NUMBER" "G52199-004"
					( Origin gFrontEnd )
				)
				( attribute "PHYS_PAGE" "197"
					( Origin gFrontEnd )
				)
				( attribute "ROOM" "PVDDQ_KLM_PWR_VR"
					( Origin gFrontEnd )
				)
				( attribute "ROT" "0"
					( Origin gFrontEnd )
				)
				( attribute "SEC" "1"
					( Origin gFrontEnd )
				)
				( attribute "SEC_TYPE" "1206"
					( Origin gFrontEnd )
				)
				( attribute "TOLERANCE" "1%"
					( Origin gFrontEnd )
				)
				( attribute "VALUE" "0.002"
					( Origin gFrontEnd )
				)
				( attribute "VER" "1"
					( Origin gFrontEnd )
				)
				( attribute "WATTAGE" "1W"
					( Origin gFrontEnd )
				)
				( attribute "XY" "(-750,4750)"
					( Origin gFrontEnd )
				)
				( attribute "CHIPS_PART_NAME" "RES"
					( Origin gPackager )
				)
				( attribute "CDS_PART_NAME" "RES_1206-0.002,1%,1W,CHIP,G521A"
					( Origin gPackager )
				)
				( objectStatus "R9M4" )
				( pin "a"
					( attribute "PN" "1"
						( Origin gPackager )
					)
					( objectStatus "R9M4.1" )
				)
				( pin "b"
					( attribute "PN" "2"
						( Origin gPackager )
					)
					( objectStatus "R9M4.2" )
				)
			)
			( gate "@baseboard_fab2_lib.baseboard_fab2(sch_1):page197_i144"
				( attribute "BOM_COST" "PVDDQ_KLM_VR"
					( Origin gFrontEnd )
				)
				( attribute "CDS_LIB" "mstr_vreg"
					( Origin gPackager )
				)
				( attribute "CDS_LOCATION" "U1B1"
					( Origin gPackager )
				)
				( attribute "CDS_SEC" "1"
					( Origin gPackager )
				)
				( attribute "LOCATION" "U1B1"
					( Origin gFrontEnd )
				)
				( attribute "MATERIAL" "IC"
					( Origin gFrontEnd )
				)
				( attribute "PACK_TYPE" "SOT"
					( Origin gFrontEnd )
				)
				( attribute "PART_NUMBER" "H35789-001"
					( Origin gFrontEnd )
				)
				( attribute "PHYS_PAGE" "197"
					( Origin gFrontEnd )
				)
				( attribute "ROOM" "PVDDQ_KLM_PWR_VR"
					( Origin gFrontEnd )
				)
				( attribute "ROT" "0"
					( Origin gFrontEnd )
				)
				( attribute "SEC" "1"
					( Origin gFrontEnd )
				)
				( attribute "SEC_TYPE" "SOT"
					( Origin gFrontEnd )
				)
				( attribute "VER" "1"
					( Origin gFrontEnd )
				)
				( attribute "XY" "(25,4425)"
					( Origin gFrontEnd )
				)
				( attribute "CHIPS_PART_NAME" "MAX9634"
					( Origin gPackager )
				)
				( attribute "CDS_PART_NAME" "MAX9634_SOT-IC,H35789-001"
					( Origin gPackager )
				)
				( objectStatus "U1B1" )
				( pin "gnd(0)"
					( attribute "PN" "2"
						( Origin gPackager )
					)
					( objectStatus "U1B1.2" )
				)
				( pin "gnd(1)"
					( attribute "PN" "1"
						( Origin gPackager )
					)
					( objectStatus "U1B1.1" )
				)
				( pin "\out\"
					( attribute "PN" "3"
						( Origin gPackager )
					)
					( objectStatus "U1B1.3" )
				)
				( pin "rsn"
					( attribute "PN" "4"
						( Origin gPackager )
					)
					( objectStatus "U1B1.4" )
				)
				( pin "rsp"
					( attribute "PN" "5"
						( Origin gPackager )
					)
					( objectStatus "U1B1.5" )
				)
			)
			( gate "@baseboard_fab2_lib.baseboard_fab2(sch_1):page198_i1"
				( attribute "CDS_LIB" "mstr_vreg"
					( Origin gPackager )
				)
				( attribute "CDS_LMAN_SYM_OUTLINE" "-250,250,250,-250"
					( Origin gPackager )
				)
				( attribute "CDS_LOCATION" "EU2T1"
					( Origin gPackager )
				)
				( attribute "CDS_SEC" "1"
					( Origin gPackager )
				)
				( attribute "LOCATION" "EU2T1"
					( Origin gFrontEnd )
				)
				( attribute "MATERIAL" "IC"
					( Origin gFrontEnd )
				)
				( attribute "PACK_TYPE" "SM"
					( Origin gFrontEnd )
				)
				( attribute "PART_NUMBER" "G56246-001"
					( Origin gFrontEnd )
				)
				( attribute "PHYS_PAGE" "198"
					( Origin gFrontEnd )
				)
				( attribute "ROOM" "P3V3_PWR_SWITCH"
					( Origin gFrontEnd )
				)
				( attribute "ROT" "0"
					( Origin gFrontEnd )
				)
				( attribute "SEC" "1"
					( Origin gPackager )
				)
				( attribute "VER" "1"
					( Origin gFrontEnd )
				)
				( attribute "XY" "(-7000,3825)"
					( Origin gFrontEnd )
				)
				( attribute "CHIPS_PART_NAME" "SLG55021"
					( Origin gPackager )
				)
				( attribute "CDS_PART_NAME" "SLG55021_SM-IC,G56246-001"
					( Origin gPackager )
				)
				( objectStatus "EU2T1" )
				( pin "d"
					( attribute "PN" "5"
						( Origin gPackager )
					)
					( objectStatus "EU2T1.5" )
				)
				( pin "g"
					( attribute "PN" "7"
						( Origin gPackager )
					)
					( objectStatus "EU2T1.7" )
				)
				( pin "gnd"
					( attribute "PN" "4"
						( Origin gPackager )
					)
					( objectStatus "EU2T1.4" )
				)
				( pin "\on\"
					( attribute "PN" "2"
						( Origin gPackager )
					)
					( objectStatus "EU2T1.2" )
				)
				( pin "pg"
					( attribute "PN" "8"
						( Origin gPackager )
					)
					( objectStatus "EU2T1.8" )
				)
				( pin "s"
					( attribute "PN" "6"
						( Origin gPackager )
					)
					( objectStatus "EU2T1.6" )
				)
				( pin "shdn_n"
					( attribute "PN" "3"
						( Origin gPackager )
					)
					( objectStatus "EU2T1.3" )
				)
				( pin "thpad"
					( attribute "PN" "9"
						( Origin gPackager )
					)
					( objectStatus "EU2T1.9" )
				)
				( pin "vcc"
					( attribute "PN" "1"
						( Origin gPackager )
					)
					( objectStatus "EU2T1.1" )
				)
			)
			( gate "@baseboard_fab2_lib.baseboard_fab2(sch_1):page198_i13"
				( attribute "CDS_LIB" "mstr_vreg"
					( Origin gPackager )
				)
				( attribute "CDS_LMAN_SYM_OUTLINE" "-250,250,250,-250"
					( Origin gPackager )
				)
				( attribute "CDS_LOCATION" "EU8B1"
					( Origin gPackager )
				)
				( attribute "CDS_SEC" "1"
					( Origin gPackager )
				)
				( attribute "LOCATION" "EU8B1"
					( Origin gFrontEnd )
				)
				( attribute "MATERIAL" "IC"
					( Origin gFrontEnd )
				)
				( attribute "PACK_TYPE" "SM"
					( Origin gFrontEnd )
				)
				( attribute "PART_NUMBER" "G56246-001"
					( Origin gFrontEnd )
				)
				( attribute "PHYS_PAGE" "198"
					( Origin gFrontEnd )
				)
				( attribute "ROOM" "P5V_PWR_SWITCH"
					( Origin gFrontEnd )
				)
				( attribute "ROT" "0"
					( Origin gFrontEnd )
				)
				( attribute "SEC" "1"
					( Origin gFrontEnd )
				)
				( attribute "SEC_TYPE" "SM"
					( Origin gFrontEnd )
				)
				( attribute "VER" "1"
					( Origin gFrontEnd )
				)
				( attribute "XY" "(-3300,3800)"
					( Origin gFrontEnd )
				)
				( attribute "CHIPS_PART_NAME" "SLG55021"
					( Origin gPackager )
				)
				( attribute "CDS_PART_NAME" "SLG55021_SM-IC,G56246-001"
					( Origin gPackager )
				)
				( objectStatus "EU8B1" )
				( pin "d"
					( attribute "PN" "5"
						( Origin gPackager )
					)
					( objectStatus "EU8B1.5" )
				)
				( pin "g"
					( attribute "PN" "7"
						( Origin gPackager )
					)
					( objectStatus "EU8B1.7" )
				)
				( pin "gnd"
					( attribute "PN" "4"
						( Origin gPackager )
					)
					( objectStatus "EU8B1.4" )
				)
				( pin "\on\"
					( attribute "PN" "2"
						( Origin gPackager )
					)
					( objectStatus "EU8B1.2" )
				)
				( pin "pg"
					( attribute "PN" "8"
						( Origin gPackager )
					)
					( objectStatus "EU8B1.8" )
				)
				( pin "s"
					( attribute "PN" "6"
						( Origin gPackager )
					)
					( objectStatus "EU8B1.6" )
				)
				( pin "shdn_n"
					( attribute "PN" "3"
						( Origin gPackager )
					)
					( objectStatus "EU8B1.3" )
				)
				( pin "thpad"
					( attribute "PN" "9"
						( Origin gPackager )
					)
					( objectStatus "EU8B1.9" )
				)
				( pin "vcc"
					( attribute "PN" "1"
						( Origin gPackager )
					)
					( objectStatus "EU8B1.1" )
				)
			)
			( gate "@baseboard_fab2_lib.baseboard_fab2(sch_1):page198_i19"
				( attribute "CDS_LIB" "mstr_vreg"
					( Origin gPackager )
				)
				( attribute "CDS_LMAN_SYM_OUTLINE" "-250,250,250,-250"
					( Origin gPackager )
				)
				( attribute "CDS_LOCATION" "EU7E1"
					( Origin gPackager )
				)
				( attribute "CDS_SEC" "1"
					( Origin gPackager )
				)
				( attribute "LOCATION" "EU7E1"
					( Origin gFrontEnd )
				)
				( attribute "MATERIAL" "IC"
					( Origin gFrontEnd )
				)
				( attribute "PACK_TYPE" "SM"
					( Origin gFrontEnd )
				)
				( attribute "PART_NUMBER" "G56246-001"
					( Origin gFrontEnd )
				)
				( attribute "PHYS_PAGE" "198"
					( Origin gFrontEnd )
				)
				( attribute "ROOM" "P12V_PWR_SWITCH"
					( Origin gFrontEnd )
				)
				( attribute "ROT" "0"
					( Origin gFrontEnd )
				)
				( attribute "SEC" "1"
					( Origin gFrontEnd )
				)
				( attribute "SEC_TYPE" "SM"
					( Origin gFrontEnd )
				)
				( attribute "VER" "1"
					( Origin gFrontEnd )
				)
				( attribute "XY" "(-6725,1850)"
					( Origin gFrontEnd )
				)
				( attribute "CHIPS_PART_NAME" "SLG55021"
					( Origin gPackager )
				)
				( attribute "CDS_PART_NAME" "SLG55021_SM-IC,G56246-001"
					( Origin gPackager )
				)
				( objectStatus "EU7E1" )
				( pin "d"
					( attribute "PN" "5"
						( Origin gPackager )
					)
					( objectStatus "EU7E1.5" )
				)
				( pin "g"
					( attribute "PN" "7"
						( Origin gPackager )
					)
					( objectStatus "EU7E1.7" )
				)
				( pin "gnd"
					( attribute "PN" "4"
						( Origin gPackager )
					)
					( objectStatus "EU7E1.4" )
				)
				( pin "\on\"
					( attribute "PN" "2"
						( Origin gPackager )
					)
					( objectStatus "EU7E1.2" )
				)
				( pin "pg"
					( attribute "PN" "8"
						( Origin gPackager )
					)
					( objectStatus "EU7E1.8" )
				)
				( pin "s"
					( attribute "PN" "6"
						( Origin gPackager )
					)
					( objectStatus "EU7E1.6" )
				)
				( pin "shdn_n"
					( attribute "PN" "3"
						( Origin gPackager )
					)
					( objectStatus "EU7E1.3" )
				)
				( pin "thpad"
					( attribute "PN" "9"
						( Origin gPackager )
					)
					( objectStatus "EU7E1.9" )
				)
				( pin "vcc"
					( attribute "PN" "1"
						( Origin gPackager )
					)
					( objectStatus "EU7E1.1" )
				)
			)
			( gate "@baseboard_fab2_lib.baseboard_fab2(sch_1):page198_i24"
				( attribute "CDS_LIB" "dev_discrete"
					( Origin gPackager )
				)
				( attribute "CDS_LOCATION" "C8F17"
					( Origin gPackager )
				)
				( attribute "CDS_SEC" "1"
					( Origin gPackager )
				)
				( attribute "LOCATION" "C8F17"
					( Origin gFrontEnd )
				)
				( attribute "MATERIAL" "X7R"
					( Origin gFrontEnd )
				)
				( attribute "PACK_TYPE" "0402V"
					( Origin gFrontEnd )
				)
				( attribute "PART_NUMBER" "A36096-030"
					( Origin gFrontEnd )
				)
				( attribute "PHYS_PAGE" "198"
					( Origin gFrontEnd )
				)
				( attribute "ROOM" "P3V3_PWR_SWITCH"
					( Origin gFrontEnd )
				)
				( attribute "ROT" "0"
					( Origin gFrontEnd )
				)
				( attribute "SEC" "1"
					( Origin gFrontEnd )
				)
				( attribute "SEC_TYPE" "0402V"
					( Origin gFrontEnd )
				)
				( attribute "TOLERANCE" "10%"
					( Origin gFrontEnd )
				)
				( attribute "VALUE" "0.1UF"
					( Origin gFrontEnd )
				)
				( attribute "VER" "1"
					( Origin gFrontEnd )
				)
				( attribute "VOLTAGE" "16V"
					( Units "uVoltage" "V" 1.000000)
					( Origin gFrontEnd )
				)
				( attribute "XY" "(-8000,4200)"
					( Origin gFrontEnd )
				)
				( attribute "CHIPS_PART_NAME" "CAP_A"
					( Origin gPackager )
				)
				( attribute "CDS_PART_NAME" "CAP_A_0402V-0.1UF,16V,10%,X7R,A"
					( Origin gPackager )
				)
				( objectStatus "C8F17" )
				( pin "a"
					( attribute "PN" "1"
						( Origin gPackager )
					)
					( objectStatus "C8F17.1" )
				)
				( pin "b"
					( attribute "PN" "2"
						( Origin gPackager )
					)
					( objectStatus "C8F17.2" )
				)
			)
			( gate "@baseboard_fab2_lib.baseboard_fab2(sch_1):page198_i26"
				( attribute "CDS_LIB" "dev_discrete"
					( Origin gPackager )
				)
				( attribute "CDS_LOCATION" "C8B8"
					( Origin gPackager )
				)
				( attribute "CDS_SEC" "1"
					( Origin gPackager )
				)
				( attribute "LOCATION" "C8B8"
					( Origin gFrontEnd )
				)
				( attribute "MATERIAL" "X7R"
					( Origin gFrontEnd )
				)
				( attribute "PACK_TYPE" "0402V"
					( Origin gFrontEnd )
				)
				( attribute "PART_NUMBER" "A36096-030"
					( Origin gFrontEnd )
				)
				( attribute "PHYS_PAGE" "198"
					( Origin gFrontEnd )
				)
				( attribute "ROOM" "P5V_PWR_SWITCH"
					( Origin gFrontEnd )
				)
				( attribute "ROT" "0"
					( Origin gFrontEnd )
				)
				( attribute "SEC" "1"
					( Origin gFrontEnd )
				)
				( attribute "SEC_TYPE" "0402V"
					( Origin gFrontEnd )
				)
				( attribute "TOLERANCE" "10%"
					( Origin gFrontEnd )
				)
				( attribute "VALUE" "0.1UF"
					( Origin gFrontEnd )
				)
				( attribute "VER" "1"
					( Origin gFrontEnd )
				)
				( attribute "VOLTAGE" "16V"
					( Units "uVoltage" "V" 1.000000)
					( Origin gFrontEnd )
				)
				( attribute "XY" "(-4300,4125)"
					( Origin gFrontEnd )
				)
				( attribute "CHIPS_PART_NAME" "CAP_A"
					( Origin gPackager )
				)
				( attribute "CDS_PART_NAME" "CAP_A_0402V-0.1UF,16V,10%,X7R,A"
					( Origin gPackager )
				)
				( objectStatus "C8B8" )
				( pin "a"
					( attribute "PN" "1"
						( Origin gPackager )
					)
					( objectStatus "C8B8.1" )
				)
				( pin "b"
					( attribute "PN" "2"
						( Origin gPackager )
					)
					( objectStatus "C8B8.2" )
				)
			)
			( gate "@baseboard_fab2_lib.baseboard_fab2(sch_1):page198_i28"
				( attribute "CDS_LIB" "dev_discrete"
					( Origin gPackager )
				)
				( attribute "CDS_LOCATION" "C8E19"
					( Origin gPackager )
				)
				( attribute "CDS_SEC" "1"
					( Origin gPackager )
				)
				( attribute "LOCATION" "C8E19"
					( Origin gFrontEnd )
				)
				( attribute "MATERIAL" "X7R"
					( Origin gFrontEnd )
				)
				( attribute "PACK_TYPE" "0402V"
					( Origin gFrontEnd )
				)
				( attribute "PART_NUMBER" "A36096-030"
					( Origin gFrontEnd )
				)
				( attribute "PHYS_PAGE" "198"
					( Origin gFrontEnd )
				)
				( attribute "ROOM" "P12V_PWR_SWITCH"
					( Origin gFrontEnd )
				)
				( attribute "ROT" "0"
					( Origin gFrontEnd )
				)
				( attribute "SEC" "1"
					( Origin gFrontEnd )
				)
				( attribute "SEC_TYPE" "0402V"
					( Origin gFrontEnd )
				)
				( attribute "TOLERANCE" "10%"
					( Origin gFrontEnd )
				)
				( attribute "VALUE" "0.1UF"
					( Origin gFrontEnd )
				)
				( attribute "VER" "1"
					( Origin gFrontEnd )
				)
				( attribute "VOLTAGE" "16V"
					( Units "uVoltage" "V" 1.000000)
					( Origin gFrontEnd )
				)
				( attribute "XY" "(-7725,2175)"
					( Origin gFrontEnd )
				)
				( attribute "CHIPS_PART_NAME" "CAP_A"
					( Origin gPackager )
				)
				( attribute "CDS_PART_NAME" "CAP_A_0402V-0.1UF,16V,10%,X7R,A"
					( Origin gPackager )
				)
				( objectStatus "C8E19" )
				( pin "a"
					( attribute "PN" "1"
						( Origin gPackager )
					)
					( objectStatus "C8E19.1" )
				)
				( pin "b"
					( attribute "PN" "2"
						( Origin gPackager )
					)
					( objectStatus "C8E19.2" )
				)
			)
			( gate "@baseboard_fab2_lib.baseboard_fab2(sch_1):page198_i37"
				( attribute "BOM_COST" "PWR_SWITCH"
					( Origin gFrontEnd )
				)
				( attribute "CDS_LIB" "dev_discrete"
					( Origin gPackager )
				)
				( attribute "CDS_LOCATION" "C8B5"
					( Origin gPackager )
				)
				( attribute "CDS_SEC" "1"
					( Origin gPackager )
				)
				( attribute "LOCATION" "C8B5"
					( Origin gFrontEnd )
				)
				( attribute "MATERIAL" "X7R"
					( Origin gFrontEnd )
				)
				( attribute "PACK_TYPE" "0402V"
					( Origin gFrontEnd )
				)
				( attribute "PART_NUMBER" "A36096-030"
					( Origin gFrontEnd )
				)
				( attribute "PHYS_PAGE" "198"
					( Origin gFrontEnd )
				)
				( attribute "ROOM" "P5V_PWR_SWITCH"
					( Origin gFrontEnd )
				)
				( attribute "ROT" "0"
					( Origin gFrontEnd )
				)
				( attribute "SEC" "1"
					( Origin gFrontEnd )
				)
				( attribute "SEC_TYPE" "0402V"
					( Origin gFrontEnd )
				)
				( attribute "TOLERANCE" "10%"
					( Origin gFrontEnd )
				)
				( attribute "VALUE" "0.1UF"
					( Origin gFrontEnd )
				)
				( attribute "VER" "1"
					( Origin gFrontEnd )
				)
				( attribute "VOLTAGE" "16V"
					( Units "uVoltage" "V" 1.000000)
					( Origin gFrontEnd )
				)
				( attribute "XY" "(-1050,4400)"
					( Origin gFrontEnd )
				)
				( attribute "CHIPS_PART_NAME" "CAP_A"
					( Origin gPackager )
				)
				( attribute "CDS_PART_NAME" "CAP_A_0402V-0.1UF,16V,10%,X7R,A"
					( Origin gPackager )
				)
				( objectStatus "C8B5" )
				( pin "a"
					( attribute "PN" "1"
						( Origin gPackager )
					)
					( objectStatus "C8B5.1" )
				)
				( pin "b"
					( attribute "PN" "2"
						( Origin gPackager )
					)
					( objectStatus "C8B5.2" )
				)
			)
			( gate "@baseboard_fab2_lib.baseboard_fab2(sch_1):page198_i38"
				( attribute "CDS_LIB" "mstr_discrete"
					( Origin gPackager )
				)
				( attribute "CDS_LOCATION" "C8B12"
					( Origin gPackager )
				)
				( attribute "CDS_SEC" "1"
					( Origin gPackager )
				)
				( attribute "LOCATION" "C8B12"
					( Origin gFrontEnd )
				)
				( attribute "MATERIAL" "X6S"
					( Origin gFrontEnd )
				)
				( attribute "PACK_TYPE" "0805"
					( Origin gFrontEnd )
				)
				( attribute "PART_NUMBER" "C95333-007"
					( Origin gFrontEnd )
				)
				( attribute "PHYS_PAGE" "198"
					( Origin gFrontEnd )
				)
				( attribute "ROOM" "P5V_PWR_SWITCH"
					( Origin gFrontEnd )
				)
				( attribute "ROT" "0"
					( Origin gFrontEnd )
				)
				( attribute "SEC" "1"
					( Origin gFrontEnd )
				)
				( attribute "SEC_TYPE" "0805"
					( Origin gFrontEnd )
				)
				( attribute "TOLERANCE" "10%"
					( Origin gFrontEnd )
				)
				( attribute "VALUE" "10UF"
					( Origin gFrontEnd )
				)
				( attribute "VER" "1"
					( Origin gFrontEnd )
				)
				( attribute "VOLTAGE" "16V"
					( Units "uVoltage" "V" 1.000000)
					( Origin gFrontEnd )
				)
				( attribute "XY" "(-1375,4400)"
					( Origin gFrontEnd )
				)
				( attribute "CHIPS_PART_NAME" "CAP"
					( Origin gPackager )
				)
				( attribute "CDS_PART_NAME" "CAP_0805-10UF,16V,10%,X6S,C953A"
					( Origin gPackager )
				)
				( objectStatus "C8B12" )
				( pin "a"
					( attribute "PN" "1"
						( Origin gPackager )
					)
					( objectStatus "C8B12.1" )
				)
				( pin "b"
					( attribute "PN" "2"
						( Origin gPackager )
					)
					( objectStatus "C8B12.2" )
				)
			)
			( gate "@baseboard_fab2_lib.baseboard_fab2(sch_1):page198_i40"
				( attribute "CDS_LIB" "mstr_discrete"
					( Origin gPackager )
				)
				( attribute "CDS_LOCATION" "C8B6"
					( Origin gPackager )
				)
				( attribute "CDS_SEC" "1"
					( Origin gPackager )
				)
				( attribute "LOCATION" "C8B6"
					( Origin gFrontEnd )
				)
				( attribute "MATERIAL" "X6S"
					( Origin gFrontEnd )
				)
				( attribute "PACK_TYPE" "0805"
					( Origin gFrontEnd )
				)
				( attribute "PART_NUMBER" "C95333-007"
					( Origin gFrontEnd )
				)
				( attribute "PHYS_PAGE" "198"
					( Origin gFrontEnd )
				)
				( attribute "ROOM" "P5V_PWR_SWITCH"
					( Origin gFrontEnd )
				)
				( attribute "ROT" "0"
					( Origin gFrontEnd )
				)
				( attribute "SEC" "1"
					( Origin gFrontEnd )
				)
				( attribute "SEC_TYPE" "0805"
					( Origin gFrontEnd )
				)
				( attribute "TOLERANCE" "10%"
					( Origin gFrontEnd )
				)
				( attribute "VALUE" "10UF"
					( Origin gFrontEnd )
				)
				( attribute "VER" "1"
					( Origin gFrontEnd )
				)
				( attribute "VOLTAGE" "16V"
					( Units "uVoltage" "V" 1.000000)
					( Origin gFrontEnd )
				)
				( attribute "XY" "(-1100,3250)"
					( Origin gFrontEnd )
				)
				( attribute "CHIPS_PART_NAME" "CAP"
					( Origin gPackager )
				)
				( attribute "CDS_PART_NAME" "CAP_0805-10UF,16V,10%,X6S,C953A"
					( Origin gPackager )
				)
				( objectStatus "C8B6" )
				( pin "a"
					( attribute "PN" "1"
						( Origin gPackager )
					)
					( objectStatus "C8B6.1" )
				)
				( pin "b"
					( attribute "PN" "2"
						( Origin gPackager )
					)
					( objectStatus "C8B6.2" )
				)
			)
			( gate "@baseboard_fab2_lib.baseboard_fab2(sch_1):page198_i41"
				( attribute "BOM_COST" "PWR_SWITCH"
					( Origin gFrontEnd )
				)
				( attribute "CDS_LIB" "dev_discrete"
					( Origin gPackager )
				)
				( attribute "CDS_LOCATION" "C8B7"
					( Origin gPackager )
				)
				( attribute "CDS_SEC" "1"
					( Origin gPackager )
				)
				( attribute "LOCATION" "C8B7"
					( Origin gFrontEnd )
				)
				( attribute "MATERIAL" "X7R"
					( Origin gFrontEnd )
				)
				( attribute "PACK_TYPE" "0402V"
					( Origin gFrontEnd )
				)
				( attribute "PART_NUMBER" "A36096-030"
					( Origin gFrontEnd )
				)
				( attribute "PHYS_PAGE" "198"
					( Origin gFrontEnd )
				)
				( attribute "ROOM" "P5V_PWR_SWITCH"
					( Origin gFrontEnd )
				)
				( attribute "ROT" "0"
					( Origin gFrontEnd )
				)
				( attribute "SEC" "1"
					( Origin gFrontEnd )
				)
				( attribute "SEC_TYPE" "0402V"
					( Origin gFrontEnd )
				)
				( attribute "TOLERANCE" "10%"
					( Origin gFrontEnd )
				)
				( attribute "VALUE" "0.1UF"
					( Origin gFrontEnd )
				)
				( attribute "VER" "1"
					( Origin gFrontEnd )
				)
				( attribute "VOLTAGE" "16V"
					( Units "uVoltage" "V" 1.000000)
					( Origin gFrontEnd )
				)
				( attribute "XY" "(-775,3250)"
					( Origin gFrontEnd )
				)
				( attribute "CHIPS_PART_NAME" "CAP_A"
					( Origin gPackager )
				)
				( attribute "CDS_PART_NAME" "CAP_A_0402V-0.1UF,16V,10%,X7R,A"
					( Origin gPackager )
				)
				( objectStatus "C8B7" )
				( pin "a"
					( attribute "PN" "1"
						( Origin gPackager )
					)
					( objectStatus "C8B7.1" )
				)
				( pin "b"
					( attribute "PN" "2"
						( Origin gPackager )
					)
					( objectStatus "C8B7.2" )
				)
			)
			( gate "@baseboard_fab2_lib.baseboard_fab2(sch_1):page198_i43"
				( attribute "BOM_COST" "PWR_SWITCH"
					( Origin gFrontEnd )
				)
				( attribute "CDS_LIB" "dev_discrete"
					( Origin gPackager )
				)
				( attribute "CDS_LOCATION" "C2T36"
					( Origin gPackager )
				)
				( attribute "CDS_SEC" "1"
					( Origin gPackager )
				)
				( attribute "LOCATION" "C2T36"
					( Origin gFrontEnd )
				)
				( attribute "MATERIAL" "X7R"
					( Origin gFrontEnd )
				)
				( attribute "PACK_TYPE" "0402V"
					( Origin gFrontEnd )
				)
				( attribute "PART_NUMBER" "A36096-030"
					( Origin gFrontEnd )
				)
				( attribute "PHYS_PAGE" "198"
					( Origin gFrontEnd )
				)
				( attribute "ROOM" "P3V3_PWR_SWITCH"
					( Origin gFrontEnd )
				)
				( attribute "ROT" "0"
					( Origin gFrontEnd )
				)
				( attribute "SEC" "1"
					( Origin gFrontEnd )
				)
				( attribute "SEC_TYPE" "0402V"
					( Origin gFrontEnd )
				)
				( attribute "TOLERANCE" "10%"
					( Origin gFrontEnd )
				)
				( attribute "VALUE" "0.1UF"
					( Origin gFrontEnd )
				)
				( attribute "VER" "1"
					( Origin gFrontEnd )
				)
				( attribute "VOLTAGE" "16V"
					( Units "uVoltage" "V" 1.000000)
					( Origin gFrontEnd )
				)
				( attribute "XY" "(-5050,4275)"
					( Origin gFrontEnd )
				)
				( attribute "CHIPS_PART_NAME" "CAP_A"
					( Origin gPackager )
				)
				( attribute "CDS_PART_NAME" "CAP_A_0402V-0.1UF,16V,10%,X7R,A"
					( Origin gPackager )
				)
				( objectStatus "C2T36" )
				( pin "a"
					( attribute "PN" "1"
						( Origin gPackager )
					)
					( objectStatus "C2T36.1" )
				)
				( pin "b"
					( attribute "PN" "2"
						( Origin gPackager )
					)
					( objectStatus "C2T36.2" )
				)
			)
			( gate "@baseboard_fab2_lib.baseboard_fab2(sch_1):page198_i44"
				( attribute "CDS_LIB" "mstr_discrete"
					( Origin gPackager )
				)
				( attribute "CDS_LOCATION" "C2U1"
					( Origin gPackager )
				)
				( attribute "CDS_SEC" "1"
					( Origin gPackager )
				)
				( attribute "LOCATION" "C2U1"
					( Origin gFrontEnd )
				)
				( attribute "MATERIAL" "X6S"
					( Origin gFrontEnd )
				)
				( attribute "PACK_TYPE" "0805"
					( Origin gFrontEnd )
				)
				( attribute "PART_NUMBER" "C95333-007"
					( Origin gFrontEnd )
				)
				( attribute "PHYS_PAGE" "198"
					( Origin gFrontEnd )
				)
				( attribute "ROOM" "P3V3_PWR_SWITCH"
					( Origin gFrontEnd )
				)
				( attribute "ROT" "0"
					( Origin gFrontEnd )
				)
				( attribute "SEC" "1"
					( Origin gFrontEnd )
				)
				( attribute "SEC_TYPE" "0805"
					( Origin gFrontEnd )
				)
				( attribute "TOLERANCE" "10%"
					( Origin gFrontEnd )
				)
				( attribute "VALUE" "10UF"
					( Origin gFrontEnd )
				)
				( attribute "VER" "1"
					( Origin gFrontEnd )
				)
				( attribute "VOLTAGE" "16V"
					( Units "uVoltage" "V" 1.000000)
					( Origin gFrontEnd )
				)
				( attribute "XY" "(-5375,4275)"
					( Origin gFrontEnd )
				)
				( attribute "CHIPS_PART_NAME" "CAP"
					( Origin gPackager )
				)
				( attribute "CDS_PART_NAME" "CAP_0805-10UF,16V,10%,X6S,C953A"
					( Origin gPackager )
				)
				( objectStatus "C2U1" )
				( pin "a"
					( attribute "PN" "1"
						( Origin gPackager )
					)
					( objectStatus "C2U1.1" )
				)
				( pin "b"
					( attribute "PN" "2"
						( Origin gPackager )
					)
					( objectStatus "C2U1.2" )
				)
			)
			( gate "@baseboard_fab2_lib.baseboard_fab2(sch_1):page198_i46"
				( attribute "BOM_COST" "PWR_SWITCH"
					( Origin gFrontEnd )
				)
				( attribute "CDS_LIB" "dev_discrete"
					( Origin gPackager )
				)
				( attribute "CDS_LOCATION" "C2U19"
					( Origin gPackager )
				)
				( attribute "CDS_SEC" "1"
					( Origin gPackager )
				)
				( attribute "LOCATION" "C2U19"
					( Origin gFrontEnd )
				)
				( attribute "MATERIAL" "X7R"
					( Origin gFrontEnd )
				)
				( attribute "PACK_TYPE" "0402V"
					( Origin gFrontEnd )
				)
				( attribute "PART_NUMBER" "A36096-030"
					( Origin gFrontEnd )
				)
				( attribute "PHYS_PAGE" "198"
					( Origin gFrontEnd )
				)
				( attribute "ROOM" "P3V3_PWR_SWITCH"
					( Origin gFrontEnd )
				)
				( attribute "ROT" "0"
					( Origin gFrontEnd )
				)
				( attribute "SEC" "1"
					( Origin gFrontEnd )
				)
				( attribute "SEC_TYPE" "0402V"
					( Origin gFrontEnd )
				)
				( attribute "TOLERANCE" "10%"
					( Origin gFrontEnd )
				)
				( attribute "VALUE" "0.1UF"
					( Origin gFrontEnd )
				)
				( attribute "VER" "1"
					( Origin gFrontEnd )
				)
				( attribute "VOLTAGE" "16V"
					( Units "uVoltage" "V" 1.000000)
					( Origin gFrontEnd )
				)
				( attribute "XY" "(-4675,3200)"
					( Origin gFrontEnd )
				)
				( attribute "CHIPS_PART_NAME" "CAP_A"
					( Origin gPackager )
				)
				( attribute "CDS_PART_NAME" "CAP_A_0402V-0.1UF,16V,10%,X7R,A"
					( Origin gPackager )
				)
				( objectStatus "C2U19" )
				( pin "a"
					( attribute "PN" "1"
						( Origin gPackager )
					)
					( objectStatus "C2U19.1" )
				)
				( pin "b"
					( attribute "PN" "2"
						( Origin gPackager )
					)
					( objectStatus "C2U19.2" )
				)
			)
			( gate "@baseboard_fab2_lib.baseboard_fab2(sch_1):page198_i47"
				( attribute "CDS_LIB" "mstr_discrete"
					( Origin gPackager )
				)
				( attribute "CDS_LOCATION" "C2U2"
					( Origin gPackager )
				)
				( attribute "CDS_SEC" "1"
					( Origin gPackager )
				)
				( attribute "LOCATION" "C2U2"
					( Origin gFrontEnd )
				)
				( attribute "MATERIAL" "X6S"
					( Origin gFrontEnd )
				)
				( attribute "PACK_TYPE" "0805"
					( Origin gFrontEnd )
				)
				( attribute "PART_NUMBER" "C95333-007"
					( Origin gFrontEnd )
				)
				( attribute "PHYS_PAGE" "198"
					( Origin gFrontEnd )
				)
				( attribute "ROOM" "P3V3_PWR_SWITCH"
					( Origin gFrontEnd )
				)
				( attribute "ROT" "0"
					( Origin gFrontEnd )
				)
				( attribute "SEC" "1"
					( Origin gFrontEnd )
				)
				( attribute "SEC_TYPE" "0805"
					( Origin gFrontEnd )
				)
				( attribute "TOLERANCE" "10%"
					( Origin gFrontEnd )
				)
				( attribute "VALUE" "10UF"
					( Origin gFrontEnd )
				)
				( attribute "VER" "1"
					( Origin gFrontEnd )
				)
				( attribute "VOLTAGE" "16V"
					( Units "uVoltage" "V" 1.000000)
					( Origin gFrontEnd )
				)
				( attribute "XY" "(-5000,3200)"
					( Origin gFrontEnd )
				)
				( attribute "CHIPS_PART_NAME" "CAP"
					( Origin gPackager )
				)
				( attribute "CDS_PART_NAME" "CAP_0805-10UF,16V,10%,X6S,C953A"
					( Origin gPackager )
				)
				( objectStatus "C2U2" )
				( pin "a"
					( attribute "PN" "1"
						( Origin gPackager )
					)
					( objectStatus "C2U2.1" )
				)
				( pin "b"
					( attribute "PN" "2"
						( Origin gPackager )
					)
					( objectStatus "C2U2.2" )
				)
			)
			( gate "@baseboard_fab2_lib.baseboard_fab2(sch_1):page198_i49"
				( attribute "BOM_COST" "PWR_SWITCH"
					( Origin gFrontEnd )
				)
				( attribute "CDS_LIB" "dev_discrete"
					( Origin gPackager )
				)
				( attribute "CDS_LOCATION" "C7E9"
					( Origin gPackager )
				)
				( attribute "CDS_SEC" "1"
					( Origin gPackager )
				)
				( attribute "LOCATION" "C7E9"
					( Origin gFrontEnd )
				)
				( attribute "MATERIAL" "X7R"
					( Origin gFrontEnd )
				)
				( attribute "PACK_TYPE" "0402V"
					( Origin gFrontEnd )
				)
				( attribute "PART_NUMBER" "A36096-030"
					( Origin gFrontEnd )
				)
				( attribute "PHYS_PAGE" "198"
					( Origin gFrontEnd )
				)
				( attribute "ROOM" "P12V_PWR_SWITCH"
					( Origin gFrontEnd )
				)
				( attribute "ROT" "0"
					( Origin gFrontEnd )
				)
				( attribute "SEC" "1"
					( Origin gFrontEnd )
				)
				( attribute "SEC_TYPE" "0402V"
					( Origin gFrontEnd )
				)
				( attribute "TOLERANCE" "10%"
					( Origin gFrontEnd )
				)
				( attribute "VALUE" "0.1UF"
					( Origin gFrontEnd )
				)
				( attribute "VER" "1"
					( Origin gFrontEnd )
				)
				( attribute "VOLTAGE" "16V"
					( Units "uVoltage" "V" 1.000000)
					( Origin gFrontEnd )
				)
				( attribute "XY" "(-4675,1200)"
					( Origin gFrontEnd )
				)
				( attribute "CHIPS_PART_NAME" "CAP_A"
					( Origin gPackager )
				)
				( attribute "CDS_PART_NAME" "CAP_A_0402V-0.1UF,16V,10%,X7R,A"
					( Origin gPackager )
				)
				( objectStatus "C7E9" )
				( pin "a"
					( attribute "PN" "1"
						( Origin gPackager )
					)
					( objectStatus "C7E9.1" )
				)
				( pin "b"
					( attribute "PN" "2"
						( Origin gPackager )
					)
					( objectStatus "C7E9.2" )
				)
			)
			( gate "@baseboard_fab2_lib.baseboard_fab2(sch_1):page198_i50"
				( attribute "CDS_LIB" "mstr_discrete"
					( Origin gPackager )
				)
				( attribute "CDS_LOCATION" "C7E8"
					( Origin gPackager )
				)
				( attribute "CDS_SEC" "1"
					( Origin gPackager )
				)
				( attribute "LOCATION" "C7E8"
					( Origin gFrontEnd )
				)
				( attribute "MATERIAL" "X6S"
					( Origin gFrontEnd )
				)
				( attribute "PACK_TYPE" "0805"
					( Origin gFrontEnd )
				)
				( attribute "PART_NUMBER" "C95333-007"
					( Origin gFrontEnd )
				)
				( attribute "PHYS_PAGE" "198"
					( Origin gFrontEnd )
				)
				( attribute "ROOM" "P12V_PWR_SWITCH"
					( Origin gFrontEnd )
				)
				( attribute "ROT" "0"
					( Origin gFrontEnd )
				)
				( attribute "SEC" "1"
					( Origin gFrontEnd )
				)
				( attribute "SEC_TYPE" "0805"
					( Origin gFrontEnd )
				)
				( attribute "TOLERANCE" "10%"
					( Origin gFrontEnd )
				)
				( attribute "VALUE" "10UF"
					( Origin gFrontEnd )
				)
				( attribute "VER" "1"
					( Origin gFrontEnd )
				)
				( attribute "VOLTAGE" "16V"
					( Units "uVoltage" "V" 1.000000)
					( Origin gFrontEnd )
				)
				( attribute "XY" "(-5125,1250)"
					( Origin gFrontEnd )
				)
				( attribute "CHIPS_PART_NAME" "CAP"
					( Origin gPackager )
				)
				( attribute "CDS_PART_NAME" "CAP_0805-10UF,16V,10%,X6S,C953A"
					( Origin gPackager )
				)
				( objectStatus "C7E8" )
				( pin "a"
					( attribute "PN" "1"
						( Origin gPackager )
					)
					( objectStatus "C7E8.1" )
				)
				( pin "b"
					( attribute "PN" "2"
						( Origin gPackager )
					)
					( objectStatus "C7E8.2" )
				)
			)
			( gate "@baseboard_fab2_lib.baseboard_fab2(sch_1):page198_i52"
				( attribute "BOM_COST" "PWR_SWITCH"
					( Origin gFrontEnd )
				)
				( attribute "CDS_LIB" "dev_discrete"
					( Origin gPackager )
				)
				( attribute "CDS_LOCATION" "C7E5"
					( Origin gPackager )
				)
				( attribute "CDS_SEC" "1"
					( Origin gPackager )
				)
				( attribute "LOCATION" "C7E5"
					( Origin gFrontEnd )
				)
				( attribute "MATERIAL" "X7R"
					( Origin gFrontEnd )
				)
				( attribute "PACK_TYPE" "0402V"
					( Origin gFrontEnd )
				)
				( attribute "PART_NUMBER" "A36096-030"
					( Origin gFrontEnd )
				)
				( attribute "PHYS_PAGE" "198"
					( Origin gFrontEnd )
				)
				( attribute "ROOM" "P12V_PWR_SWITCH"
					( Origin gFrontEnd )
				)
				( attribute "ROT" "0"
					( Origin gFrontEnd )
				)
				( attribute "SEC" "1"
					( Origin gFrontEnd )
				)
				( attribute "SEC_TYPE" "0402V"
					( Origin gFrontEnd )
				)
				( attribute "TOLERANCE" "10%"
					( Origin gFrontEnd )
				)
				( attribute "VALUE" "0.1UF"
					( Origin gFrontEnd )
				)
				( attribute "VER" "1"
					( Origin gFrontEnd )
				)
				( attribute "VOLTAGE" "16V"
					( Units "uVoltage" "V" 1.000000)
					( Origin gFrontEnd )
				)
				( attribute "XY" "(-4775,2250)"
					( Origin gFrontEnd )
				)
				( attribute "CHIPS_PART_NAME" "CAP_A"
					( Origin gPackager )
				)
				( attribute "CDS_PART_NAME" "CAP_A_0402V-0.1UF,16V,10%,X7R,A"
					( Origin gPackager )
				)
				( objectStatus "C7E5" )
				( pin "a"
					( attribute "PN" "1"
						( Origin gPackager )
					)
					( objectStatus "C7E5.1" )
				)
				( pin "b"
					( attribute "PN" "2"
						( Origin gPackager )
					)
					( objectStatus "C7E5.2" )
				)
			)
			( gate "@baseboard_fab2_lib.baseboard_fab2(sch_1):page198_i53"
				( attribute "CDS_LIB" "mstr_discrete"
					( Origin gPackager )
				)
				( attribute "CDS_LOCATION" "C7E6"
					( Origin gPackager )
				)
				( attribute "CDS_SEC" "1"
					( Origin gPackager )
				)
				( attribute "LOCATION" "C7E6"
					( Origin gFrontEnd )
				)
				( attribute "MATERIAL" "X6S"
					( Origin gFrontEnd )
				)
				( attribute "PACK_TYPE" "0805"
					( Origin gFrontEnd )
				)
				( attribute "PART_NUMBER" "C95333-007"
					( Origin gFrontEnd )
				)
				( attribute "PHYS_PAGE" "198"
					( Origin gFrontEnd )
				)
				( attribute "ROOM" "P12V_PWR_SWITCH"
					( Origin gFrontEnd )
				)
				( attribute "ROT" "0"
					( Origin gFrontEnd )
				)
				( attribute "SEC" "1"
					( Origin gFrontEnd )
				)
				( attribute "SEC_TYPE" "0805"
					( Origin gFrontEnd )
				)
				( attribute "TOLERANCE" "10%"
					( Origin gFrontEnd )
				)
				( attribute "VALUE" "10UF"
					( Origin gFrontEnd )
				)
				( attribute "VER" "1"
					( Origin gFrontEnd )
				)
				( attribute "VOLTAGE" "16V"
					( Units "uVoltage" "V" 1.000000)
					( Origin gFrontEnd )
				)
				( attribute "XY" "(-5100,2250)"
					( Origin gFrontEnd )
				)
				( attribute "CHIPS_PART_NAME" "CAP"
					( Origin gPackager )
				)
				( attribute "CDS_PART_NAME" "CAP_0805-10UF,16V,10%,X6S,C953A"
					( Origin gPackager )
				)
				( objectStatus "C7E6" )
				( pin "a"
					( attribute "PN" "1"
						( Origin gPackager )
					)
					( objectStatus "C7E6.1" )
				)
				( pin "b"
					( attribute "PN" "2"
						( Origin gPackager )
					)
					( objectStatus "C7E6.2" )
				)
			)
			( gate "@baseboard_fab2_lib.baseboard_fab2(sch_1):page198_i61"
				( attribute "CDS_LIB" "mstr_discrete"
					( Origin gPackager )
				)
				( attribute "CDS_LOCATION" "C1B18"
					( Origin gPackager )
				)
				( attribute "CDS_SEC" "1"
					( Origin gPackager )
				)
				( attribute "LOCATION" "C1B18"
					( Origin gFrontEnd )
				)
				( attribute "MATERIAL" "X6S"
					( Origin gFrontEnd )
				)
				( attribute "PACK_TYPE" "0805"
					( Origin gFrontEnd )
				)
				( attribute "PART_NUMBER" "C95333-007"
					( Origin gFrontEnd )
				)
				( attribute "PHYS_PAGE" "198"
					( Origin gFrontEnd )
				)
				( attribute "ROOM" "P12V_FAN_PWR_SWITCH"
					( Origin gFrontEnd )
				)
				( attribute "ROT" "0"
					( Origin gFrontEnd )
				)
				( attribute "SEC" "1"
					( Origin gFrontEnd )
				)
				( attribute "SEC_TYPE" "0805"
					( Origin gFrontEnd )
				)
				( attribute "TOLERANCE" "10%"
					( Origin gFrontEnd )
				)
				( attribute "VALUE" "10UF"
					( Origin gFrontEnd )
				)
				( attribute "VER" "1"
					( Origin gFrontEnd )
				)
				( attribute "VOLTAGE" "16V"
					( Units "uVoltage" "V" 1.000000)
					( Origin gFrontEnd )
				)
				( attribute "XY" "(-1175,1225)"
					( Origin gFrontEnd )
				)
				( attribute "CHIPS_PART_NAME" "CAP"
					( Origin gPackager )
				)
				( attribute "CDS_PART_NAME" "CAP_0805-10UF,16V,10%,X6S,C953A"
					( Origin gPackager )
				)
				( objectStatus "C1B18" )
				( pin "a"
					( attribute "PN" "1"
						( Origin gPackager )
					)
					( objectStatus "C1B18.1" )
				)
				( pin "b"
					( attribute "PN" "2"
						( Origin gPackager )
					)
					( objectStatus "C1B18.2" )
				)
			)
			( gate "@baseboard_fab2_lib.baseboard_fab2(sch_1):page198_i64"
				( attribute "BOM_COST" "PWR_SWITCH"
					( Origin gFrontEnd )
				)
				( attribute "CDS_LIB" "dev_discrete"
					( Origin gPackager )
				)
				( attribute "CDS_LOCATION" "C1B19"
					( Origin gPackager )
				)
				( attribute "CDS_SEC" "1"
					( Origin gPackager )
				)
				( attribute "LOCATION" "C1B19"
					( Origin gFrontEnd )
				)
				( attribute "MATERIAL" "X7R"
					( Origin gFrontEnd )
				)
				( attribute "PACK_TYPE" "0402V"
					( Origin gFrontEnd )
				)
				( attribute "PART_NUMBER" "A36096-030"
					( Origin gFrontEnd )
				)
				( attribute "PHYS_PAGE" "198"
					( Origin gFrontEnd )
				)
				( attribute "ROOM" "P12V_FAN_PWR_SWITCH"
					( Origin gFrontEnd )
				)
				( attribute "ROT" "0"
					( Origin gFrontEnd )
				)
				( attribute "SEC" "1"
					( Origin gFrontEnd )
				)
				( attribute "SEC_TYPE" "0402V"
					( Origin gFrontEnd )
				)
				( attribute "TOLERANCE" "10%"
					( Origin gFrontEnd )
				)
				( attribute "VALUE" "0.1UF"
					( Origin gFrontEnd )
				)
				( attribute "VER" "1"
					( Origin gFrontEnd )
				)
				( attribute "VOLTAGE" "16V"
					( Units "uVoltage" "V" 1.000000)
					( Origin gFrontEnd )
				)
				( attribute "XY" "(-725,1225)"
					( Origin gFrontEnd )
				)
				( attribute "CHIPS_PART_NAME" "CAP_A"
					( Origin gPackager )
				)
				( attribute "CDS_PART_NAME" "CAP_A_0402V-0.1UF,16V,10%,X7R,A"
					( Origin gPackager )
				)
				( objectStatus "C1B19" )
				( pin "a"
					( attribute "PN" "1"
						( Origin gPackager )
					)
					( objectStatus "C1B19.1" )
				)
				( pin "b"
					( attribute "PN" "2"
						( Origin gPackager )
					)
					( objectStatus "C1B19.2" )
				)
			)
			( gate "@baseboard_fab2_lib.baseboard_fab2(sch_1):page198_i67"
				( attribute "CDS_LIB" "dev_discrete"
					( Origin gPackager )
				)
				( attribute "CDS_LOCATION" "C9M6"
					( Origin gPackager )
				)
				( attribute "CDS_SEC" "1"
					( Origin gPackager )
				)
				( attribute "LOCATION" "C9M6"
					( Origin gFrontEnd )
				)
				( attribute "MATERIAL" "X7R"
					( Origin gFrontEnd )
				)
				( attribute "PACK_TYPE" "0402V"
					( Origin gFrontEnd )
				)
				( attribute "PART_NUMBER" "A36096-030"
					( Origin gFrontEnd )
				)
				( attribute "PHYS_PAGE" "198"
					( Origin gFrontEnd )
				)
				( attribute "ROOM" "P12V_FAN_PWR_SWITCH"
					( Origin gFrontEnd )
				)
				( attribute "ROT" "0"
					( Origin gFrontEnd )
				)
				( attribute "SEC" "1"
					( Origin gFrontEnd )
				)
				( attribute "SEC_TYPE" "0402V"
					( Origin gFrontEnd )
				)
				( attribute "TOLERANCE" "10%"
					( Origin gFrontEnd )
				)
				( attribute "VALUE" "0.1UF"
					( Origin gFrontEnd )
				)
				( attribute "VER" "1"
					( Origin gFrontEnd )
				)
				( attribute "VOLTAGE" "16V"
					( Units "uVoltage" "V" 1.000000)
					( Origin gFrontEnd )
				)
				( attribute "XY" "(-3775,2150)"
					( Origin gFrontEnd )
				)
				( attribute "CHIPS_PART_NAME" "CAP_A"
					( Origin gPackager )
				)
				( attribute "CDS_PART_NAME" "CAP_A_0402V-0.1UF,16V,10%,X7R,A"
					( Origin gPackager )
				)
				( objectStatus "C9M6" )
				( pin "a"
					( attribute "PN" "1"
						( Origin gPackager )
					)
					( objectStatus "C9M6.1" )
				)
				( pin "b"
					( attribute "PN" "2"
						( Origin gPackager )
					)
					( objectStatus "C9M6.2" )
				)
			)
			( gate "@baseboard_fab2_lib.baseboard_fab2(sch_1):page198_i69"
				( attribute "CDS_LIB" "mstr_vreg"
					( Origin gPackager )
				)
				( attribute "CDS_LMAN_SYM_OUTLINE" "-250,250,250,-250"
					( Origin gPackager )
				)
				( attribute "CDS_LOCATION" "EU9M1"
					( Origin gPackager )
				)
				( attribute "CDS_SEC" "1"
					( Origin gPackager )
				)
				( attribute "LOCATION" "EU9M1"
					( Origin gFrontEnd )
				)
				( attribute "MATERIAL" "IC"
					( Origin gFrontEnd )
				)
				( attribute "PACK_TYPE" "SM"
					( Origin gFrontEnd )
				)
				( attribute "PART_NUMBER" "G56246-001"
					( Origin gFrontEnd )
				)
				( attribute "PHYS_PAGE" "198"
					( Origin gFrontEnd )
				)
				( attribute "ROOM" "P12V_FAN_PWR_SWITCH"
					( Origin gFrontEnd )
				)
				( attribute "ROT" "0"
					( Origin gFrontEnd )
				)
				( attribute "SEC" "1"
					( Origin gFrontEnd )
				)
				( attribute "SEC_TYPE" "SM"
					( Origin gFrontEnd )
				)
				( attribute "VER" "1"
					( Origin gFrontEnd )
				)
				( attribute "XY" "(-2775,1825)"
					( Origin gFrontEnd )
				)
				( attribute "CHIPS_PART_NAME" "SLG55021"
					( Origin gPackager )
				)
				( attribute "CDS_PART_NAME" "SLG55021_SM-IC,G56246-001"
					( Origin gPackager )
				)
				( objectStatus "EU9M1" )
				( pin "d"
					( attribute "PN" "5"
						( Origin gPackager )
					)
					( objectStatus "EU9M1.5" )
				)
				( pin "g"
					( attribute "PN" "7"
						( Origin gPackager )
					)
					( objectStatus "EU9M1.7" )
				)
				( pin "gnd"
					( attribute "PN" "4"
						( Origin gPackager )
					)
					( objectStatus "EU9M1.4" )
				)
				( pin "\on\"
					( attribute "PN" "2"
						( Origin gPackager )
					)
					( objectStatus "EU9M1.2" )
				)
				( pin "pg"
					( attribute "PN" "8"
						( Origin gPackager )
					)
					( objectStatus "EU9M1.8" )
				)
				( pin "s"
					( attribute "PN" "6"
						( Origin gPackager )
					)
					( objectStatus "EU9M1.6" )
				)
				( pin "shdn_n"
					( attribute "PN" "3"
						( Origin gPackager )
					)
					( objectStatus "EU9M1.3" )
				)
				( pin "thpad"
					( attribute "PN" "9"
						( Origin gPackager )
					)
					( objectStatus "EU9M1.9" )
				)
				( pin "vcc"
					( attribute "PN" "1"
						( Origin gPackager )
					)
					( objectStatus "EU9M1.1" )
				)
			)
			( gate "@baseboard_fab2_lib.baseboard_fab2(sch_1):page198_i74"
				( attribute "CDS_LIB" "mstr_discrete"
					( Origin gPackager )
				)
				( attribute "CDS_LOCATION" "C9M10"
					( Origin gPackager )
				)
				( attribute "CDS_SEC" "1"
					( Origin gPackager )
				)
				( attribute "LOCATION" "C9M10"
					( Origin gFrontEnd )
				)
				( attribute "MATERIAL" "X6S"
					( Origin gFrontEnd )
				)
				( attribute "PACK_TYPE" "0805"
					( Origin gFrontEnd )
				)
				( attribute "PART_NUMBER" "C95333-007"
					( Origin gFrontEnd )
				)
				( attribute "PHYS_PAGE" "198"
					( Origin gFrontEnd )
				)
				( attribute "ROOM" "P12V_FAN_PWR_SWITCH"
					( Origin gFrontEnd )
				)
				( attribute "ROT" "0"
					( Origin gFrontEnd )
				)
				( attribute "SEC" "1"
					( Origin gFrontEnd )
				)
				( attribute "SEC_TYPE" "0805"
					( Origin gFrontEnd )
				)
				( attribute "TOLERANCE" "10%"
					( Origin gFrontEnd )
				)
				( attribute "VALUE" "10UF"
					( Origin gFrontEnd )
				)
				( attribute "VER" "1"
					( Origin gFrontEnd )
				)
				( attribute "VOLTAGE" "16V"
					( Units "uVoltage" "V" 1.000000)
					( Origin gFrontEnd )
				)
				( attribute "XY" "(-1150,2225)"
					( Origin gFrontEnd )
				)
				( attribute "CHIPS_PART_NAME" "CAP"
					( Origin gPackager )
				)
				( attribute "CDS_PART_NAME" "CAP_0805-10UF,16V,10%,X6S,C953A"
					( Origin gPackager )
				)
				( objectStatus "C9M10" )
				( pin "a"
					( attribute "PN" "1"
						( Origin gPackager )
					)
					( objectStatus "C9M10.1" )
				)
				( pin "b"
					( attribute "PN" "2"
						( Origin gPackager )
					)
					( objectStatus "C9M10.2" )
				)
			)
			( gate "@baseboard_fab2_lib.baseboard_fab2(sch_1):page198_i76"
				( attribute "BOM_COST" "PWR_SWITCH"
					( Origin gFrontEnd )
				)
				( attribute "CDS_LIB" "dev_discrete"
					( Origin gPackager )
				)
				( attribute "CDS_LOCATION" "C9M9"
					( Origin gPackager )
				)
				( attribute "CDS_SEC" "1"
					( Origin gPackager )
				)
				( attribute "LOCATION" "C9M9"
					( Origin gFrontEnd )
				)
				( attribute "MATERIAL" "X7R"
					( Origin gFrontEnd )
				)
				( attribute "PACK_TYPE" "0402V"
					( Origin gFrontEnd )
				)
				( attribute "PART_NUMBER" "A36096-030"
					( Origin gFrontEnd )
				)
				( attribute "PHYS_PAGE" "198"
					( Origin gFrontEnd )
				)
				( attribute "ROOM" "P12V_FAN_PWR_SWITCH"
					( Origin gFrontEnd )
				)
				( attribute "ROT" "0"
					( Origin gFrontEnd )
				)
				( attribute "SEC" "1"
					( Origin gFrontEnd )
				)
				( attribute "SEC_TYPE" "0402V"
					( Origin gFrontEnd )
				)
				( attribute "TOLERANCE" "10%"
					( Origin gFrontEnd )
				)
				( attribute "VALUE" "0.1UF"
					( Origin gFrontEnd )
				)
				( attribute "VER" "1"
					( Origin gFrontEnd )
				)
				( attribute "VOLTAGE" "16V"
					( Units "uVoltage" "V" 1.000000)
					( Origin gFrontEnd )
				)
				( attribute "XY" "(-825,2225)"
					( Origin gFrontEnd )
				)
				( attribute "CHIPS_PART_NAME" "CAP_A"
					( Origin gPackager )
				)
				( attribute "CDS_PART_NAME" "CAP_A_0402V-0.1UF,16V,10%,X7R,A"
					( Origin gPackager )
				)
				( objectStatus "C9M9" )
				( pin "a"
					( attribute "PN" "1"
						( Origin gPackager )
					)
					( objectStatus "C9M9.1" )
				)
				( pin "b"
					( attribute "PN" "2"
						( Origin gPackager )
					)
					( objectStatus "C9M9.2" )
				)
			)
			( gate "@baseboard_fab2_lib.baseboard_fab2(sch_1):page198_i78"
				( attribute "BOM_COST" "IO_SLOT"
					( Origin gFrontEnd )
				)
				( attribute "CDS_LIB" "mstr_discrete"
					( Origin gPackager )
				)
				( attribute "CDS_LOCATION" "R8E12"
					( Origin gPackager )
				)
				( attribute "CDS_SEC" "1"
					( Origin gPackager )
				)
				( attribute "LOCATION" "R8E12"
					( Origin gFrontEnd )
				)
				( attribute "MATERIAL" "EMPTY"
					( Origin gFrontEnd )
				)
				( attribute "PACK_TYPE" "0402"
					( Origin gFrontEnd )
				)
				( attribute "PART_NUMBER" "G21796-072"
					( Origin gFrontEnd )
				)
				( attribute "PHYS_PAGE" "198"
					( Origin gFrontEnd )
				)
				( attribute "ROOM" "IO_SLOT"
					( Origin gFrontEnd )
				)
				( attribute "ROT" "0"
					( Origin gFrontEnd )
				)
				( attribute "SEC" "1"
					( Origin gPackager )
				)
				( attribute "TOLERANCE" "1%"
					( Origin gFrontEnd )
				)
				( attribute "VALUE" "4.75K"
					( Origin gFrontEnd )
				)
				( attribute "VER" "2"
					( Origin gFrontEnd )
				)
				( attribute "WATTAGE" "1/16W"
					( Origin gFrontEnd )
				)
				( attribute "XY" "(-6925,3050)"
					( Origin gFrontEnd )
				)
				( attribute "CHIPS_PART_NAME" "RES"
					( Origin gPackager )
				)
				( attribute "CDS_PART_NAME" "RES_0402-4.75K,1%,1/16W,EMPTY,A"
					( Origin gPackager )
				)
				( objectStatus "R8E12" )
				( pin "a"
					( attribute "PN" "1"
						( Origin gPackager )
					)
					( objectStatus "R8E12.1" )
				)
				( pin "b"
					( attribute "PN" "2"
						( Origin gPackager )
					)
					( objectStatus "R8E12.2" )
				)
			)
			( gate "@baseboard_fab2_lib.baseboard_fab2(sch_1):page198_i83"
				( attribute "CDS_LIB" "mstr_discrete"
					( Origin gPackager )
				)
				( attribute "CDS_LOCATION" "R8B4"
					( Origin gPackager )
				)
				( attribute "CDS_SEC" "1"
					( Origin gPackager )
				)
				( attribute "LOCATION" "R8B4"
					( Origin gFrontEnd )
				)
				( attribute "MATERIAL" "CHIP"
					( Origin gFrontEnd )
				)
				( attribute "PACK_TYPE" "0402"
					( Origin gFrontEnd )
				)
				( attribute "PART_NUMBER" "G21796-010"
					( Origin gFrontEnd )
				)
				( attribute "PHYS_PAGE" "198"
					( Origin gFrontEnd )
				)
				( attribute "ROOM" "HOT_SWAP"
					( Origin gFrontEnd )
				)
				( attribute "ROT" "0"
					( Origin gFrontEnd )
				)
				( attribute "SEC" "1"
					( Origin gFrontEnd )
				)
				( attribute "SEC_TYPE" "0402"
					( Origin gFrontEnd )
				)
				( attribute "TOLERANCE" "1%"
					( Origin gFrontEnd )
				)
				( attribute "VALUE" "100.0K"
					( Origin gFrontEnd )
				)
				( attribute "VER" "2"
					( Origin gFrontEnd )
				)
				( attribute "WATTAGE" "1/16W"
					( Origin gFrontEnd )
				)
				( attribute "XY" "(-6850,2625)"
					( Origin gFrontEnd )
				)
				( attribute "CHIPS_PART_NAME" "RES"
					( Origin gPackager )
				)
				( attribute "CDS_PART_NAME" "RES_0402-100.0K,1%,1/16W,CHIP,A"
					( Origin gPackager )
				)
				( objectStatus "R8B4" )
				( pin "a"
					( attribute "PN" "1"
						( Origin gPackager )
					)
					( objectStatus "R8B4.1" )
				)
				( pin "b"
					( attribute "PN" "2"
						( Origin gPackager )
					)
					( objectStatus "R8B4.2" )
				)
			)
			( gate "@baseboard_fab2_lib.baseboard_fab2(sch_1):page198_i85"
				( attribute "CDS_LIB" "mstr_discrete"
					( Origin gPackager )
				)
				( attribute "CDS_LOCATION" "Q8G1"
					( Origin gPackager )
				)
				( attribute "CDS_SEC" "1"
					( Origin gPackager )
				)
				( attribute "LOCATION" "Q8G1"
					( Origin gFrontEnd )
				)
				( attribute "MATERIAL" "NFET"
					( Origin gFrontEnd )
				)
				( attribute "PACK_TYPE" "LCC3"
					( Origin gFrontEnd )
				)
				( attribute "PART_NUMBER" "G26762-001"
					( Origin gFrontEnd )
				)
				( attribute "PHYS_PAGE" "198"
					( Origin gFrontEnd )
				)
				( attribute "ROT" "2"
					( Origin gFrontEnd )
				)
				( attribute "SEC" "1"
					( Origin gFrontEnd )
				)
				( attribute "SEC_TYPE" "LCC3"
					( Origin gFrontEnd )
				)
				( attribute "VALUE" "BSZ019N03LS"
					( Origin gFrontEnd )
				)
				( attribute "VER" "3"
					( Origin gFrontEnd )
				)
				( attribute "XY" "(-5650,3900)"
					( Origin gFrontEnd )
				)
				( attribute "CHIPS_PART_NAME" "MOSFET_N"
					( Origin gPackager )
				)
				( attribute "CDS_PART_NAME" "MOSFET_N_LCC3-BSZ019N03LS,NFETA"
					( Origin gPackager )
				)
				( objectStatus "Q8G1" )
				( pin "drn"
					( attribute "PN" "5"
						( Origin gPackager )
					)
					( objectStatus "Q8G1.5" )
				)
				( pin "gate"
					( attribute "PN" "4"
						( Origin gPackager )
					)
					( objectStatus "Q8G1.4" )
				)
				( pin "src"
					( attribute "PN" "1"
						( Origin gPackager )
					)
					( objectStatus "Q8G1.1" )
				)
			)
			( gate "@baseboard_fab2_lib.baseboard_fab2(sch_1):page198_i86"
				( attribute "CDS_LIB" "mstr_discrete"
					( Origin gPackager )
				)
				( attribute "CDS_LOCATION" "Q1B1"
					( Origin gPackager )
				)
				( attribute "CDS_SEC" "1"
					( Origin gPackager )
				)
				( attribute "LOCATION" "Q1B1"
					( Origin gFrontEnd )
				)
				( attribute "MATERIAL" "NFET"
					( Origin gFrontEnd )
				)
				( attribute "PACK_TYPE" "LCC3"
					( Origin gFrontEnd )
				)
				( attribute "PART_NUMBER" "G26762-001"
					( Origin gFrontEnd )
				)
				( attribute "PHYS_PAGE" "198"
					( Origin gFrontEnd )
				)
				( attribute "ROT" "2"
					( Origin gFrontEnd )
				)
				( attribute "SEC" "1"
					( Origin gFrontEnd )
				)
				( attribute "SEC_TYPE" "LCC3"
					( Origin gFrontEnd )
				)
				( attribute "VALUE" "BSZ019N03LS"
					( Origin gFrontEnd )
				)
				( attribute "VER" "3"
					( Origin gFrontEnd )
				)
				( attribute "XY" "(-1375,1850)"
					( Origin gFrontEnd )
				)
				( attribute "CHIPS_PART_NAME" "MOSFET_N"
					( Origin gPackager )
				)
				( attribute "CDS_PART_NAME" "MOSFET_N_LCC3-BSZ019N03LS,NFETA"
					( Origin gPackager )
				)
				( objectStatus "Q1B1" )
				( pin "drn"
					( attribute "PN" "5"
						( Origin gPackager )
					)
					( objectStatus "Q1B1.5" )
				)
				( pin "gate"
					( attribute "PN" "4"
						( Origin gPackager )
					)
					( objectStatus "Q1B1.4" )
				)
				( pin "src"
					( attribute "PN" "1"
						( Origin gPackager )
					)
					( objectStatus "Q1B1.1" )
				)
			)
			( gate "@baseboard_fab2_lib.baseboard_fab2(sch_1):page198_i87"
				( attribute "CDS_LIB" "mstr_discrete"
					( Origin gPackager )
				)
				( attribute "CDS_LOCATION" "Q8B1"
					( Origin gPackager )
				)
				( attribute "CDS_SEC" "1"
					( Origin gPackager )
				)
				( attribute "LOCATION" "Q8B1"
					( Origin gFrontEnd )
				)
				( attribute "MATERIAL" "NFET"
					( Origin gFrontEnd )
				)
				( attribute "PACK_TYPE" "LCC3"
					( Origin gFrontEnd )
				)
				( attribute "PART_NUMBER" "G26762-001"
					( Origin gFrontEnd )
				)
				( attribute "PHYS_PAGE" "198"
					( Origin gFrontEnd )
				)
				( attribute "ROT" "2"
					( Origin gFrontEnd )
				)
				( attribute "SEC" "1"
					( Origin gFrontEnd )
				)
				( attribute "SEC_TYPE" "LCC3"
					( Origin gFrontEnd )
				)
				( attribute "VALUE" "BSZ019N03LS"
					( Origin gFrontEnd )
				)
				( attribute "VER" "3"
					( Origin gFrontEnd )
				)
				( attribute "XY" "(-1600,3850)"
					( Origin gFrontEnd )
				)
				( attribute "CHIPS_PART_NAME" "MOSFET_N"
					( Origin gPackager )
				)
				( attribute "CDS_PART_NAME" "MOSFET_N_LCC3-BSZ019N03LS,NFETA"
					( Origin gPackager )
				)
				( objectStatus "Q8B1" )
				( pin "drn"
					( attribute "PN" "5"
						( Origin gPackager )
					)
					( objectStatus "Q8B1.5" )
				)
				( pin "gate"
					( attribute "PN" "4"
						( Origin gPackager )
					)
					( objectStatus "Q8B1.4" )
				)
				( pin "src"
					( attribute "PN" "1"
						( Origin gPackager )
					)
					( objectStatus "Q8B1.1" )
				)
			)
			( gate "@baseboard_fab2_lib.baseboard_fab2(sch_1):page198_i88"
				( attribute "CDS_LIB" "mstr_discrete"
					( Origin gPackager )
				)
				( attribute "CDS_LOCATION" "Q7E7"
					( Origin gPackager )
				)
				( attribute "CDS_SEC" "1"
					( Origin gPackager )
				)
				( attribute "LOCATION" "Q7E7"
					( Origin gFrontEnd )
				)
				( attribute "MATERIAL" "NFET"
					( Origin gFrontEnd )
				)
				( attribute "PACK_TYPE" "LCC3"
					( Origin gFrontEnd )
				)
				( attribute "PART_NUMBER" "G26762-001"
					( Origin gFrontEnd )
				)
				( attribute "PHYS_PAGE" "198"
					( Origin gFrontEnd )
				)
				( attribute "ROT" "2"
					( Origin gFrontEnd )
				)
				( attribute "SEC" "1"
					( Origin gFrontEnd )
				)
				( attribute "SEC_TYPE" "LCC3"
					( Origin gFrontEnd )
				)
				( attribute "VALUE" "BSZ019N03LS"
					( Origin gFrontEnd )
				)
				( attribute "VER" "3"
					( Origin gFrontEnd )
				)
				( attribute "XY" "(-5325,1850)"
					( Origin gFrontEnd )
				)
				( attribute "CHIPS_PART_NAME" "MOSFET_N"
					( Origin gPackager )
				)
				( attribute "CDS_PART_NAME" "MOSFET_N_LCC3-BSZ019N03LS,NFETA"
					( Origin gPackager )
				)
				( objectStatus "Q7E7" )
				( pin "drn"
					( attribute "PN" "5"
						( Origin gPackager )
					)
					( objectStatus "Q7E7.5" )
				)
				( pin "gate"
					( attribute "PN" "4"
						( Origin gPackager )
					)
					( objectStatus "Q7E7.4" )
				)
				( pin "src"
					( attribute "PN" "1"
						( Origin gPackager )
					)
					( objectStatus "Q7E7.1" )
				)
			)
			( gate "@baseboard_fab2_lib.baseboard_fab2(sch_1):page199_i2"
				( attribute "CDS_LIB" "mstr_discrete"
					( Origin gPackager )
				)
				( attribute "CDS_LOCATION" "R9P30"
					( Origin gPackager )
				)
				( attribute "CDS_SEC" "1"
					( Origin gPackager )
				)
				( attribute "LOCATION" "R9P30"
					( Origin gFrontEnd )
				)
				( attribute "MATERIAL" "CHIP"
					( Origin gFrontEnd )
				)
				( attribute "PACK_TYPE" "0603"
					( Origin gFrontEnd )
				)
				( attribute "PART_NUMBER" "G22026-041"
					( Origin gFrontEnd )
				)
				( attribute "PHYS_PAGE" "199"
					( Origin gFrontEnd )
				)
				( attribute "ROOM" "HOT_SWAP"
					( Origin gFrontEnd )
				)
				( attribute "ROT" "0"
					( Origin gFrontEnd )
				)
				( attribute "SEC" "1"
					( Origin gFrontEnd )
				)
				( attribute "SEC_TYPE" "0603"
					( Origin gFrontEnd )
				)
				( attribute "TOLERANCE" "1%"
					( Origin gFrontEnd )
				)
				( attribute "VALUE" "10.0"
					( Origin gFrontEnd )
				)
				( attribute "VER" "2"
					( Origin gFrontEnd )
				)
				( attribute "WATTAGE" "1/10W"
					( Origin gFrontEnd )
				)
				( attribute "XY" "(-5525,4025)"
					( Origin gFrontEnd )
				)
				( attribute "CHIPS_PART_NAME" "RES"
					( Origin gPackager )
				)
				( attribute "CDS_PART_NAME" "RES_0603-10.0,1%,1/10W,CHIP,G2A"
					( Origin gPackager )
				)
				( objectStatus "R9P30" )
				( pin "a"
					( attribute "PN" "1"
						( Origin gPackager )
					)
					( objectStatus "R9P30.1" )
				)
				( pin "b"
					( attribute "PN" "2"
						( Origin gPackager )
					)
					( objectStatus "R9P30.2" )
				)
			)
			( gate "@baseboard_fab2_lib.baseboard_fab2(sch_1):page199_i3"
				( attribute "CDS_LIB" "mstr_discrete"
					( Origin gPackager )
				)
				( attribute "CDS_LOCATION" "C1D25"
					( Origin gPackager )
				)
				( attribute "CDS_SEC" "1"
					( Origin gPackager )
				)
				( attribute "LOCATION" "C1D25"
					( Origin gFrontEnd )
				)
				( attribute "MATERIAL" "X6S"
					( Origin gFrontEnd )
				)
				( attribute "PACK_TYPE" "0402"
					( Origin gFrontEnd )
				)
				( attribute "PART_NUMBER" "D97712-011"
					( Origin gFrontEnd )
				)
				( attribute "PHYS_PAGE" "199"
					( Origin gFrontEnd )
				)
				( attribute "ROOM" "HOT_SWAP"
					( Origin gFrontEnd )
				)
				( attribute "ROT" "0"
					( Origin gFrontEnd )
				)
				( attribute "SEC" "1"
					( Origin gFrontEnd )
				)
				( attribute "SEC_TYPE" "0402"
					( Origin gFrontEnd )
				)
				( attribute "TOLERANCE" "10%"
					( Origin gFrontEnd )
				)
				( attribute "VALUE" "1.0UF"
					( Origin gFrontEnd )
				)
				( attribute "VER" "1"
					( Origin gFrontEnd )
				)
				( attribute "VOLTAGE" "16V"
					( Units "uVoltage" "V" 1.000000)
					( Origin gFrontEnd )
				)
				( attribute "XY" "(-5525,3600)"
					( Origin gFrontEnd )
				)
				( attribute "CHIPS_PART_NAME" "CAP"
					( Origin gPackager )
				)
				( attribute "CDS_PART_NAME" "CAP_0402-1.0UF,16V,10%,X6S,D97A"
					( Origin gPackager )
				)
				( objectStatus "C1D25" )
				( pin "a"
					( attribute "PN" "1"
						( Origin gPackager )
					)
					( objectStatus "C1D25.1" )
				)
				( pin "b"
					( attribute "PN" "2"
						( Origin gPackager )
					)
					( objectStatus "C1D25.2" )
				)
			)
			( gate "@baseboard_fab2_lib.baseboard_fab2(sch_1):page199_i6"
				( attribute "CDS_LIB" "mstr_discrete"
					( Origin gPackager )
				)
				( attribute "CDS_LOCATION" "R9P28"
					( Origin gPackager )
				)
				( attribute "CDS_SEC" "1"
					( Origin gPackager )
				)
				( attribute "LOCATION" "R9P28"
					( Origin gFrontEnd )
				)
				( attribute "MATERIAL" "CHIP"
					( Origin gFrontEnd )
				)
				( attribute "PACK_TYPE" "0402"
					( Origin gFrontEnd )
				)
				( attribute "PART_NUMBER" "G21796-010"
					( Origin gFrontEnd )
				)
				( attribute "PHYS_PAGE" "199"
					( Origin gFrontEnd )
				)
				( attribute "ROOM" "HOT_SWAP"
					( Origin gFrontEnd )
				)
				( attribute "ROT" "0"
					( Origin gFrontEnd )
				)
				( attribute "SEC" "1"
					( Origin gFrontEnd )
				)
				( attribute "SEC_TYPE" "0402"
					( Origin gFrontEnd )
				)
				( attribute "TOLERANCE" "1%"
					( Origin gFrontEnd )
				)
				( attribute "VALUE" "100.0K"
					( Origin gFrontEnd )
				)
				( attribute "VER" "2"
					( Origin gFrontEnd )
				)
				( attribute "WATTAGE" "1/16W"
					( Origin gFrontEnd )
				)
				( attribute "XY" "(-7200,4025)"
					( Origin gFrontEnd )
				)
				( attribute "CHIPS_PART_NAME" "RES"
					( Origin gPackager )
				)
				( attribute "CDS_PART_NAME" "RES_0402-100.0K,1%,1/16W,CHIP,A"
					( Origin gPackager )
				)
				( objectStatus "R9P28" )
				( pin "a"
					( attribute "PN" "1"
						( Origin gPackager )
					)
					( objectStatus "R9P28.1" )
				)
				( pin "b"
					( attribute "PN" "2"
						( Origin gPackager )
					)
					( objectStatus "R9P28.2" )
				)
			)
			( gate "@baseboard_fab2_lib.baseboard_fab2(sch_1):page199_i7"
				( attribute "CDS_LIB" "dev_discrete"
					( Origin gPackager )
				)
				( attribute "CDS_LOCATION" "C1D27"
					( Origin gPackager )
				)
				( attribute "CDS_SEC" "1"
					( Origin gPackager )
				)
				( attribute "LOCATION" "C1D27"
					( Origin gFrontEnd )
				)
				( attribute "MATERIAL" "X7R"
					( Origin gFrontEnd )
				)
				( attribute "PACK_TYPE" "0402V"
					( Origin gFrontEnd )
				)
				( attribute "PART_NUMBER" "A36096-030"
					( Origin gFrontEnd )
				)
				( attribute "PHYS_PAGE" "199"
					( Origin gFrontEnd )
				)
				( attribute "ROOM" "HOT_SWAP"
					( Origin gFrontEnd )
				)
				( attribute "ROT" "2"
					( Origin gFrontEnd )
				)
				( attribute "SEC" "1"
					( Origin gFrontEnd )
				)
				( attribute "SEC_TYPE" "0402V"
					( Origin gFrontEnd )
				)
				( attribute "TOLERANCE" "10%"
					( Origin gFrontEnd )
				)
				( attribute "VALUE" "0.1UF"
					( Origin gFrontEnd )
				)
				( attribute "VER" "1"
					( Origin gFrontEnd )
				)
				( attribute "VOLTAGE" "16V"
					( Units "uVoltage" "V" 1.000000)
					( Origin gFrontEnd )
				)
				( attribute "XY" "(-6775,3575)"
					( Origin gFrontEnd )
				)
				( attribute "CHIPS_PART_NAME" "CAP_A"
					( Origin gPackager )
				)
				( attribute "CDS_PART_NAME" "CAP_A_0402V-0.1UF,16V,10%,X7R,A"
					( Origin gPackager )
				)
				( objectStatus "C1D27" )
				( pin "a"
					( attribute "PN" "1"
						( Origin gPackager )
					)
					( objectStatus "C1D27.1" )
				)
				( pin "b"
					( attribute "PN" "2"
						( Origin gPackager )
					)
					( objectStatus "C1D27.2" )
				)
			)
			( gate "@baseboard_fab2_lib.baseboard_fab2(sch_1):page199_i9"
				( attribute "CDS_LIB" "mstr_discrete"
					( Origin gPackager )
				)
				( attribute "CDS_LOCATION" "R1D43"
					( Origin gPackager )
				)
				( attribute "CDS_SEC" "1"
					( Origin gPackager )
				)
				( attribute "LOCATION" "R1D43"
					( Origin gFrontEnd )
				)
				( attribute "MATERIAL" "CHIP"
					( Origin gFrontEnd )
				)
				( attribute "PACK_TYPE" "0402"
					( Origin gFrontEnd )
				)
				( attribute "PART_NUMBER" "G21796-177"
					( Origin gFrontEnd )
				)
				( attribute "PHYS_PAGE" "199"
					( Origin gFrontEnd )
				)
				( attribute "ROOM" "HOT_SWAP"
					( Origin gFrontEnd )
				)
				( attribute "ROT" "0"
					( Origin gFrontEnd )
				)
				( attribute "SEC" "1"
					( Origin gFrontEnd )
				)
				( attribute "SEC_TYPE" "0402"
					( Origin gFrontEnd )
				)
				( attribute "TOLERANCE" "1%"
					( Origin gFrontEnd )
				)
				( attribute "VALUE" "7.5K"
					( Origin gFrontEnd )
				)
				( attribute "VER" "2"
					( Origin gFrontEnd )
				)
				( attribute "WATTAGE" "1/16W"
					( Origin gFrontEnd )
				)
				( attribute "XY" "(-7200,3625)"
					( Origin gFrontEnd )
				)
				( attribute "CHIPS_PART_NAME" "RES"
					( Origin gPackager )
				)
				( attribute "CDS_PART_NAME" "RES_0402-7.5K,1%,1/16W,CHIP,G2A"
					( Origin gPackager )
				)
				( objectStatus "R1D43" )
				( pin "a"
					( attribute "PN" "1"
						( Origin gPackager )
					)
					( objectStatus "R1D43.1" )
				)
				( pin "b"
					( attribute "PN" "2"
						( Origin gPackager )
					)
					( objectStatus "R1D43.2" )
				)
			)
			( gate "@baseboard_fab2_lib.baseboard_fab2(sch_1):page199_i10"
				( attribute "CDS_LIB" "mstr_controller"
					( Origin gPackager )
				)
				( attribute "CDS_LOCATION" "EU1D2"
					( Origin gPackager )
				)
				( attribute "CDS_SEC" "1"
					( Origin gPackager )
				)
				( attribute "LOCATION" "EU1D2"
					( Origin gFrontEnd )
				)
				( attribute "MATERIAL" "IC"
					( Origin gFrontEnd )
				)
				( attribute "PACK_TYPE" "SM"
					( Origin gFrontEnd )
				)
				( attribute "PART_NUMBER" "G99251-001"
					( Origin gFrontEnd )
				)
				( attribute "PHYS_PAGE" "199"
					( Origin gFrontEnd )
				)
				( attribute "ROOM" "HOT_SWAP"
					( Origin gFrontEnd )
				)
				( attribute "ROT" "0"
					( Origin gFrontEnd )
				)
				( attribute "SEC" "1"
					( Origin gFrontEnd )
				)
				( attribute "SEC_TYPE" "SM"
					( Origin gFrontEnd )
				)
				( attribute "VER" "1"
					( Origin gFrontEnd )
				)
				( attribute "XY" "(-3250,2575)"
					( Origin gFrontEnd )
				)
				( attribute "CHIPS_PART_NAME" "ADM1278"
					( Origin gPackager )
				)
				( attribute "CDS_PART_NAME" "ADM1278_SM-IC,G99251-001"
					( Origin gPackager )
				)
				( objectStatus "EU1D2" )
				( pin "adr1"
					( attribute "PN" "7"
						( Origin gPackager )
					)
					( objectStatus "EU1D2.7" )
				)
				( pin "adr2"
					( attribute "PN" "8"
						( Origin gPackager )
					)
					( objectStatus "EU1D2.8" )
				)
				( pin "csout"
					( attribute "PN" "19"
						( Origin gPackager )
					)
					( objectStatus "EU1D2.19" )
				)
				( pin "enable"
					( attribute "PN" "12"
						( Origin gPackager )
					)
					( objectStatus "EU1D2.12" )
				)
				( pin "ep"
					( attribute "PN" "33"
						( Origin gPackager )
					)
					( objectStatus "EU1D2.33" )
				)
				( pin "fault_n"
					( attribute "PN" "6"
						( Origin gPackager )
					)
					( objectStatus "EU1D2.6" )
				)
				( pin "gate"
					( attribute "PN" "24"
						( Origin gPackager )
					)
					( objectStatus "EU1D2.24" )
				)
				( pin "gnd"
					( attribute "PN" "22"
						( Origin gPackager )
					)
					( objectStatus "EU1D2.22" )
				)
				( pin "gpo1_alert1_n_conv"
					( attribute "PN" "13"
						( Origin gPackager )
					)
					( objectStatus "EU1D2.13" )
				)
				( pin "gpo2_alert2_n"
					( attribute "PN" "14"
						( Origin gPackager )
					)
					( objectStatus "EU1D2.14" )
				)
				( pin "hsn"
					( attribute "PN" "27"
						( Origin gPackager )
					)
					( objectStatus "EU1D2.27" )
				)
				( pin "hsp"
					( attribute "PN" "28"
						( Origin gPackager )
					)
					( objectStatus "EU1D2.28" )
				)
				( pin "iset"
					( attribute "PN" "3"
						( Origin gPackager )
					)
					( objectStatus "EU1D2.3" )
				)
				( pin "istart"
					( attribute "PN" "4"
						( Origin gPackager )
					)
					( objectStatus "EU1D2.4" )
				)
				( pin "mclk"
					( attribute "PN" "10"
						( Origin gPackager )
					)
					( objectStatus "EU1D2.10" )
				)
				( pin "mdat"
					( attribute "PN" "11"
						( Origin gPackager )
					)
					( objectStatus "EU1D2.11" )
				)
				( pin "mon"
					( attribute "PN" "26"
						( Origin gPackager )
					)
					( objectStatus "EU1D2.26" )
				)
				( pin "mop"
					( attribute "PN" "29"
						( Origin gPackager )
					)
					( objectStatus "EU1D2.29" )
				)
				( pin "ov"
					( attribute "PN" "32"
						( Origin gPackager )
					)
					( objectStatus "EU1D2.32" )
				)
				( pin "pgnd"
					( attribute "PN" "23"
						( Origin gPackager )
					)
					( objectStatus "EU1D2.23" )
				)
				( pin "pset"
					( attribute "PN" "1"
						( Origin gPackager )
					)
					( objectStatus "EU1D2.1" )
				)
				( pin "pwgin"
					( attribute "PN" "21"
						( Origin gPackager )
					)
					( objectStatus "EU1D2.21" )
				)
				( pin "pwrgd"
					( attribute "PN" "18"
						( Origin gPackager )
					)
					( objectStatus "EU1D2.18" )
				)
				( pin "retry_n"
					( attribute "PN" "17"
						( Origin gPackager )
					)
					( objectStatus "EU1D2.17" )
				)
				( pin "scl"
					( attribute "PN" "16"
						( Origin gPackager )
					)
					( objectStatus "EU1D2.16" )
				)
				( pin "sda"
					( attribute "PN" "15"
						( Origin gPackager )
					)
					( objectStatus "EU1D2.15" )
				)
				( pin "spiss_n"
					( attribute "PN" "9"
						( Origin gPackager )
					)
					( objectStatus "EU1D2.9" )
				)
				( pin "temp"
					( attribute "PN" "25"
						( Origin gPackager )
					)
					( objectStatus "EU1D2.25" )
				)
				( pin "timer"
					( attribute "PN" "5"
						( Origin gPackager )
					)
					( objectStatus "EU1D2.5" )
				)
				( pin "uv"
					( attribute "PN" "31"
						( Origin gPackager )
					)
					( objectStatus "EU1D2.31" )
				)
				( pin "vcap"
					( attribute "PN" "2"
						( Origin gPackager )
					)
					( objectStatus "EU1D2.2" )
				)
				( pin "vcc"
					( attribute "PN" "30"
						( Origin gPackager )
					)
					( objectStatus "EU1D2.30" )
				)
				( pin "vout"
					( attribute "PN" "20"
						( Origin gPackager )
					)
					( objectStatus "EU1D2.20" )
				)
			)
			( gate "@baseboard_fab2_lib.baseboard_fab2(sch_1):page199_i12"
				( attribute "CDS_LIB" "mstr_discrete"
					( Origin gPackager )
				)
				( attribute "CDS_LOCATION" "R9P29"
					( Origin gPackager )
				)
				( attribute "CDS_SEC" "1"
					( Origin gPackager )
				)
				( attribute "LOCATION" "R9P29"
					( Origin gFrontEnd )
				)
				( attribute "MATERIAL" "CHIP"
					( Origin gFrontEnd )
				)
				( attribute "PACK_TYPE" "0402"
					( Origin gFrontEnd )
				)
				( attribute "PART_NUMBER" "G21796-010"
					( Origin gFrontEnd )
				)
				( attribute "PHYS_PAGE" "199"
					( Origin gFrontEnd )
				)
				( attribute "ROOM" "HOT_SWAP"
					( Origin gFrontEnd )
				)
				( attribute "ROT" "0"
					( Origin gFrontEnd )
				)
				( attribute "SEC" "1"
					( Origin gFrontEnd )
				)
				( attribute "SEC_TYPE" "0402"
					( Origin gFrontEnd )
				)
				( attribute "TOLERANCE" "1%"
					( Origin gFrontEnd )
				)
				( attribute "VALUE" "100.0K"
					( Origin gFrontEnd )
				)
				( attribute "VER" "2"
					( Origin gFrontEnd )
				)
				( attribute "WATTAGE" "1/16W"
					( Origin gFrontEnd )
				)
				( attribute "XY" "(-6500,4050)"
					( Origin gFrontEnd )
				)
				( attribute "CHIPS_PART_NAME" "RES"
					( Origin gPackager )
				)
				( attribute "CDS_PART_NAME" "RES_0402-100.0K,1%,1/16W,CHIP,A"
					( Origin gPackager )
				)
				( objectStatus "R9P29" )
				( pin "a"
					( attribute "PN" "1"
						( Origin gPackager )
					)
					( objectStatus "R9P29.1" )
				)
				( pin "b"
					( attribute "PN" "2"
						( Origin gPackager )
					)
					( objectStatus "R9P29.2" )
				)
			)
			( gate "@baseboard_fab2_lib.baseboard_fab2(sch_1):page199_i13"
				( attribute "CDS_LIB" "mstr_discrete"
					( Origin gPackager )
				)
				( attribute "CDS_LOCATION" "R1D42"
					( Origin gPackager )
				)
				( attribute "CDS_SEC" "1"
					( Origin gPackager )
				)
				( attribute "LOCATION" "R1D42"
					( Origin gFrontEnd )
				)
				( attribute "MATERIAL" "CHIP"
					( Origin gFrontEnd )
				)
				( attribute "PACK_TYPE" "0402"
					( Origin gFrontEnd )
				)
				( attribute "PART_NUMBER" "G21796-220"
					( Origin gFrontEnd )
				)
				( attribute "PHYS_PAGE" "199"
					( Origin gFrontEnd )
				)
				( attribute "ROOM" "HOT_SWAP"
					( Origin gFrontEnd )
				)
				( attribute "ROT" "0"
					( Origin gFrontEnd )
				)
				( attribute "SEC" "1"
					( Origin gFrontEnd )
				)
				( attribute "SEC_TYPE" "0402"
					( Origin gFrontEnd )
				)
				( attribute "TOLERANCE" "1%"
					( Origin gFrontEnd )
				)
				( attribute "VALUE" "11K"
					( Origin gFrontEnd )
				)
				( attribute "VER" "2"
					( Origin gFrontEnd )
				)
				( attribute "WATTAGE" "1/16W"
					( Origin gFrontEnd )
				)
				( attribute "XY" "(-6500,3600)"
					( Origin gFrontEnd )
				)
				( attribute "CHIPS_PART_NAME" "RES"
					( Origin gPackager )
				)
				( attribute "CDS_PART_NAME" "RES_0402-11K,1%,1/16W,CHIP,G21A"
					( Origin gPackager )
				)
				( objectStatus "R1D42" )
				( pin "a"
					( attribute "PN" "1"
						( Origin gPackager )
					)
					( objectStatus "R1D42.1" )
				)
				( pin "b"
					( attribute "PN" "2"
						( Origin gPackager )
					)
					( objectStatus "R1D42.2" )
				)
			)
			( gate "@baseboard_fab2_lib.baseboard_fab2(sch_1):page199_i15"
				( attribute "CDS_LIB" "mstr_discrete"
					( Origin gPackager )
				)
				( attribute "CDS_LOCATION" "R1D37"
					( Origin gPackager )
				)
				( attribute "CDS_SEC" "1"
					( Origin gPackager )
				)
				( attribute "LOCATION" "R1D37"
					( Origin gFrontEnd )
				)
				( attribute "MATERIAL" "CHIP"
					( Origin gFrontEnd )
				)
				( attribute "NO_XNET_CONNECTION" "1"
					( Origin gFrontEnd )
				)
				( attribute "PACK_TYPE" "0402"
					( Origin gFrontEnd )
				)
				( attribute "PART_NUMBER" "G21796-010"
					( Origin gFrontEnd )
				)
				( attribute "PHYS_PAGE" "199"
					( Origin gFrontEnd )
				)
				( attribute "ROOM" "HOT_SWAP"
					( Origin gFrontEnd )
				)
				( attribute "ROT" "0"
					( Origin gFrontEnd )
				)
				( attribute "SEC" "1"
					( Origin gFrontEnd )
				)
				( attribute "SEC_TYPE" "0402"
					( Origin gFrontEnd )
				)
				( attribute "TOLERANCE" "1%"
					( Origin gFrontEnd )
				)
				( attribute "VALUE" "100.0K"
					( Origin gFrontEnd )
				)
				( attribute "VER" "2"
					( Origin gFrontEnd )
				)
				( attribute "WATTAGE" "1/16W"
					( Origin gFrontEnd )
				)
				( attribute "XY" "(-6600,1450)"
					( Origin gFrontEnd )
				)
				( attribute "CHIPS_PART_NAME" "RES"
					( Origin gPackager )
				)
				( attribute "CDS_PART_NAME" "RES_0402-100.0K,1%,1/16W,CHIP,A"
					( Origin gPackager )
				)
				( objectStatus "R1D37" )
				( pin "a"
					( attribute "PN" "1"
						( Origin gPackager )
					)
					( objectStatus "R1D37.1" )
				)
				( pin "b"
					( attribute "PN" "2"
						( Origin gPackager )
					)
					( objectStatus "R1D37.2" )
				)
			)
			( gate "@baseboard_fab2_lib.baseboard_fab2(sch_1):page199_i16"
				( attribute "CDS_LIB" "mstr_discrete"
					( Origin gPackager )
				)
				( attribute "CDS_LOCATION" "R1D39"
					( Origin gPackager )
				)
				( attribute "CDS_SEC" "1"
					( Origin gPackager )
				)
				( attribute "LOCATION" "R1D39"
					( Origin gFrontEnd )
				)
				( attribute "MATERIAL" "CHIP"
					( Origin gFrontEnd )
				)
				( attribute "NO_XNET_CONNECTION" "1"
					( Origin gFrontEnd )
				)
				( attribute "PACK_TYPE" "0402"
					( Origin gFrontEnd )
				)
				( attribute "PART_NUMBER" "G21796-010"
					( Origin gFrontEnd )
				)
				( attribute "PHYS_PAGE" "199"
					( Origin gFrontEnd )
				)
				( attribute "ROOM" "HOT_SWAP"
					( Origin gFrontEnd )
				)
				( attribute "ROT" "0"
					( Origin gFrontEnd )
				)
				( attribute "SEC" "1"
					( Origin gFrontEnd )
				)
				( attribute "SEC_TYPE" "0402"
					( Origin gFrontEnd )
				)
				( attribute "TOLERANCE" "1%"
					( Origin gFrontEnd )
				)
				( attribute "VALUE" "100.0K"
					( Origin gFrontEnd )
				)
				( attribute "VER" "2"
					( Origin gFrontEnd )
				)
				( attribute "WATTAGE" "1/16W"
					( Origin gFrontEnd )
				)
				( attribute "XY" "(-5300,1425)"
					( Origin gFrontEnd )
				)
				( attribute "CHIPS_PART_NAME" "RES"
					( Origin gPackager )
				)
				( attribute "CDS_PART_NAME" "RES_0402-100.0K,1%,1/16W,CHIP,A"
					( Origin gPackager )
				)
				( objectStatus "R1D39" )
				( pin "a"
					( attribute "PN" "1"
						( Origin gPackager )
					)
					( objectStatus "R1D39.1" )
				)
				( pin "b"
					( attribute "PN" "2"
						( Origin gPackager )
					)
					( objectStatus "R1D39.2" )
				)
			)
			( gate "@baseboard_fab2_lib.baseboard_fab2(sch_1):page199_i17"
				( attribute "CDS_LIB" "mstr_discrete"
					( Origin gPackager )
				)
				( attribute "CDS_LOCATION" "R1D32"
					( Origin gPackager )
				)
				( attribute "CDS_SEC" "1"
					( Origin gPackager )
				)
				( attribute "LOCATION" "R1D32"
					( Origin gFrontEnd )
				)
				( attribute "MATERIAL" "CHIP"
					( Origin gFrontEnd )
				)
				( attribute "NO_XNET_CONNECTION" "1"
					( Origin gFrontEnd )
				)
				( attribute "PACK_TYPE" "0402"
					( Origin gFrontEnd )
				)
				( attribute "PART_NUMBER" "G21796-010"
					( Origin gFrontEnd )
				)
				( attribute "PHYS_PAGE" "199"
					( Origin gFrontEnd )
				)
				( attribute "ROOM" "HOT_SWAP"
					( Origin gFrontEnd )
				)
				( attribute "ROT" "0"
					( Origin gFrontEnd )
				)
				( attribute "SEC" "1"
					( Origin gFrontEnd )
				)
				( attribute "SEC_TYPE" "0402"
					( Origin gFrontEnd )
				)
				( attribute "TOLERANCE" "1%"
					( Origin gFrontEnd )
				)
				( attribute "VALUE" "100.0K"
					( Origin gFrontEnd )
				)
				( attribute "VER" "2"
					( Origin gFrontEnd )
				)
				( attribute "WATTAGE" "1/16W"
					( Origin gFrontEnd )
				)
				( attribute "XY" "(-5600,1400)"
					( Origin gFrontEnd )
				)
				( attribute "CHIPS_PART_NAME" "RES"
					( Origin gPackager )
				)
				( attribute "CDS_PART_NAME" "RES_0402-100.0K,1%,1/16W,CHIP,A"
					( Origin gPackager )
				)
				( objectStatus "R1D32" )
				( pin "a"
					( attribute "PN" "1"
						( Origin gPackager )
					)
					( objectStatus "R1D32.1" )
				)
				( pin "b"
					( attribute "PN" "2"
						( Origin gPackager )
					)
					( objectStatus "R1D32.2" )
				)
			)
			( gate "@baseboard_fab2_lib.baseboard_fab2(sch_1):page199_i19"
				( attribute "CDS_LIB" "mstr_discrete"
					( Origin gPackager )
				)
				( attribute "CDS_LOCATION" "R1D41"
					( Origin gPackager )
				)
				( attribute "CDS_SEC" "1"
					( Origin gPackager )
				)
				( attribute "LOCATION" "R1D41"
					( Origin gFrontEnd )
				)
				( attribute "MATERIAL" "CHIP"
					( Origin gFrontEnd )
				)
				( attribute "PACK_TYPE" "0805"
					( Origin gFrontEnd )
				)
				( attribute "PART_NUMBER" "G22179-004"
					( Origin gFrontEnd )
				)
				( attribute "PHYS_PAGE" "199"
					( Origin gFrontEnd )
				)
				( attribute "ROOM" "HOT_SWAP"
					( Origin gFrontEnd )
				)
				( attribute "ROT" "0"
					( Origin gFrontEnd )
				)
				( attribute "SEC" "1"
					( Origin gFrontEnd )
				)
				( attribute "SEC_TYPE" "0805"
					( Origin gFrontEnd )
				)
				( attribute "TOLERANCE" "5%"
					( Origin gFrontEnd )
				)
				( attribute "VALUE" "0.0"
					( Origin gFrontEnd )
				)
				( attribute "VER" "1"
					( Origin gFrontEnd )
				)
				( attribute "WATTAGE" "1/8W"
					( Origin gFrontEnd )
				)
				( attribute "XY" "(-3025,300)"
					( Origin gFrontEnd )
				)
				( attribute "CHIPS_PART_NAME" "RES"
					( Origin gPackager )
				)
				( attribute "CDS_PART_NAME" "RES_0805-0.0,5%,1/8W,CHIP,G221A"
					( Origin gPackager )
				)
				( objectStatus "R1D41" )
				( pin "a"
					( attribute "PN" "1"
						( Origin gPackager )
					)
					( objectStatus "R1D41.1" )
				)
				( pin "b"
					( attribute "PN" "2"
						( Origin gPackager )
					)
					( objectStatus "R1D41.2" )
				)
			)
			( gate "@baseboard_fab2_lib.baseboard_fab2(sch_1):page199_i24"
				( attribute "CDS_LIB" "mstr_discrete"
					( Origin gPackager )
				)
				( attribute "CDS_LOCATION" "C9P14"
					( Origin gPackager )
				)
				( attribute "CDS_SEC" "1"
					( Origin gPackager )
				)
				( attribute "LOCATION" "C9P14"
					( Origin gFrontEnd )
				)
				( attribute "MATERIAL" "X7R"
					( Origin gFrontEnd )
				)
				( attribute "PACK_TYPE" "0603LF"
					( Origin gFrontEnd )
				)
				( attribute "PART_NUMBER" "603269-064"
					( Origin gFrontEnd )
				)
				( attribute "PHYS_PAGE" "199"
					( Origin gFrontEnd )
				)
				( attribute "ROOM" "HOT_SWAP"
					( Origin gFrontEnd )
				)
				( attribute "ROT" "0"
					( Origin gFrontEnd )
				)
				( attribute "SEC" "1"
					( Origin gFrontEnd )
				)
				( attribute "SEC_TYPE" "0603LF"
					( Origin gFrontEnd )
				)
				( attribute "TOLERANCE" "10%"
					( Origin gFrontEnd )
				)
				( attribute "VALUE" "0.033UF"
					( Origin gFrontEnd )
				)
				( attribute "VER" "1"
					( Origin gFrontEnd )
				)
				( attribute "VOLTAGE" "50V"
					( Units "uVoltage" "V" 1.000000)
					( Origin gFrontEnd )
				)
				( attribute "XY" "(-4850,1500)"
					( Origin gFrontEnd )
				)
				( attribute "CHIPS_PART_NAME" "CAP"
					( Origin gPackager )
				)
				( attribute "CDS_PART_NAME" "CAP_0603LF-0.033UF,50V,10%,X7RA"
					( Origin gPackager )
				)
				( objectStatus "C9P14" )
				( pin "a"
					( attribute "PN" "1"
						( Origin gPackager )
					)
					( objectStatus "C9P14.1" )
				)
				( pin "b"
					( attribute "PN" "2"
						( Origin gPackager )
					)
					( objectStatus "C9P14.2" )
				)
			)
			( gate "@baseboard_fab2_lib.baseboard_fab2(sch_1):page199_i26"
				( attribute "CDS_LIB" "mstr_discrete"
					( Origin gPackager )
				)
				( attribute "CDS_LOCATION" "R1D28"
					( Origin gPackager )
				)
				( attribute "CDS_SEC" "1"
					( Origin gPackager )
				)
				( attribute "LOCATION" "R1D28"
					( Origin gFrontEnd )
				)
				( attribute "MATERIAL" "EMPTY"
					( Origin gFrontEnd )
				)
				( attribute "PACK_TYPE" "0402"
					( Origin gFrontEnd )
				)
				( attribute "PART_NUMBER" "G21796-017"
					( Origin gFrontEnd )
				)
				( attribute "PHYS_PAGE" "199"
					( Origin gFrontEnd )
				)
				( attribute "ROOM" "HOT_SWAP"
					( Origin gFrontEnd )
				)
				( attribute "ROT" "0"
					( Origin gFrontEnd )
				)
				( attribute "SEC" "1"
					( Origin gFrontEnd )
				)
				( attribute "SEC_TYPE" "0402"
					( Origin gFrontEnd )
				)
				( attribute "TOLERANCE" "1%"
					( Origin gFrontEnd )
				)
				( attribute "VALUE" "100.0"
					( Origin gFrontEnd )
				)
				( attribute "VER" "2"
					( Origin gFrontEnd )
				)
				( attribute "WATTAGE" "1/16W"
					( Origin gFrontEnd )
				)
				( attribute "XY" "(-4625,1025)"
					( Origin gFrontEnd )
				)
				( attribute "CHIPS_PART_NAME" "RES"
					( Origin gPackager )
				)
				( attribute "CDS_PART_NAME" "RES_0402-100.0,1%,1/16W,EMPTY,A"
					( Origin gPackager )
				)
				( objectStatus "R1D28" )
				( pin "a"
					( attribute "PN" "1"
						( Origin gPackager )
					)
					( objectStatus "R1D28.1" )
				)
				( pin "b"
					( attribute "PN" "2"
						( Origin gPackager )
					)
					( objectStatus "R1D28.2" )
				)
			)
			( gate "@baseboard_fab2_lib.baseboard_fab2(sch_1):page199_i27"
				( attribute "CDS_LIB" "mstr_discrete"
					( Origin gPackager )
				)
				( attribute "CDS_LOCATION" "R1D24"
					( Origin gPackager )
				)
				( attribute "CDS_SEC" "1"
					( Origin gPackager )
				)
				( attribute "LOCATION" "R1D24"
					( Origin gFrontEnd )
				)
				( attribute "MATERIAL" "CHIP"
					( Origin gFrontEnd )
				)
				( attribute "PACK_TYPE" "0402"
					( Origin gFrontEnd )
				)
				( attribute "PART_NUMBER" "G21497-005"
					( Origin gFrontEnd )
				)
				( attribute "PHYS_PAGE" "199"
					( Origin gFrontEnd )
				)
				( attribute "ROOM" "HOT_SWAP"
					( Origin gFrontEnd )
				)
				( attribute "ROT" "0"
					( Origin gFrontEnd )
				)
				( attribute "SEC" "1"
					( Origin gFrontEnd )
				)
				( attribute "SEC_TYPE" "0402"
					( Origin gFrontEnd )
				)
				( attribute "TOLERANCE" "5%"
					( Origin gFrontEnd )
				)
				( attribute "VALUE" "0.0"
					( Origin gFrontEnd )
				)
				( attribute "VER" "1"
					( Origin gFrontEnd )
				)
				( attribute "WATTAGE" "1/16W"
					( Origin gFrontEnd )
				)
				( attribute "XY" "(-5600,2725)"
					( Origin gFrontEnd )
				)
				( attribute "CHIPS_PART_NAME" "RES"
					( Origin gPackager )
				)
				( attribute "CDS_PART_NAME" "RES_0402-0.0,5%,1/16W,CHIP,G21A"
					( Origin gPackager )
				)
				( objectStatus "R1D24" )
				( pin "a"
					( attribute "PN" "1"
						( Origin gPackager )
					)
					( objectStatus "R1D24.1" )
				)
				( pin "b"
					( attribute "PN" "2"
						( Origin gPackager )
					)
					( objectStatus "R1D24.2" )
				)
			)
			( gate "@baseboard_fab2_lib.baseboard_fab2(sch_1):page199_i28"
				( attribute "CDS_LIB" "mstr_discrete"
					( Origin gPackager )
				)
				( attribute "CDS_LOCATION" "R1D25"
					( Origin gPackager )
				)
				( attribute "CDS_SEC" "1"
					( Origin gPackager )
				)
				( attribute "LOCATION" "R1D25"
					( Origin gFrontEnd )
				)
				( attribute "MATERIAL" "CHIP"
					( Origin gFrontEnd )
				)
				( attribute "PACK_TYPE" "0402"
					( Origin gFrontEnd )
				)
				( attribute "PART_NUMBER" "G21497-005"
					( Origin gFrontEnd )
				)
				( attribute "PHYS_PAGE" "199"
					( Origin gFrontEnd )
				)
				( attribute "ROOM" "HOT_SWAP"
					( Origin gFrontEnd )
				)
				( attribute "ROT" "0"
					( Origin gFrontEnd )
				)
				( attribute "SEC" "1"
					( Origin gFrontEnd )
				)
				( attribute "SEC_TYPE" "0402"
					( Origin gFrontEnd )
				)
				( attribute "TOLERANCE" "5%"
					( Origin gFrontEnd )
				)
				( attribute "VALUE" "0.0"
					( Origin gFrontEnd )
				)
				( attribute "VER" "1"
					( Origin gFrontEnd )
				)
				( attribute "WATTAGE" "1/16W"
					( Origin gFrontEnd )
				)
				( attribute "XY" "(-5600,2675)"
					( Origin gFrontEnd )
				)
				( attribute "CHIPS_PART_NAME" "RES"
					( Origin gPackager )
				)
				( attribute "CDS_PART_NAME" "RES_0402-0.0,5%,1/16W,CHIP,G21A"
					( Origin gPackager )
				)
				( objectStatus "R1D25" )
				( pin "a"
					( attribute "PN" "1"
						( Origin gPackager )
					)
					( objectStatus "R1D25.1" )
				)
				( pin "b"
					( attribute "PN" "2"
						( Origin gPackager )
					)
					( objectStatus "R1D25.2" )
				)
			)
			( gate "@baseboard_fab2_lib.baseboard_fab2(sch_1):page199_i33"
				( attribute "CDS_LIB" "mstr_discrete"
					( Origin gPackager )
				)
				( attribute "CDS_LOCATION" "R9P17"
					( Origin gPackager )
				)
				( attribute "CDS_SEC" "1"
					( Origin gPackager )
				)
				( attribute "LOCATION" "R9P17"
					( Origin gFrontEnd )
				)
				( attribute "MATERIAL" "CHIP"
					( Origin gFrontEnd )
				)
				( attribute "PACK_TYPE" "0402"
					( Origin gFrontEnd )
				)
				( attribute "PART_NUMBER" "G21796-109"
					( Origin gFrontEnd )
				)
				( attribute "PHYS_PAGE" "199"
					( Origin gFrontEnd )
				)
				( attribute "ROOM" "HOT_SWAP"
					( Origin gFrontEnd )
				)
				( attribute "ROT" "0"
					( Origin gFrontEnd )
				)
				( attribute "SEC" "1"
					( Origin gFrontEnd )
				)
				( attribute "SEC_TYPE" "0402"
					( Origin gFrontEnd )
				)
				( attribute "TOLERANCE" "1%"
					( Origin gFrontEnd )
				)
				( attribute "VALUE" "150.0K"
					( Origin gFrontEnd )
				)
				( attribute "VER" "2"
					( Origin gFrontEnd )
				)
				( attribute "WATTAGE" "1/16W"
					( Origin gFrontEnd )
				)
				( attribute "XY" "(-8000,2375)"
					( Origin gFrontEnd )
				)
				( attribute "CHIPS_PART_NAME" "RES"
					( Origin gPackager )
				)
				( attribute "CDS_PART_NAME" "RES_0402-150.0K,1%,1/16W,CHIP,A"
					( Origin gPackager )
				)
				( objectStatus "R9P17" )
				( pin "a"
					( attribute "PN" "1"
						( Origin gPackager )
					)
					( objectStatus "R9P17.1" )
				)
				( pin "b"
					( attribute "PN" "2"
						( Origin gPackager )
					)
					( objectStatus "R9P17.2" )
				)
			)
			( gate "@baseboard_fab2_lib.baseboard_fab2(sch_1):page199_i36"
				( attribute "CDS_LIB" "mstr_discrete"
					( Origin gPackager )
				)
				( attribute "CDS_LOCATION" "R9P16"
					( Origin gPackager )
				)
				( attribute "CDS_SEC" "1"
					( Origin gPackager )
				)
				( attribute "LOCATION" "R9P16"
					( Origin gFrontEnd )
				)
				( attribute "MATERIAL" "CHIP"
					( Origin gFrontEnd )
				)
				( attribute "PACK_TYPE" "0402"
					( Origin gFrontEnd )
				)
				( attribute "PART_NUMBER" "G21497-005"
					( Origin gFrontEnd )
				)
				( attribute "PHYS_PAGE" "199"
					( Origin gFrontEnd )
				)
				( attribute "ROOM" "HOT_SWAP"
					( Origin gFrontEnd )
				)
				( attribute "ROT" "0"
					( Origin gFrontEnd )
				)
				( attribute "SEC" "1"
					( Origin gFrontEnd )
				)
				( attribute "SEC_TYPE" "0402"
					( Origin gFrontEnd )
				)
				( attribute "TOLERANCE" "5%"
					( Origin gFrontEnd )
				)
				( attribute "VALUE" "0.0"
					( Origin gFrontEnd )
				)
				( attribute "VER" "2"
					( Origin gFrontEnd )
				)
				( attribute "WATTAGE" "1/16W"
					( Origin gFrontEnd )
				)
				( attribute "XY" "(-7675,2375)"
					( Origin gFrontEnd )
				)
				( attribute "CHIPS_PART_NAME" "RES"
					( Origin gPackager )
				)
				( attribute "CDS_PART_NAME" "RES_0402-0.0,5%,1/16W,CHIP,G21A"
					( Origin gPackager )
				)
				( objectStatus "R9P16" )
				( pin "a"
					( attribute "PN" "1"
						( Origin gPackager )
					)
					( objectStatus "R9P16.1" )
				)
				( pin "b"
					( attribute "PN" "2"
						( Origin gPackager )
					)
					( objectStatus "R9P16.2" )
				)
			)
			( gate "@baseboard_fab2_lib.baseboard_fab2(sch_1):page199_i37"
				( attribute "CDS_LIB" "mstr_discrete"
					( Origin gPackager )
				)
				( attribute "CDS_LOCATION" "R1D29"
					( Origin gPackager )
				)
				( attribute "CDS_SEC" "1"
					( Origin gPackager )
				)
				( attribute "LOCATION" "R1D29"
					( Origin gFrontEnd )
				)
				( attribute "MATERIAL" "EMPTY"
					( Origin gFrontEnd )
				)
				( attribute "NO_XNET_CONNECTION" "1"
					( Origin gFrontEnd )
				)
				( attribute "PACK_TYPE" "0402"
					( Origin gFrontEnd )
				)
				( attribute "PART_NUMBER" "G21796-072"
					( Origin gFrontEnd )
				)
				( attribute "PHYS_PAGE" "199"
					( Origin gFrontEnd )
				)
				( attribute "ROOM" "HOT_SWAP"
					( Origin gFrontEnd )
				)
				( attribute "ROT" "0"
					( Origin gFrontEnd )
				)
				( attribute "SEC" "1"
					( Origin gFrontEnd )
				)
				( attribute "SEC_TYPE" "0402"
					( Origin gFrontEnd )
				)
				( attribute "TOLERANCE" "1%"
					( Origin gFrontEnd )
				)
				( attribute "VALUE" "4.75K"
					( Origin gFrontEnd )
				)
				( attribute "VER" "2"
					( Origin gFrontEnd )
				)
				( attribute "WATTAGE" "1/16W"
					( Origin gFrontEnd )
				)
				( attribute "XY" "(-8000,2825)"
					( Origin gFrontEnd )
				)
				( attribute "CHIPS_PART_NAME" "RES"
					( Origin gPackager )
				)
				( attribute "CDS_PART_NAME" "RES_0402-4.75K,1%,1/16W,EMPTY,A"
					( Origin gPackager )
				)
				( objectStatus "R1D29" )
				( pin "a"
					( attribute "PN" "1"
						( Origin gPackager )
					)
					( objectStatus "R1D29.1" )
				)
				( pin "b"
					( attribute "PN" "2"
						( Origin gPackager )
					)
					( objectStatus "R1D29.2" )
				)
			)
			( gate "@baseboard_fab2_lib.baseboard_fab2(sch_1):page199_i38"
				( attribute "CDS_LIB" "mstr_discrete"
					( Origin gPackager )
				)
				( attribute "CDS_LOCATION" "R1D27"
					( Origin gPackager )
				)
				( attribute "CDS_SEC" "1"
					( Origin gPackager )
				)
				( attribute "LOCATION" "R1D27"
					( Origin gFrontEnd )
				)
				( attribute "MATERIAL" "EMPTY"
					( Origin gFrontEnd )
				)
				( attribute "NO_XNET_CONNECTION" "1"
					( Origin gFrontEnd )
				)
				( attribute "PACK_TYPE" "0402"
					( Origin gFrontEnd )
				)
				( attribute "PART_NUMBER" "G21796-072"
					( Origin gFrontEnd )
				)
				( attribute "PHYS_PAGE" "199"
					( Origin gFrontEnd )
				)
				( attribute "ROOM" "HOT_SWAP"
					( Origin gFrontEnd )
				)
				( attribute "ROT" "0"
					( Origin gFrontEnd )
				)
				( attribute "SEC" "1"
					( Origin gFrontEnd )
				)
				( attribute "SEC_TYPE" "0402"
					( Origin gFrontEnd )
				)
				( attribute "TOLERANCE" "1%"
					( Origin gFrontEnd )
				)
				( attribute "VALUE" "4.75K"
					( Origin gFrontEnd )
				)
				( attribute "VER" "2"
					( Origin gFrontEnd )
				)
				( attribute "WATTAGE" "1/16W"
					( Origin gFrontEnd )
				)
				( attribute "XY" "(-7675,2850)"
					( Origin gFrontEnd )
				)
				( attribute "CHIPS_PART_NAME" "RES"
					( Origin gPackager )
				)
				( attribute "CDS_PART_NAME" "RES_0402-4.75K,1%,1/16W,EMPTY,A"
					( Origin gPackager )
				)
				( objectStatus "R1D27" )
				( pin "a"
					( attribute "PN" "1"
						( Origin gPackager )
					)
					( objectStatus "R1D27.1" )
				)
				( pin "b"
					( attribute "PN" "2"
						( Origin gPackager )
					)
					( objectStatus "R1D27.2" )
				)
			)
			( gate "@baseboard_fab2_lib.baseboard_fab2(sch_1):page199_i41"
				( attribute "BOM_COST" "MIO_USB"
					( Origin gFrontEnd )
				)
				( attribute "CDS_LIB" "mstr_discrete"
					( Origin gPackager )
				)
				( attribute "CDS_LOCATION" "R9P18"
					( Origin gPackager )
				)
				( attribute "CDS_SEC" "1"
					( Origin gPackager )
				)
				( attribute "LOCATION" "R9P18"
					( Origin gFrontEnd )
				)
				( attribute "MATERIAL" "CHIP"
					( Origin gFrontEnd )
				)
				( attribute "PACK_TYPE" "0402"
					( Origin gFrontEnd )
				)
				( attribute "PART_NUMBER" "G21796-107"
					( Origin gFrontEnd )
				)
				( attribute "PHYS_PAGE" "199"
					( Origin gFrontEnd )
				)
				( attribute "ROOM" "HOT_SWAP"
					( Origin gFrontEnd )
				)
				( attribute "ROT" "2"
					( Origin gFrontEnd )
				)
				( attribute "SEC" "1"
					( Origin gFrontEnd )
				)
				( attribute "SEC_TYPE" "0402"
					( Origin gFrontEnd )
				)
				( attribute "TOLERANCE" "1%"
					( Origin gFrontEnd )
				)
				( attribute "VALUE" "15.0K"
					( Origin gFrontEnd )
				)
				( attribute "VER" "2"
					( Origin gFrontEnd )
				)
				( attribute "WATTAGE" "1/16W"
					( Origin gFrontEnd )
				)
				( attribute "XY" "(-3125,1075)"
					( Origin gFrontEnd )
				)
				( attribute "CHIPS_PART_NAME" "RES"
					( Origin gPackager )
				)
				( attribute "CDS_PART_NAME" "RES_0402-15.0K,1%,1/16W,CHIP,GA"
					( Origin gPackager )
				)
				( objectStatus "R9P18" )
				( pin "a"
					( attribute "PN" "1"
						( Origin gPackager )
					)
					( objectStatus "R9P18.1" )
				)
				( pin "b"
					( attribute "PN" "2"
						( Origin gPackager )
					)
					( objectStatus "R9P18.2" )
				)
			)
			( gate "@baseboard_fab2_lib.baseboard_fab2(sch_1):page199_i43"
				( attribute "CDS_LIB" "mstr_discrete"
					( Origin gPackager )
				)
				( attribute "CDS_LOCATION" "R1D31"
					( Origin gPackager )
				)
				( attribute "CDS_SEC" "1"
					( Origin gPackager )
				)
				( attribute "LOCATION" "R1D31"
					( Origin gFrontEnd )
				)
				( attribute "MATERIAL" "CHIP"
					( Origin gFrontEnd )
				)
				( attribute "PACK_TYPE" "0402"
					( Origin gFrontEnd )
				)
				( attribute "PART_NUMBER" "G21796-161"
					( Origin gFrontEnd )
				)
				( attribute "PHYS_PAGE" "199"
					( Origin gFrontEnd )
				)
				( attribute "ROOM" "HOT_SWAP"
					( Origin gFrontEnd )
				)
				( attribute "ROT" "2"
					( Origin gFrontEnd )
				)
				( attribute "SEC" "1"
					( Origin gFrontEnd )
				)
				( attribute "SEC_TYPE" "0402"
					( Origin gFrontEnd )
				)
				( attribute "TOLERANCE" "1%"
					( Origin gFrontEnd )
				)
				( attribute "VALUE" "6.19K"
					( Origin gFrontEnd )
				)
				( attribute "VER" "2"
					( Origin gFrontEnd )
				)
				( attribute "WATTAGE" "1/16W"
					( Origin gFrontEnd )
				)
				( attribute "XY" "(-2825,750)"
					( Origin gFrontEnd )
				)
				( attribute "CHIPS_PART_NAME" "RES"
					( Origin gPackager )
				)
				( attribute "CDS_PART_NAME" "RES_0402-6.19K,1%,1/16W,CHIP,GA"
					( Origin gPackager )
				)
				( objectStatus "R1D31" )
				( pin "a"
					( attribute "PN" "1"
						( Origin gPackager )
					)
					( objectStatus "R1D31.1" )
				)
				( pin "b"
					( attribute "PN" "2"
						( Origin gPackager )
					)
					( objectStatus "R1D31.2" )
				)
			)
			( gate "@baseboard_fab2_lib.baseboard_fab2(sch_1):page199_i53"
				( attribute "CDS_LIB" "dev_discrete"
					( Origin gPackager )
				)
				( attribute "CDS_LOCATION" "C1D11"
					( Origin gPackager )
				)
				( attribute "CDS_SEC" "1"
					( Origin gPackager )
				)
				( attribute "LOCATION" "C1D11"
					( Origin gFrontEnd )
				)
				( attribute "MATERIAL" "X7R"
					( Origin gFrontEnd )
				)
				( attribute "PACK_TYPE" "0402V"
					( Origin gFrontEnd )
				)
				( attribute "PART_NUMBER" "A36096-030"
					( Origin gFrontEnd )
				)
				( attribute "PHYS_PAGE" "199"
					( Origin gFrontEnd )
				)
				( attribute "ROOM" "HOT_SWAP"
					( Origin gFrontEnd )
				)
				( attribute "ROT" "2"
					( Origin gFrontEnd )
				)
				( attribute "SEC" "1"
					( Origin gFrontEnd )
				)
				( attribute "SEC_TYPE" "0402V"
					( Origin gFrontEnd )
				)
				( attribute "TOLERANCE" "10%"
					( Origin gFrontEnd )
				)
				( attribute "VALUE" "0.1UF"
					( Origin gFrontEnd )
				)
				( attribute "VER" "1"
					( Origin gFrontEnd )
				)
				( attribute "VOLTAGE" "16V"
					( Units "uVoltage" "V" 1.000000)
					( Origin gFrontEnd )
				)
				( attribute "XY" "(-7025,2175)"
					( Origin gFrontEnd )
				)
				( attribute "CHIPS_PART_NAME" "CAP_A"
					( Origin gPackager )
				)
				( attribute "CDS_PART_NAME" "CAP_A_0402V-0.1UF,16V,10%,X7R,A"
					( Origin gPackager )
				)
				( objectStatus "C1D11" )
				( pin "a"
					( attribute "PN" "1"
						( Origin gPackager )
					)
					( objectStatus "C1D11.1" )
				)
				( pin "b"
					( attribute "PN" "2"
						( Origin gPackager )
					)
					( objectStatus "C1D11.2" )
				)
			)
			( gate "@baseboard_fab2_lib.baseboard_fab2(sch_1):page199_i54"
				( attribute "CDS_LIB" "mstr_discrete"
					( Origin gPackager )
				)
				( attribute "CDS_LOCATION" "R9P23"
					( Origin gPackager )
				)
				( attribute "CDS_SEC" "1"
					( Origin gPackager )
				)
				( attribute "LOCATION" "R9P23"
					( Origin gFrontEnd )
				)
				( attribute "MATERIAL" "CHIP"
					( Origin gFrontEnd )
				)
				( attribute "PACK_TYPE" "0402"
					( Origin gFrontEnd )
				)
				( attribute "PART_NUMBER" "G21796-010"
					( Origin gFrontEnd )
				)
				( attribute "PHYS_PAGE" "199"
					( Origin gFrontEnd )
				)
				( attribute "ROOM" "HOT_SWAP"
					( Origin gFrontEnd )
				)
				( attribute "ROT" "0"
					( Origin gFrontEnd )
				)
				( attribute "SEC" "1"
					( Origin gFrontEnd )
				)
				( attribute "SEC_TYPE" "0402"
					( Origin gFrontEnd )
				)
				( attribute "TOLERANCE" "1%"
					( Origin gFrontEnd )
				)
				( attribute "VALUE" "100.0K"
					( Origin gFrontEnd )
				)
				( attribute "VER" "2"
					( Origin gFrontEnd )
				)
				( attribute "WATTAGE" "1/16W"
					( Origin gFrontEnd )
				)
				( attribute "XY" "(-6725,2025)"
					( Origin gFrontEnd )
				)
				( attribute "CHIPS_PART_NAME" "RES"
					( Origin gPackager )
				)
				( attribute "CDS_PART_NAME" "RES_0402-100.0K,1%,1/16W,CHIP,A"
					( Origin gPackager )
				)
				( objectStatus "R9P23" )
				( pin "a"
					( attribute "PN" "1"
						( Origin gPackager )
					)
					( objectStatus "R9P23.1" )
				)
				( pin "b"
					( attribute "PN" "2"
						( Origin gPackager )
					)
					( objectStatus "R9P23.2" )
				)
			)
			( gate "@baseboard_fab2_lib.baseboard_fab2(sch_1):page199_i55"
				( attribute "BOM_COST" "MIO_USB"
					( Origin gFrontEnd )
				)
				( attribute "CDS_LIB" "mstr_discrete"
					( Origin gPackager )
				)
				( attribute "CDS_LOCATION" "R9P24"
					( Origin gPackager )
				)
				( attribute "CDS_SEC" "1"
					( Origin gPackager )
				)
				( attribute "LOCATION" "R9P24"
					( Origin gFrontEnd )
				)
				( attribute "MATERIAL" "CHIP"
					( Origin gFrontEnd )
				)
				( attribute "PACK_TYPE" "0402"
					( Origin gFrontEnd )
				)
				( attribute "PART_NUMBER" "G21796-089"
					( Origin gFrontEnd )
				)
				( attribute "PHYS_PAGE" "199"
					( Origin gFrontEnd )
				)
				( attribute "ROOM" "HOT_SWAP"
					( Origin gFrontEnd )
				)
				( attribute "ROT" "2"
					( Origin gFrontEnd )
				)
				( attribute "SEC" "1"
					( Origin gFrontEnd )
				)
				( attribute "SEC_TYPE" "0402"
					( Origin gFrontEnd )
				)
				( attribute "TOLERANCE" "1%"
					( Origin gFrontEnd )
				)
				( attribute "VALUE" "12.1K"
					( Origin gFrontEnd )
				)
				( attribute "VER" "2"
					( Origin gFrontEnd )
				)
				( attribute "WATTAGE" "1/16W"
					( Origin gFrontEnd )
				)
				( attribute "XY" "(-6725,1725)"
					( Origin gFrontEnd )
				)
				( attribute "CHIPS_PART_NAME" "RES"
					( Origin gPackager )
				)
				( attribute "CDS_PART_NAME" "RES_0402-12.1K,1%,1/16W,CHIP,GA"
					( Origin gPackager )
				)
				( objectStatus "R9P24" )
				( pin "a"
					( attribute "PN" "1"
						( Origin gPackager )
					)
					( objectStatus "R9P24.1" )
				)
				( pin "b"
					( attribute "PN" "2"
						( Origin gPackager )
					)
					( objectStatus "R9P24.2" )
				)
			)
			( gate "@baseboard_fab2_lib.baseboard_fab2(sch_1):page199_i58"
				( attribute "CDS_LIB" "mstr_discrete"
					( Origin gPackager )
				)
				( attribute "CDS_LOCATION" "Q1D3"
					( Origin gPackager )
				)
				( attribute "CDS_SEC" "1"
					( Origin gPackager )
				)
				( attribute "LOCATION" "Q1D3"
					( Origin gFrontEnd )
				)
				( attribute "MATERIAL" "IC"
					( Origin gFrontEnd )
				)
				( attribute "PACK_TYPE" "SM"
					( Origin gFrontEnd )
				)
				( attribute "PART_NUMBER" "C52245-001"
					( Origin gFrontEnd )
				)
				( attribute "PHYS_PAGE" "199"
					( Origin gFrontEnd )
				)
				( attribute "ROOM" "HOT_SWAP"
					( Origin gFrontEnd )
				)
				( attribute "ROT" "0"
					( Origin gFrontEnd )
				)
				( attribute "SEC" "1"
					( Origin gFrontEnd )
				)
				( attribute "SEC_TYPE" "SM"
					( Origin gFrontEnd )
				)
				( attribute "VALUE" "MMBT3904"
					( Origin gFrontEnd )
				)
				( attribute "VER" "1"
					( Origin gFrontEnd )
				)
				( attribute "XY" "(-1650,1650)"
					( Origin gFrontEnd )
				)
				( attribute "CHIPS_PART_NAME" "NPN"
					( Origin gPackager )
				)
				( attribute "CDS_PART_NAME" "NPN_SM-MMBT3904,IC,C52245-001"
					( Origin gPackager )
				)
				( objectStatus "Q1D3" )
				( pin "b"
					( attribute "PN" "1"
						( Origin gPackager )
					)
					( objectStatus "Q1D3.1" )
				)
				( pin "c"
					( attribute "PN" "3"
						( Origin gPackager )
					)
					( objectStatus "Q1D3.3" )
				)
				( pin "e"
					( attribute "PN" "2"
						( Origin gPackager )
					)
					( objectStatus "Q1D3.2" )
				)
			)
			( gate "@baseboard_fab2_lib.baseboard_fab2(sch_1):page199_i65"
				( attribute "BOM_COST" "MIO_USB"
					( Origin gFrontEnd )
				)
				( attribute "CDS_LIB" "mstr_discrete"
					( Origin gPackager )
				)
				( attribute "CDS_LOCATION" "R1D36"
					( Origin gPackager )
				)
				( attribute "CDS_SEC" "1"
					( Origin gPackager )
				)
				( attribute "LOCATION" "R1D36"
					( Origin gFrontEnd )
				)
				( attribute "MATERIAL" "CHIP"
					( Origin gFrontEnd )
				)
				( attribute "PACK_TYPE" "0402"
					( Origin gFrontEnd )
				)
				( attribute "PART_NUMBER" "G21796-026"
					( Origin gFrontEnd )
				)
				( attribute "PHYS_PAGE" "199"
					( Origin gFrontEnd )
				)
				( attribute "ROOM" "HOT_SWAP"
					( Origin gFrontEnd )
				)
				( attribute "ROT" "0"
					( Origin gFrontEnd )
				)
				( attribute "SEC" "1"
					( Origin gFrontEnd )
				)
				( attribute "SEC_TYPE" "0402"
					( Origin gFrontEnd )
				)
				( attribute "TOLERANCE" "1%"
					( Origin gFrontEnd )
				)
				( attribute "VALUE" "1.00K"
					( Origin gFrontEnd )
				)
				( attribute "VER" "2"
					( Origin gFrontEnd )
				)
				( attribute "WATTAGE" "1/16W"
					( Origin gFrontEnd )
				)
				( attribute "XY" "(-400,3025)"
					( Origin gFrontEnd )
				)
				( attribute "CHIPS_PART_NAME" "RES"
					( Origin gPackager )
				)
				( attribute "CDS_PART_NAME" "RES_0402-1.00K,1%,1/16W,CHIP,GA"
					( Origin gPackager )
				)
				( objectStatus "R1D36" )
				( pin "a"
					( attribute "PN" "1"
						( Origin gPackager )
					)
					( objectStatus "R1D36.1" )
				)
				( pin "b"
					( attribute "PN" "2"
						( Origin gPackager )
					)
					( objectStatus "R1D36.2" )
				)
			)
			( gate "@baseboard_fab2_lib.baseboard_fab2(sch_1):page199_i67"
				( attribute "CDS_LIB" "dev_discrete"
					( Origin gPackager )
				)
				( attribute "CDS_LOCATION" "C9P12"
					( Origin gPackager )
				)
				( attribute "CDS_SEC" "1"
					( Origin gPackager )
				)
				( attribute "LOCATION" "C9P12"
					( Origin gFrontEnd )
				)
				( attribute "MATERIAL" "EMPTY"
					( Origin gFrontEnd )
				)
				( attribute "PACK_TYPE" "0402V"
					( Origin gFrontEnd )
				)
				( attribute "PART_NUMBER" "A36096-030"
					( Origin gFrontEnd )
				)
				( attribute "PHYS_PAGE" "199"
					( Origin gFrontEnd )
				)
				( attribute "ROOM" "HOT_SWAP"
					( Origin gFrontEnd )
				)
				( attribute "ROT" "0"
					( Origin gFrontEnd )
				)
				( attribute "SEC" "1"
					( Origin gFrontEnd )
				)
				( attribute "SEC_TYPE" "0402V"
					( Origin gFrontEnd )
				)
				( attribute "TOLERANCE" "10%"
					( Origin gFrontEnd )
				)
				( attribute "VALUE" "0.1UF"
					( Origin gFrontEnd )
				)
				( attribute "VER" "1"
					( Origin gFrontEnd )
				)
				( attribute "VOLTAGE" "16V"
					( Units "uVoltage" "V" 1.000000)
					( Origin gFrontEnd )
				)
				( attribute "XY" "(-400,2625)"
					( Origin gFrontEnd )
				)
				( attribute "CHIPS_PART_NAME" "CAP_A"
					( Origin gPackager )
				)
				( attribute "CDS_PART_NAME" "CAP_A_0402V-0.1UF,16V,10%,EMPTA"
					( Origin gPackager )
				)
				( objectStatus "C9P12" )
				( pin "a"
					( attribute "PN" "1"
						( Origin gPackager )
					)
					( objectStatus "C9P12.1" )
				)
				( pin "b"
					( attribute "PN" "2"
						( Origin gPackager )
					)
					( objectStatus "C9P12.2" )
				)
			)
			( gate "@baseboard_fab2_lib.baseboard_fab2(sch_1):page199_i82"
				( attribute "CDS_LIB" "mstr_discrete"
					( Origin gPackager )
				)
				( attribute "CDS_LOCATION" "Q1D1"
					( Origin gPackager )
				)
				( attribute "CDS_SEC" "2"
					( Origin gPackager )
				)
				( attribute "LOCATION" "Q1D1"
					( Origin gFrontEnd )
				)
				( attribute "MATERIAL" "FET"
					( Origin gFrontEnd )
				)
				( attribute "PACK_TYPE" "SMLF"
					( Origin gFrontEnd )
				)
				( attribute "PART_NUMBER" "D24280-001"
					( Origin gFrontEnd )
				)
				( attribute "PHYS_PAGE" "199"
					( Origin gFrontEnd )
				)
				( attribute "ROOM" "HOT_SWAP"
					( Origin gFrontEnd )
				)
				( attribute "ROT" "0"
					( Origin gFrontEnd )
				)
				( attribute "SEC" "2"
					( Origin gFrontEnd )
				)
				( attribute "SEC_TYPE" "SMLF"
					( Origin gFrontEnd )
				)
				( attribute "VALUE" "2N7002DW"
					( Origin gFrontEnd )
				)
				( attribute "VER" "5"
					( Origin gFrontEnd )
				)
				( attribute "XY" "(-6600,400)"
					( Origin gFrontEnd )
				)
				( attribute "CHIPS_PART_NAME" "FET_N_DUAL"
					( Origin gPackager )
				)
				( attribute "CDS_PART_NAME" "FET_N_DUAL_SMLF-2N7002DW,FET,DA"
					( Origin gPackager )
				)
				( objectStatus "Q1D1" )
				( pin "drain(0)"
					( attribute "PN" "3"
						( Origin gPackager )
					)
					( objectStatus "Q1D1.3" )
				)
				( pin "gate(0)"
					( attribute "PN" "5"
						( Origin gPackager )
					)
					( objectStatus "Q1D1.5" )
				)
				( pin "source(0)"
					( attribute "PN" "4"
						( Origin gPackager )
					)
					( objectStatus "Q1D1.4" )
				)
			)
			( gate "@baseboard_fab2_lib.baseboard_fab2(sch_1):page199_i84"
				( attribute "CDS_LIB" "mstr_discrete"
					( Origin gPackager )
				)
				( attribute "CDS_LOCATION" "R1D13"
					( Origin gPackager )
				)
				( attribute "CDS_SEC" "1"
					( Origin gPackager )
				)
				( attribute "LOCATION" "R1D13"
					( Origin gFrontEnd )
				)
				( attribute "MATERIAL" "CHIP"
					( Origin gFrontEnd )
				)
				( attribute "NO_XNET_CONNECTION" "1"
					( Origin gFrontEnd )
				)
				( attribute "PACK_TYPE" "0402"
					( Origin gFrontEnd )
				)
				( attribute "PART_NUMBER" "G21796-058"
					( Origin gFrontEnd )
				)
				( attribute "PHYS_PAGE" "199"
					( Origin gFrontEnd )
				)
				( attribute "ROOM" "HOT_SWAP"
					( Origin gFrontEnd )
				)
				( attribute "ROT" "1"
					( Origin gFrontEnd )
				)
				( attribute "SEC" "1"
					( Origin gFrontEnd )
				)
				( attribute "SEC_TYPE" "0402"
					( Origin gFrontEnd )
				)
				( attribute "TOLERANCE" "1%"
					( Origin gFrontEnd )
				)
				( attribute "VALUE" "90.9K"
					( Origin gFrontEnd )
				)
				( attribute "VER" "1"
					( Origin gFrontEnd )
				)
				( attribute "WATTAGE" "1/16W"
					( Origin gFrontEnd )
				)
				( attribute "XY" "(-6600,925)"
					( Origin gFrontEnd )
				)
				( attribute "CHIPS_PART_NAME" "RES"
					( Origin gPackager )
				)
				( attribute "CDS_PART_NAME" "RES_0402-90.9K,1%,1/16W,CHIP,GA"
					( Origin gPackager )
				)
				( objectStatus "R1D13" )
				( pin "a"
					( attribute "PN" "1"
						( Origin gPackager )
					)
					( objectStatus "R1D13.1" )
				)
				( pin "b"
					( attribute "PN" "2"
						( Origin gPackager )
					)
					( objectStatus "R1D13.2" )
				)
			)
			( gate "@baseboard_fab2_lib.baseboard_fab2(sch_1):page199_i85"
				( attribute "CDS_LIB" "mstr_discrete"
					( Origin gPackager )
				)
				( attribute "CDS_LOCATION" "R1D16"
					( Origin gPackager )
				)
				( attribute "CDS_SEC" "1"
					( Origin gPackager )
				)
				( attribute "LOCATION" "R1D16"
					( Origin gFrontEnd )
				)
				( attribute "MATERIAL" "CHIP"
					( Origin gFrontEnd )
				)
				( attribute "NO_XNET_CONNECTION" "1"
					( Origin gFrontEnd )
				)
				( attribute "PACK_TYPE" "0402"
					( Origin gFrontEnd )
				)
				( attribute "PART_NUMBER" "G21796-007"
					( Origin gFrontEnd )
				)
				( attribute "PHYS_PAGE" "199"
					( Origin gFrontEnd )
				)
				( attribute "ROOM" "HOT_SWAP"
					( Origin gFrontEnd )
				)
				( attribute "ROT" "0"
					( Origin gFrontEnd )
				)
				( attribute "SEC" "1"
					( Origin gFrontEnd )
				)
				( attribute "SEC_TYPE" "0402"
					( Origin gFrontEnd )
				)
				( attribute "TOLERANCE" "1%"
					( Origin gFrontEnd )
				)
				( attribute "VALUE" "69.8K"
					( Origin gFrontEnd )
				)
				( attribute "VER" "2"
					( Origin gFrontEnd )
				)
				( attribute "WATTAGE" "1/16W"
					( Origin gFrontEnd )
				)
				( attribute "XY" "(-5875,875)"
					( Origin gFrontEnd )
				)
				( attribute "CHIPS_PART_NAME" "RES"
					( Origin gPackager )
				)
				( attribute "CDS_PART_NAME" "RES_0402-69.8K,1%,1/16W,CHIP,GA"
					( Origin gPackager )
				)
				( objectStatus "R1D16" )
				( pin "a"
					( attribute "PN" "1"
						( Origin gPackager )
					)
					( objectStatus "R1D16.1" )
				)
				( pin "b"
					( attribute "PN" "2"
						( Origin gPackager )
					)
					( objectStatus "R1D16.2" )
				)
			)
			( gate "@baseboard_fab2_lib.baseboard_fab2(sch_1):page199_i86"
				( attribute "CDS_LIB" "mstr_discrete"
					( Origin gPackager )
				)
				( attribute "CDS_LOCATION" "Q1D1"
					( Origin gPackager )
				)
				( attribute "CDS_SEC" "1"
					( Origin gPackager )
				)
				( attribute "LOCATION" "Q1D1"
					( Origin gFrontEnd )
				)
				( attribute "MATERIAL" "FET"
					( Origin gFrontEnd )
				)
				( attribute "PACK_TYPE" "SMLF"
					( Origin gFrontEnd )
				)
				( attribute "PART_NUMBER" "D24280-001"
					( Origin gFrontEnd )
				)
				( attribute "PHYS_PAGE" "199"
					( Origin gFrontEnd )
				)
				( attribute "ROOM" "HOT_SWAP"
					( Origin gFrontEnd )
				)
				( attribute "ROT" "0"
					( Origin gFrontEnd )
				)
				( attribute "SEC" "1"
					( Origin gFrontEnd )
				)
				( attribute "SEC_TYPE" "SMLF"
					( Origin gFrontEnd )
				)
				( attribute "VALUE" "2N7002DW"
					( Origin gFrontEnd )
				)
				( attribute "VER" "5"
					( Origin gFrontEnd )
				)
				( attribute "XY" "(-5875,275)"
					( Origin gFrontEnd )
				)
				( attribute "CHIPS_PART_NAME" "FET_N_DUAL"
					( Origin gPackager )
				)
				( attribute "CDS_PART_NAME" "FET_N_DUAL_SMLF-2N7002DW,FET,DA"
					( Origin gPackager )
				)
				( objectStatus "Q1D1" )
				( pin "drain(0)"
					( attribute "PN" "6"
						( Origin gPackager )
					)
					( objectStatus "Q1D1.6" )
				)
				( pin "gate(0)"
					( attribute "PN" "2"
						( Origin gPackager )
					)
					( objectStatus "Q1D1.2" )
				)
				( pin "source(0)"
					( attribute "PN" "1"
						( Origin gPackager )
					)
					( objectStatus "Q1D1.1" )
				)
			)
			( gate "@baseboard_fab2_lib.baseboard_fab2(sch_1):page199_i87"
				( attribute "CDS_LIB" "mstr_discrete"
					( Origin gPackager )
				)
				( attribute "CDS_LOCATION" "R1D18"
					( Origin gPackager )
				)
				( attribute "CDS_SEC" "1"
					( Origin gPackager )
				)
				( attribute "LOCATION" "R1D18"
					( Origin gFrontEnd )
				)
				( attribute "MATERIAL" "CHIP"
					( Origin gFrontEnd )
				)
				( attribute "PACK_TYPE" "0402"
					( Origin gFrontEnd )
				)
				( attribute "PART_NUMBER" "G21796-010"
					( Origin gFrontEnd )
				)
				( attribute "PHYS_PAGE" "199"
					( Origin gFrontEnd )
				)
				( attribute "ROOM" "HOT_SWAP"
					( Origin gFrontEnd )
				)
				( attribute "ROT" "0"
					( Origin gFrontEnd )
				)
				( attribute "SEC" "1"
					( Origin gFrontEnd )
				)
				( attribute "SEC_TYPE" "0402"
					( Origin gFrontEnd )
				)
				( attribute "TOLERANCE" "1%"
					( Origin gFrontEnd )
				)
				( attribute "VALUE" "100.0K"
					( Origin gFrontEnd )
				)
				( attribute "VER" "2"
					( Origin gFrontEnd )
				)
				( attribute "WATTAGE" "1/16W"
					( Origin gFrontEnd )
				)
				( attribute "XY" "(-6950,-50)"
					( Origin gFrontEnd )
				)
				( attribute "CHIPS_PART_NAME" "RES"
					( Origin gPackager )
				)
				( attribute "CDS_PART_NAME" "RES_0402-100.0K,1%,1/16W,CHIP,A"
					( Origin gPackager )
				)
				( objectStatus "R1D18" )
				( pin "a"
					( attribute "PN" "1"
						( Origin gPackager )
					)
					( objectStatus "R1D18.1" )
				)
				( pin "b"
					( attribute "PN" "2"
						( Origin gPackager )
					)
					( objectStatus "R1D18.2" )
				)
			)
			( gate "@baseboard_fab2_lib.baseboard_fab2(sch_1):page199_i88"
				( attribute "CDS_LIB" "mstr_discrete"
					( Origin gPackager )
				)
				( attribute "CDS_LOCATION" "R1D11"
					( Origin gPackager )
				)
				( attribute "CDS_SEC" "1"
					( Origin gPackager )
				)
				( attribute "LOCATION" "R1D11"
					( Origin gFrontEnd )
				)
				( attribute "MATERIAL" "CHIP"
					( Origin gFrontEnd )
				)
				( attribute "PACK_TYPE" "0402"
					( Origin gFrontEnd )
				)
				( attribute "PART_NUMBER" "G21796-010"
					( Origin gFrontEnd )
				)
				( attribute "PHYS_PAGE" "199"
					( Origin gFrontEnd )
				)
				( attribute "ROOM" "HOT_SWAP"
					( Origin gFrontEnd )
				)
				( attribute "ROT" "0"
					( Origin gFrontEnd )
				)
				( attribute "SEC" "1"
					( Origin gFrontEnd )
				)
				( attribute "SEC_TYPE" "0402"
					( Origin gFrontEnd )
				)
				( attribute "TOLERANCE" "1%"
					( Origin gFrontEnd )
				)
				( attribute "VALUE" "100.0K"
					( Origin gFrontEnd )
				)
				( attribute "VER" "2"
					( Origin gFrontEnd )
				)
				( attribute "WATTAGE" "1/16W"
					( Origin gFrontEnd )
				)
				( attribute "XY" "(-6300,-50)"
					( Origin gFrontEnd )
				)
				( attribute "CHIPS_PART_NAME" "RES"
					( Origin gPackager )
				)
				( attribute "CDS_PART_NAME" "RES_0402-100.0K,1%,1/16W,CHIP,A"
					( Origin gPackager )
				)
				( objectStatus "R1D11" )
				( pin "a"
					( attribute "PN" "1"
						( Origin gPackager )
					)
					( objectStatus "R1D11.1" )
				)
				( pin "b"
					( attribute "PN" "2"
						( Origin gPackager )
					)
					( objectStatus "R1D11.2" )
				)
			)
			( gate "@baseboard_fab2_lib.baseboard_fab2(sch_1):page199_i92"
				( attribute "CDS_LIB" "mstr_discrete"
					( Origin gPackager )
				)
				( attribute "CDS_LOCATION" "R1D15"
					( Origin gPackager )
				)
				( attribute "CDS_SEC" "1"
					( Origin gPackager )
				)
				( attribute "LOCATION" "R1D15"
					( Origin gFrontEnd )
				)
				( attribute "MATERIAL" "CHIP"
					( Origin gFrontEnd )
				)
				( attribute "PACK_TYPE" "0402"
					( Origin gFrontEnd )
				)
				( attribute "PART_NUMBER" "G21796-010"
					( Origin gFrontEnd )
				)
				( attribute "PHYS_PAGE" "199"
					( Origin gFrontEnd )
				)
				( attribute "ROOM" "HOT_SWAP"
					( Origin gFrontEnd )
				)
				( attribute "ROT" "0"
					( Origin gFrontEnd )
				)
				( attribute "SEC" "1"
					( Origin gFrontEnd )
				)
				( attribute "SEC_TYPE" "0402"
					( Origin gFrontEnd )
				)
				( attribute "TOLERANCE" "1%"
					( Origin gFrontEnd )
				)
				( attribute "VALUE" "100.0K"
					( Origin gFrontEnd )
				)
				( attribute "VER" "2"
					( Origin gFrontEnd )
				)
				( attribute "WATTAGE" "1/16W"
					( Origin gFrontEnd )
				)
				( attribute "XY" "(-7300,750)"
					( Origin gFrontEnd )
				)
				( attribute "CHIPS_PART_NAME" "RES"
					( Origin gPackager )
				)
				( attribute "CDS_PART_NAME" "RES_0402-100.0K,1%,1/16W,CHIP,A"
					( Origin gPackager )
				)
				( objectStatus "R1D15" )
				( pin "a"
					( attribute "PN" "1"
						( Origin gPackager )
					)
					( objectStatus "R1D15.1" )
				)
				( pin "b"
					( attribute "PN" "2"
						( Origin gPackager )
					)
					( objectStatus "R1D15.2" )
				)
			)
			( gate "@baseboard_fab2_lib.baseboard_fab2(sch_1):page199_i99"
				( attribute "CDS_LIB" "mstr_discrete"
					( Origin gPackager )
				)
				( attribute "CDS_LOCATION" "VR1D1"
					( Origin gPackager )
				)
				( attribute "CDS_SEC" "1"
					( Origin gPackager )
				)
				( attribute "LOCATION" "VR1D1"
					( Origin gFrontEnd )
				)
				( attribute "MATERIAL" "IC"
					( Origin gFrontEnd )
				)
				( attribute "PACK_TYPE" "SM"
					( Origin gFrontEnd )
				)
				( attribute "PART_NUMBER" "H69095-001"
					( Origin gFrontEnd )
				)
				( attribute "PHYS_PAGE" "199"
					( Origin gFrontEnd )
				)
				( attribute "ROT" "0"
					( Origin gFrontEnd )
				)
				( attribute "SEC" "1"
					( Origin gFrontEnd )
				)
				( attribute "SEC_TYPE" "SM"
					( Origin gFrontEnd )
				)
				( attribute "VALUE" "13V"
					( Origin gFrontEnd )
				)
				( attribute "VER" "4"
					( Origin gFrontEnd )
				)
				( attribute "XY" "(-5100,3875)"
					( Origin gFrontEnd )
				)
				( attribute "CHIPS_PART_NAME" "ZENER"
					( Origin gPackager )
				)
				( attribute "CDS_PART_NAME" "ZENER_SM-13V,IC,H69095-001"
					( Origin gPackager )
				)
				( objectStatus "VR1D1" )
				( pin "a"
					( attribute "PN" "2"
						( Origin gPackager )
					)
					( objectStatus "VR1D1.2" )
				)
				( pin "c"
					( attribute "PN" "1"
						( Origin gPackager )
					)
					( objectStatus "VR1D1.1" )
				)
			)
			( gate "@baseboard_fab2_lib.baseboard_fab2(sch_1):page199_i100"
				( attribute "CDS_LIB" "mstr_discrete"
					( Origin gPackager )
				)
				( attribute "CDS_LOCATION" "R1D40"
					( Origin gPackager )
				)
				( attribute "CDS_SEC" "1"
					( Origin gPackager )
				)
				( attribute "LOCATION" "R1D40"
					( Origin gFrontEnd )
				)
				( attribute "MATERIAL" "CHIP"
					( Origin gFrontEnd )
				)
				( attribute "PACK_TYPE" "0402"
					( Origin gFrontEnd )
				)
				( attribute "PART_NUMBER" "G21796-133"
					( Origin gFrontEnd )
				)
				( attribute "PHYS_PAGE" "199"
					( Origin gFrontEnd )
				)
				( attribute "ROOM" "HOT_SWAP"
					( Origin gFrontEnd )
				)
				( attribute "ROT" "0"
					( Origin gFrontEnd )
				)
				( attribute "SEC" "1"
					( Origin gFrontEnd )
				)
				( attribute "SEC_TYPE" "0402"
					( Origin gFrontEnd )
				)
				( attribute "TOLERANCE" "1%"
					( Origin gFrontEnd )
				)
				( attribute "VALUE" "40.2K"
					( Origin gFrontEnd )
				)
				( attribute "VER" "2"
					( Origin gFrontEnd )
				)
				( attribute "WATTAGE" "1/16W"
					( Origin gFrontEnd )
				)
				( attribute "XY" "(-5300,800)"
					( Origin gFrontEnd )
				)
				( attribute "CHIPS_PART_NAME" "RES"
					( Origin gPackager )
				)
				( attribute "CDS_PART_NAME" "RES_0402-40.2K,1%,1/16W,CHIP,GA"
					( Origin gPackager )
				)
				( objectStatus "R1D40" )
				( pin "a"
					( attribute "PN" "1"
						( Origin gPackager )
					)
					( objectStatus "R1D40.1" )
				)
				( pin "b"
					( attribute "PN" "2"
						( Origin gPackager )
					)
					( objectStatus "R1D40.2" )
				)
			)
			( gate "@baseboard_fab2_lib.baseboard_fab2(sch_1):page199_i102"
				( attribute "CDS_LIB" "mstr_discrete"
					( Origin gPackager )
				)
				( attribute "CDS_LOCATION" "R1D34"
					( Origin gPackager )
				)
				( attribute "CDS_SEC" "1"
					( Origin gPackager )
				)
				( attribute "LOCATION" "R1D34"
					( Origin gFrontEnd )
				)
				( attribute "MATERIAL" "CHIP"
					( Origin gFrontEnd )
				)
				( attribute "PACK_TYPE" "0402"
					( Origin gFrontEnd )
				)
				( attribute "PART_NUMBER" "G21796-317"
					( Origin gFrontEnd )
				)
				( attribute "PHYS_PAGE" "199"
					( Origin gFrontEnd )
				)
				( attribute "ROOM" "HOT_SWAP"
					( Origin gFrontEnd )
				)
				( attribute "ROT" "0"
					( Origin gFrontEnd )
				)
				( attribute "SEC" "1"
					( Origin gFrontEnd )
				)
				( attribute "SEC_TYPE" "0402"
					( Origin gFrontEnd )
				)
				( attribute "TOLERANCE" "1.0%"
					( Origin gFrontEnd )
				)
				( attribute "VALUE" "16K"
					( Origin gFrontEnd )
				)
				( attribute "VER" "2"
					( Origin gFrontEnd )
				)
				( attribute "WATTAGE" "1/16W"
					( Origin gFrontEnd )
				)
				( attribute "XY" "(-5600,750)"
					( Origin gFrontEnd )
				)
				( attribute "CHIPS_PART_NAME" "RES"
					( Origin gPackager )
				)
				( attribute "CDS_PART_NAME" "RES_0402-16K,1.0%,1/16W,CHIP,GA"
					( Origin gPackager )
				)
				( objectStatus "R1D34" )
				( pin "a"
					( attribute "PN" "1"
						( Origin gPackager )
					)
					( objectStatus "R1D34.1" )
				)
				( pin "b"
					( attribute "PN" "2"
						( Origin gPackager )
					)
					( objectStatus "R1D34.2" )
				)
			)
			( gate "@baseboard_fab2_lib.baseboard_fab2(sch_1):page199_i105"
				( attribute "CDS_LIB" "dev_discrete"
					( Origin gPackager )
				)
				( attribute "CDS_LOCATION" "C9P15"
					( Origin gPackager )
				)
				( attribute "CDS_SEC" "1"
					( Origin gPackager )
				)
				( attribute "LOCATION" "C9P15"
					( Origin gFrontEnd )
				)
				( attribute "MATERIAL" "X7R"
					( Origin gFrontEnd )
				)
				( attribute "PACK_TYPE" "0402V"
					( Origin gFrontEnd )
				)
				( attribute "PART_NUMBER" "A36096-030"
					( Origin gFrontEnd )
				)
				( attribute "PHYS_PAGE" "199"
					( Origin gFrontEnd )
				)
				( attribute "ROOM" "HOT_SWAP"
					( Origin gFrontEnd )
				)
				( attribute "ROT" "2"
					( Origin gFrontEnd )
				)
				( attribute "SEC" "1"
					( Origin gPackager )
				)
				( attribute "TOLERANCE" "10%"
					( Origin gFrontEnd )
				)
				( attribute "VALUE" "0.1UF"
					( Origin gFrontEnd )
				)
				( attribute "VER" "1"
					( Origin gFrontEnd )
				)
				( attribute "VOLTAGE" "16V"
					( Units "uVoltage" "V" 1.000000)
					( Origin gFrontEnd )
				)
				( attribute "XY" "(-6150,850)"
					( Origin gFrontEnd )
				)
				( attribute "CHIPS_PART_NAME" "CAP_A"
					( Origin gPackager )
				)
				( attribute "CDS_PART_NAME" "CAP_A_0402V-0.1UF,16V,10%,X7R,A"
					( Origin gPackager )
				)
				( objectStatus "C9P15" )
				( pin "a"
					( attribute "PN" "1"
						( Origin gPackager )
					)
					( objectStatus "C9P15.1" )
				)
				( pin "b"
					( attribute "PN" "2"
						( Origin gPackager )
					)
					( objectStatus "C9P15.2" )
				)
			)
			( gate "@baseboard_fab2_lib.baseboard_fab2(sch_1):page199_i107"
				( attribute "CDS_LIB" "dev_discrete"
					( Origin gPackager )
				)
				( attribute "CDS_LOCATION" "C1D26"
					( Origin gPackager )
				)
				( attribute "CDS_SEC" "1"
					( Origin gPackager )
				)
				( attribute "LOCATION" "C1D26"
					( Origin gFrontEnd )
				)
				( attribute "MATERIAL" "X7R"
					( Origin gFrontEnd )
				)
				( attribute "PACK_TYPE" "0402V"
					( Origin gFrontEnd )
				)
				( attribute "PART_NUMBER" "A36096-030"
					( Origin gFrontEnd )
				)
				( attribute "PHYS_PAGE" "199"
					( Origin gFrontEnd )
				)
				( attribute "ROOM" "HOT_SWAP"
					( Origin gFrontEnd )
				)
				( attribute "ROT" "2"
					( Origin gFrontEnd )
				)
				( attribute "SEC" "1"
					( Origin gFrontEnd )
				)
				( attribute "SEC_TYPE" "0402V"
					( Origin gFrontEnd )
				)
				( attribute "TOLERANCE" "10%"
					( Origin gFrontEnd )
				)
				( attribute "VALUE" "0.1UF"
					( Origin gFrontEnd )
				)
				( attribute "VER" "1"
					( Origin gFrontEnd )
				)
				( attribute "VOLTAGE" "16V"
					( Units "uVoltage" "V" 1.000000)
					( Origin gFrontEnd )
				)
				( attribute "XY" "(-6075,3575)"
					( Origin gFrontEnd )
				)
				( attribute "CHIPS_PART_NAME" "CAP_A"
					( Origin gPackager )
				)
				( attribute "CDS_PART_NAME" "CAP_A_0402V-0.1UF,16V,10%,X7R,A"
					( Origin gPackager )
				)
				( objectStatus "C1D26" )
				( pin "a"
					( attribute "PN" "1"
						( Origin gPackager )
					)
					( objectStatus "C1D26.1" )
				)
				( pin "b"
					( attribute "PN" "2"
						( Origin gPackager )
					)
					( objectStatus "C1D26.2" )
				)
			)
			( gate "@baseboard_fab2_lib.baseboard_fab2(sch_1):page199_i108"
				( attribute "CDS_LIB" "mstr_discrete"
					( Origin gPackager )
				)
				( attribute "CDS_LOCATION" "R1D33"
					( Origin gPackager )
				)
				( attribute "CDS_SEC" "1"
					( Origin gPackager )
				)
				( attribute "LOCATION" "R1D33"
					( Origin gFrontEnd )
				)
				( attribute "MATERIAL" "CHIP"
					( Origin gFrontEnd )
				)
				( attribute "PACK_TYPE" "0402"
					( Origin gFrontEnd )
				)
				( attribute "PART_NUMBER" "G21796-074"
					( Origin gFrontEnd )
				)
				( attribute "PHYS_PAGE" "199"
					( Origin gFrontEnd )
				)
				( attribute "ROT" "0"
					( Origin gFrontEnd )
				)
				( attribute "SEC" "1"
					( Origin gFrontEnd )
				)
				( attribute "SEC_TYPE" "0402"
					( Origin gFrontEnd )
				)
				( attribute "TOLERANCE" "1%"
					( Origin gFrontEnd )
				)
				( attribute "VALUE" "33.2"
					( Origin gFrontEnd )
				)
				( attribute "VER" "1"
					( Origin gFrontEnd )
				)
				( attribute "WATTAGE" "1/16W"
					( Origin gFrontEnd )
				)
				( attribute "XY" "(-2050,925)"
					( Origin gFrontEnd )
				)
				( attribute "CHIPS_PART_NAME" "RES"
					( Origin gPackager )
				)
				( attribute "CDS_PART_NAME" "RES_0402-33.2,1%,1/16W,CHIP,G2A"
					( Origin gPackager )
				)
				( objectStatus "R1D33" )
				( pin "a"
					( attribute "PN" "1"
						( Origin gPackager )
					)
					( objectStatus "R1D33.1" )
				)
				( pin "b"
					( attribute "PN" "2"
						( Origin gPackager )
					)
					( objectStatus "R1D33.2" )
				)
			)
			( gate "@baseboard_fab2_lib.baseboard_fab2(sch_1):page199_i109"
				( attribute "CDS_LIB" "mstr_discrete"
					( Origin gPackager )
				)
				( attribute "CDS_LOCATION" "R1D26"
					( Origin gPackager )
				)
				( attribute "CDS_SEC" "1"
					( Origin gPackager )
				)
				( attribute "LOCATION" "R1D26"
					( Origin gFrontEnd )
				)
				( attribute "MATERIAL" "CHIP"
					( Origin gFrontEnd )
				)
				( attribute "PACK_TYPE" "0402"
					( Origin gFrontEnd )
				)
				( attribute "PART_NUMBER" "G21796-074"
					( Origin gFrontEnd )
				)
				( attribute "PHYS_PAGE" "199"
					( Origin gFrontEnd )
				)
				( attribute "ROT" "0"
					( Origin gFrontEnd )
				)
				( attribute "SEC" "1"
					( Origin gFrontEnd )
				)
				( attribute "SEC_TYPE" "0402"
					( Origin gFrontEnd )
				)
				( attribute "TOLERANCE" "1%"
					( Origin gFrontEnd )
				)
				( attribute "VALUE" "33.2"
					( Origin gFrontEnd )
				)
				( attribute "VER" "1"
					( Origin gFrontEnd )
				)
				( attribute "WATTAGE" "1/16W"
					( Origin gFrontEnd )
				)
				( attribute "XY" "(-1700,3950)"
					( Origin gFrontEnd )
				)
				( attribute "CHIPS_PART_NAME" "RES"
					( Origin gPackager )
				)
				( attribute "CDS_PART_NAME" "RES_0402-33.2,1%,1/16W,CHIP,G2A"
					( Origin gPackager )
				)
				( objectStatus "R1D26" )
				( pin "a"
					( attribute "PN" "1"
						( Origin gPackager )
					)
					( objectStatus "R1D26.1" )
				)
				( pin "b"
					( attribute "PN" "2"
						( Origin gPackager )
					)
					( objectStatus "R1D26.2" )
				)
			)
			( gate "@baseboard_fab2_lib.baseboard_fab2(sch_1):page199_i110"
				( attribute "CDS_LIB" "mstr_discrete"
					( Origin gPackager )
				)
				( attribute "CDS_LOCATION" "R1D30"
					( Origin gPackager )
				)
				( attribute "CDS_SEC" "1"
					( Origin gPackager )
				)
				( attribute "LOCATION" "R1D30"
					( Origin gFrontEnd )
				)
				( attribute "MATERIAL" "CHIP"
					( Origin gFrontEnd )
				)
				( attribute "PACK_TYPE" "0402"
					( Origin gFrontEnd )
				)
				( attribute "PART_NUMBER" "G21796-074"
					( Origin gFrontEnd )
				)
				( attribute "PHYS_PAGE" "199"
					( Origin gFrontEnd )
				)
				( attribute "ROT" "0"
					( Origin gFrontEnd )
				)
				( attribute "SEC" "1"
					( Origin gFrontEnd )
				)
				( attribute "SEC_TYPE" "0402"
					( Origin gFrontEnd )
				)
				( attribute "TOLERANCE" "1%"
					( Origin gFrontEnd )
				)
				( attribute "VALUE" "33.2"
					( Origin gFrontEnd )
				)
				( attribute "VER" "1"
					( Origin gFrontEnd )
				)
				( attribute "WATTAGE" "1/16W"
					( Origin gFrontEnd )
				)
				( attribute "XY" "(-2050,1375)"
					( Origin gFrontEnd )
				)
				( attribute "CHIPS_PART_NAME" "RES"
					( Origin gPackager )
				)
				( attribute "CDS_PART_NAME" "RES_0402-33.2,1%,1/16W,CHIP,G2A"
					( Origin gPackager )
				)
				( objectStatus "R1D30" )
				( pin "a"
					( attribute "PN" "1"
						( Origin gPackager )
					)
					( objectStatus "R1D30.1" )
				)
				( pin "b"
					( attribute "PN" "2"
						( Origin gPackager )
					)
					( objectStatus "R1D30.2" )
				)
			)
			( gate "@baseboard_fab2_lib.baseboard_fab2(sch_1):page199_i119"
				( attribute "CDS_LIB" "mstr_discrete"
					( Origin gPackager )
				)
				( attribute "CDS_LOCATION" "C1D19"
					( Origin gPackager )
				)
				( attribute "CDS_SEC" "1"
					( Origin gPackager )
				)
				( attribute "LOCATION" "C1D19"
					( Origin gFrontEnd )
				)
				( attribute "MATERIAL" "X6S"
					( Origin gFrontEnd )
				)
				( attribute "PACK_TYPE" "0402"
					( Origin gFrontEnd )
				)
				( attribute "PART_NUMBER" "D97712-011"
					( Origin gFrontEnd )
				)
				( attribute "PHYS_PAGE" "199"
					( Origin gFrontEnd )
				)
				( attribute "ROOM" "HOT_SWAP"
					( Origin gFrontEnd )
				)
				( attribute "ROT" "0"
					( Origin gFrontEnd )
				)
				( attribute "SEC" "1"
					( Origin gFrontEnd )
				)
				( attribute "SEC_TYPE" "0402"
					( Origin gFrontEnd )
				)
				( attribute "TOLERANCE" "10%"
					( Origin gFrontEnd )
				)
				( attribute "VALUE" "1.0UF"
					( Origin gFrontEnd )
				)
				( attribute "VER" "1"
					( Origin gFrontEnd )
				)
				( attribute "VOLTAGE" "16V"
					( Units "uVoltage" "V" 1.000000)
					( Origin gFrontEnd )
				)
				( attribute "XY" "(-5650,2000)"
					( Origin gFrontEnd )
				)
				( attribute "CHIPS_PART_NAME" "CAP"
					( Origin gPackager )
				)
				( attribute "CDS_PART_NAME" "CAP_0402-1.0UF,16V,10%,X6S,D97A"
					( Origin gPackager )
				)
				( objectStatus "C1D19" )
				( pin "a"
					( attribute "PN" "1"
						( Origin gPackager )
					)
					( objectStatus "C1D19.1" )
				)
				( pin "b"
					( attribute "PN" "2"
						( Origin gPackager )
					)
					( objectStatus "C1D19.2" )
				)
			)
			( gate "@baseboard_fab2_lib.baseboard_fab2(sch_1):page199_i121"
				( attribute "CDS_LIB" "dev_discrete"
					( Origin gPackager )
				)
				( attribute "CDS_LOCATION" "C1D21"
					( Origin gPackager )
				)
				( attribute "CDS_SEC" "1"
					( Origin gPackager )
				)
				( attribute "LOCATION" "C1D21"
					( Origin gFrontEnd )
				)
				( attribute "MATERIAL" "X7R"
					( Origin gFrontEnd )
				)
				( attribute "PACK_TYPE" "0402V"
					( Origin gFrontEnd )
				)
				( attribute "PART_NUMBER" "A36096-030"
					( Origin gFrontEnd )
				)
				( attribute "PHYS_PAGE" "199"
					( Origin gFrontEnd )
				)
				( attribute "ROOM" "HOT_SWAP"
					( Origin gFrontEnd )
				)
				( attribute "ROT" "2"
					( Origin gFrontEnd )
				)
				( attribute "SEC" "1"
					( Origin gFrontEnd )
				)
				( attribute "SEC_TYPE" "0402V"
					( Origin gFrontEnd )
				)
				( attribute "TOLERANCE" "10%"
					( Origin gFrontEnd )
				)
				( attribute "VALUE" "0.1UF"
					( Origin gFrontEnd )
				)
				( attribute "VER" "1"
					( Origin gFrontEnd )
				)
				( attribute "VOLTAGE" "16V"
					( Units "uVoltage" "V" 1.000000)
					( Origin gFrontEnd )
				)
				( attribute "XY" "(-5000,425)"
					( Origin gFrontEnd )
				)
				( attribute "CHIPS_PART_NAME" "CAP_A"
					( Origin gPackager )
				)
				( attribute "CDS_PART_NAME" "CAP_A_0402V-0.1UF,16V,10%,X7R,A"
					( Origin gPackager )
				)
				( objectStatus "C1D21" )
				( pin "a"
					( attribute "PN" "1"
						( Origin gPackager )
					)
					( objectStatus "C1D21.1" )
				)
				( pin "b"
					( attribute "PN" "2"
						( Origin gPackager )
					)
					( objectStatus "C1D21.2" )
				)
			)
			( gate "@baseboard_fab2_lib.baseboard_fab2(sch_1):page199_i123"
				( attribute "BOM_COST" "SM_CONTROLLER"
					( Origin gFrontEnd )
				)
				( attribute "CDS_LIB" "mstr_conn"
					( Origin gPackager )
				)
				( attribute "CDS_LOCATION" "J1B3"
					( Origin gPackager )
				)
				( attribute "CDS_SEC" "1"
					( Origin gPackager )
				)
				( attribute "LOCATION" "J1B3"
					( Origin gFrontEnd )
				)
				( attribute "MATERIAL" "CONN"
					( Origin gFrontEnd )
				)
				( attribute "PACK_TYPE" "PIP"
					( Origin gFrontEnd )
				)
				( attribute "PART_NUMBER" "C95678-002"
					( Origin gFrontEnd )
				)
				( attribute "PHYS_PAGE" "199"
					( Origin gFrontEnd )
				)
				( attribute "ROOM" "SMBUS"
					( Origin gFrontEnd )
				)
				( attribute "ROT" "0"
					( Origin gFrontEnd )
				)
				( attribute "SEC" "1"
					( Origin gFrontEnd )
				)
				( attribute "SEC_TYPE" "PIP"
					( Origin gFrontEnd )
				)
				( attribute "VER" "1"
					( Origin gFrontEnd )
				)
				( attribute "XY" "(-7750,250)"
					( Origin gFrontEnd )
				)
				( attribute "CHIPS_PART_NAME" "CONN3_C95678002"
					( Origin gPackager )
				)
				( attribute "CDS_PART_NAME" "CONN3_C95678002_PIP-CONN,C9567A"
					( Origin gPackager )
				)
				( objectStatus "J1B3" )
				( pin "io1"
					( attribute "PN" "1"
						( Origin gPackager )
					)
					( objectStatus "J1B3.1" )
				)
				( pin "io2"
					( attribute "PN" "2"
						( Origin gPackager )
					)
					( objectStatus "J1B3.2" )
				)
				( pin "io3"
					( attribute "PN" "3"
						( Origin gPackager )
					)
					( objectStatus "J1B3.3" )
				)
			)
			( gate "@baseboard_fab2_lib.baseboard_fab2(sch_1):page199_i124"
				( attribute "CDS_LIB" "mstr_sconn"
					( Origin gPackager )
				)
				( attribute "CDS_LOCATION" "J1B4"
					( Origin gPackager )
				)
				( attribute "CDS_SEC" "1"
					( Origin gPackager )
				)
				( attribute "LOCATION" "J1B4"
					( Origin gFrontEnd )
				)
				( attribute "MATERIAL" "EMPTY"
					( Origin gFrontEnd )
				)
				( attribute "PACK_TYPE" "SM"
					( Origin gFrontEnd )
				)
				( attribute "PART_NUMBER" "D53458-001"
					( Origin gFrontEnd )
				)
				( attribute "PHYS_PAGE" "199"
					( Origin gFrontEnd )
				)
				( attribute "ROT" "0"
					( Origin gFrontEnd )
				)
				( attribute "SEC" "1"
					( Origin gFrontEnd )
				)
				( attribute "SEC_TYPE" "SM"
					( Origin gFrontEnd )
				)
				( attribute "VER" "2"
					( Origin gFrontEnd )
				)
				( attribute "XY" "(-7750,675)"
					( Origin gFrontEnd )
				)
				( attribute "CHIPS_PART_NAME" "SCONN3_D53458001"
					( Origin gPackager )
				)
				( attribute "CDS_PART_NAME" "SCONN3_D53458001_SM-EMPTY,D534A"
					( Origin gPackager )
				)
				( objectStatus "J1B4" )
				( pin "io1"
					( attribute "PN" "1"
						( Origin gPackager )
					)
					( objectStatus "J1B4.1" )
				)
				( pin "io2"
					( attribute "PN" "2"
						( Origin gPackager )
					)
					( objectStatus "J1B4.2" )
				)
				( pin "io3"
					( attribute "PN" "3"
						( Origin gPackager )
					)
					( objectStatus "J1B4.3" )
				)
			)
			( gate "@baseboard_fab2_lib.baseboard_fab2(sch_1):page200_i36"
				( attribute "CDS_LIB" "dev_discrete"
					( Origin gPackager )
				)
				( attribute "CDS_LOCATION" "C9P17"
					( Origin gPackager )
				)
				( attribute "CDS_SEC" "1"
					( Origin gPackager )
				)
				( attribute "LOCATION" "C9P17"
					( Origin gFrontEnd )
				)
				( attribute "MATERIAL" "EMPTY"
					( Origin gFrontEnd )
				)
				( attribute "PACK_TYPE" "0402V"
					( Origin gFrontEnd )
				)
				( attribute "PART_NUMBER" "A36096-030"
					( Origin gFrontEnd )
				)
				( attribute "PHYS_PAGE" "200"
					( Origin gFrontEnd )
				)
				( attribute "ROOM" "HOT_SWAP"
					( Origin gFrontEnd )
				)
				( attribute "ROT" "0"
					( Origin gFrontEnd )
				)
				( attribute "SEC" "1"
					( Origin gFrontEnd )
				)
				( attribute "SEC_TYPE" "0402V"
					( Origin gFrontEnd )
				)
				( attribute "TOLERANCE" "10%"
					( Origin gFrontEnd )
				)
				( attribute "VALUE" "0.1UF"
					( Origin gFrontEnd )
				)
				( attribute "VER" "1"
					( Origin gFrontEnd )
				)
				( attribute "VOLTAGE" "16V"
					( Units "uVoltage" "V" 1.000000)
					( Origin gFrontEnd )
				)
				( attribute "XY" "(-1025,3425)"
					( Origin gFrontEnd )
				)
				( attribute "CHIPS_PART_NAME" "CAP_A"
					( Origin gPackager )
				)
				( attribute "CDS_PART_NAME" "CAP_A_0402V-0.1UF,16V,10%,EMPTA"
					( Origin gPackager )
				)
				( objectStatus "C9P17" )
				( pin "a"
					( attribute "PN" "1"
						( Origin gPackager )
					)
					( objectStatus "C9P17.1" )
				)
				( pin "b"
					( attribute "PN" "2"
						( Origin gPackager )
					)
					( objectStatus "C9P17.2" )
				)
			)
			( gate "@baseboard_fab2_lib.baseboard_fab2(sch_1):page200_i40"
				( attribute "CDS_LIB" "dev_discrete"
					( Origin gPackager )
				)
				( attribute "CDS_LOCATION" "C9P16"
					( Origin gPackager )
				)
				( attribute "CDS_SEC" "1"
					( Origin gPackager )
				)
				( attribute "LOCATION" "C9P16"
					( Origin gFrontEnd )
				)
				( attribute "MATERIAL" "EMPTY"
					( Origin gFrontEnd )
				)
				( attribute "PACK_TYPE" "0402V"
					( Origin gFrontEnd )
				)
				( attribute "PART_NUMBER" "A36096-030"
					( Origin gFrontEnd )
				)
				( attribute "PHYS_PAGE" "200"
					( Origin gFrontEnd )
				)
				( attribute "ROOM" "HOT_SWAP"
					( Origin gFrontEnd )
				)
				( attribute "ROT" "0"
					( Origin gFrontEnd )
				)
				( attribute "SEC" "1"
					( Origin gPackager )
				)
				( attribute "TOLERANCE" "10%"
					( Origin gFrontEnd )
				)
				( attribute "VALUE" "0.1UF"
					( Origin gFrontEnd )
				)
				( attribute "VER" "1"
					( Origin gFrontEnd )
				)
				( attribute "VOLTAGE" "16V"
					( Units "uVoltage" "V" 1.000000)
					( Origin gFrontEnd )
				)
				( attribute "XY" "(-675,3000)"
					( Origin gFrontEnd )
				)
				( attribute "CHIPS_PART_NAME" "CAP_A"
					( Origin gPackager )
				)
				( attribute "CDS_PART_NAME" "CAP_A_0402V-0.1UF,16V,10%,EMPTA"
					( Origin gPackager )
				)
				( objectStatus "C9P16" )
				( pin "a"
					( attribute "PN" "1"
						( Origin gPackager )
					)
					( objectStatus "C9P16.1" )
				)
				( pin "b"
					( attribute "PN" "2"
						( Origin gPackager )
					)
					( objectStatus "C9P16.2" )
				)
			)
			( gate "@baseboard_fab2_lib.baseboard_fab2(sch_1):page200_i42"
				( attribute "CDS_LIB" "dev_discrete"
					( Origin gPackager )
				)
				( attribute "CDS_LOCATION" "C1D22"
					( Origin gPackager )
				)
				( attribute "CDS_SEC" "1"
					( Origin gPackager )
				)
				( attribute "LOCATION" "C1D22"
					( Origin gFrontEnd )
				)
				( attribute "MATERIAL" "EMPTY"
					( Origin gFrontEnd )
				)
				( attribute "PACK_TYPE" "0402V"
					( Origin gFrontEnd )
				)
				( attribute "PART_NUMBER" "A36096-030"
					( Origin gFrontEnd )
				)
				( attribute "PHYS_PAGE" "200"
					( Origin gFrontEnd )
				)
				( attribute "ROOM" "HOT_SWAP"
					( Origin gFrontEnd )
				)
				( attribute "ROT" "0"
					( Origin gFrontEnd )
				)
				( attribute "SEC" "1"
					( Origin gPackager )
				)
				( attribute "TOLERANCE" "10%"
					( Origin gFrontEnd )
				)
				( attribute "VALUE" "0.1UF"
					( Origin gFrontEnd )
				)
				( attribute "VER" "1"
					( Origin gFrontEnd )
				)
				( attribute "VOLTAGE" "16V"
					( Units "uVoltage" "V" 1.000000)
					( Origin gFrontEnd )
				)
				( attribute "XY" "(-175,3425)"
					( Origin gFrontEnd )
				)
				( attribute "CHIPS_PART_NAME" "CAP_A"
					( Origin gPackager )
				)
				( attribute "CDS_PART_NAME" "CAP_A_0402V-0.1UF,16V,10%,EMPTA"
					( Origin gPackager )
				)
				( objectStatus "C1D22" )
				( pin "a"
					( attribute "PN" "1"
						( Origin gPackager )
					)
					( objectStatus "C1D22.1" )
				)
				( pin "b"
					( attribute "PN" "2"
						( Origin gPackager )
					)
					( objectStatus "C1D22.2" )
				)
			)
			( gate "@baseboard_fab2_lib.baseboard_fab2(sch_1):page200_i43"
				( attribute "CDS_LIB" "mstr_discrete"
					( Origin gPackager )
				)
				( attribute "CDS_LOCATION" "R1D45"
					( Origin gPackager )
				)
				( attribute "CDS_SEC" "1"
					( Origin gPackager )
				)
				( attribute "LOCATION" "R1D45"
					( Origin gFrontEnd )
				)
				( attribute "MATERIAL" "CHIP"
					( Origin gFrontEnd )
				)
				( attribute "PACK_TYPE" "0402"
					( Origin gFrontEnd )
				)
				( attribute "PART_NUMBER" "G21497-005"
					( Origin gFrontEnd )
				)
				( attribute "PHYS_PAGE" "200"
					( Origin gFrontEnd )
				)
				( attribute "ROOM" "HOT_SWAP"
					( Origin gFrontEnd )
				)
				( attribute "ROT" "0"
					( Origin gFrontEnd )
				)
				( attribute "SEC" "1"
					( Origin gPackager )
				)
				( attribute "TOLERANCE" "5%"
					( Origin gFrontEnd )
				)
				( attribute "VALUE" "0.0"
					( Origin gFrontEnd )
				)
				( attribute "VER" "1"
					( Origin gFrontEnd )
				)
				( attribute "WATTAGE" "1/16W"
					( Origin gFrontEnd )
				)
				( attribute "XY" "(250,3625)"
					( Origin gFrontEnd )
				)
				( attribute "CHIPS_PART_NAME" "RES"
					( Origin gPackager )
				)
				( attribute "CDS_PART_NAME" "RES_0402-0.0,5%,1/16W,CHIP,G21A"
					( Origin gPackager )
				)
				( objectStatus "R1D45" )
				( pin "a"
					( attribute "PN" "1"
						( Origin gPackager )
					)
					( objectStatus "R1D45.1" )
				)
				( pin "b"
					( attribute "PN" "2"
						( Origin gPackager )
					)
					( objectStatus "R1D45.2" )
				)
			)
			( gate "@baseboard_fab2_lib.baseboard_fab2(sch_1):page200_i44"
				( attribute "CDS_LIB" "mstr_discrete"
					( Origin gPackager )
				)
				( attribute "CDS_LOCATION" "R1D44"
					( Origin gPackager )
				)
				( attribute "CDS_SEC" "1"
					( Origin gPackager )
				)
				( attribute "LOCATION" "R1D44"
					( Origin gFrontEnd )
				)
				( attribute "MATERIAL" "CHIP"
					( Origin gFrontEnd )
				)
				( attribute "PACK_TYPE" "0402"
					( Origin gFrontEnd )
				)
				( attribute "PART_NUMBER" "G21497-005"
					( Origin gFrontEnd )
				)
				( attribute "PHYS_PAGE" "200"
					( Origin gFrontEnd )
				)
				( attribute "ROOM" "HOT_SWAP"
					( Origin gFrontEnd )
				)
				( attribute "ROT" "0"
					( Origin gFrontEnd )
				)
				( attribute "SEC" "1"
					( Origin gPackager )
				)
				( attribute "TOLERANCE" "5%"
					( Origin gFrontEnd )
				)
				( attribute "VALUE" "0.0"
					( Origin gFrontEnd )
				)
				( attribute "VER" "1"
					( Origin gFrontEnd )
				)
				( attribute "WATTAGE" "1/16W"
					( Origin gFrontEnd )
				)
				( attribute "XY" "(225,3150)"
					( Origin gFrontEnd )
				)
				( attribute "CHIPS_PART_NAME" "RES"
					( Origin gPackager )
				)
				( attribute "CDS_PART_NAME" "RES_0402-0.0,5%,1/16W,CHIP,G21A"
					( Origin gPackager )
				)
				( objectStatus "R1D44" )
				( pin "a"
					( attribute "PN" "1"
						( Origin gPackager )
					)
					( objectStatus "R1D44.1" )
				)
				( pin "b"
					( attribute "PN" "2"
						( Origin gPackager )
					)
					( objectStatus "R1D44.2" )
				)
			)
			( gate "@baseboard_fab2_lib.baseboard_fab2(sch_1):page200_i47"
				( attribute "CDS_LIB" "mstr_discrete"
					( Origin gPackager )
				)
				( attribute "CDS_LOCATION" "R9P27"
					( Origin gPackager )
				)
				( attribute "CDS_SEC" "1"
					( Origin gPackager )
				)
				( attribute "LOCATION" "R9P27"
					( Origin gFrontEnd )
				)
				( attribute "MATERIAL" "CHIP"
					( Origin gFrontEnd )
				)
				( attribute "PACK_TYPE" "0402"
					( Origin gFrontEnd )
				)
				( attribute "PART_NUMBER" "G21796-066"
					( Origin gFrontEnd )
				)
				( attribute "PHYS_PAGE" "200"
					( Origin gFrontEnd )
				)
				( attribute "ROOM" "HOT_SWAP"
					( Origin gFrontEnd )
				)
				( attribute "ROT" "0"
					( Origin gFrontEnd )
				)
				( attribute "SEC" "1"
					( Origin gPackager )
				)
				( attribute "TOLERANCE" "1%"
					( Origin gFrontEnd )
				)
				( attribute "VALUE" "10.0"
					( Origin gFrontEnd )
				)
				( attribute "VER" "2"
					( Origin gFrontEnd )
				)
				( attribute "WATTAGE" "1/16W"
					( Origin gFrontEnd )
				)
				( attribute "XY" "(875,2800)"
					( Origin gFrontEnd )
				)
				( attribute "CHIPS_PART_NAME" "RES"
					( Origin gPackager )
				)
				( attribute "CDS_PART_NAME" "RES_0402-10.0,1%,1/16W,CHIP,G2A"
					( Origin gPackager )
				)
				( objectStatus "R9P27" )
				( pin "a"
					( attribute "PN" "1"
						( Origin gPackager )
					)
					( objectStatus "R9P27.1" )
				)
				( pin "b"
					( attribute "PN" "2"
						( Origin gPackager )
					)
					( objectStatus "R9P27.2" )
				)
			)
			( gate "@baseboard_fab2_lib.baseboard_fab2(sch_1):page200_i48"
				( attribute "CDS_LIB" "mstr_discrete"
					( Origin gPackager )
				)
				( attribute "CDS_LOCATION" "R1D46"
					( Origin gPackager )
				)
				( attribute "CDS_SEC" "1"
					( Origin gPackager )
				)
				( attribute "LOCATION" "R1D46"
					( Origin gFrontEnd )
				)
				( attribute "MATERIAL" "CHIP"
					( Origin gFrontEnd )
				)
				( attribute "PACK_TYPE" "0402"
					( Origin gFrontEnd )
				)
				( attribute "PART_NUMBER" "G21796-066"
					( Origin gFrontEnd )
				)
				( attribute "PHYS_PAGE" "200"
					( Origin gFrontEnd )
				)
				( attribute "ROOM" "HOT_SWAP"
					( Origin gFrontEnd )
				)
				( attribute "ROT" "2"
					( Origin gFrontEnd )
				)
				( attribute "SEC" "1"
					( Origin gPackager )
				)
				( attribute "TOLERANCE" "1%"
					( Origin gFrontEnd )
				)
				( attribute "VALUE" "10.0"
					( Origin gFrontEnd )
				)
				( attribute "VER" "2"
					( Origin gFrontEnd )
				)
				( attribute "WATTAGE" "1/16W"
					( Origin gFrontEnd )
				)
				( attribute "XY" "(750,2800)"
					( Origin gFrontEnd )
				)
				( attribute "CHIPS_PART_NAME" "RES"
					( Origin gPackager )
				)
				( attribute "CDS_PART_NAME" "RES_0402-10.0,1%,1/16W,CHIP,G2A"
					( Origin gPackager )
				)
				( objectStatus "R1D46" )
				( pin "a"
					( attribute "PN" "1"
						( Origin gPackager )
					)
					( objectStatus "R1D46.1" )
				)
				( pin "b"
					( attribute "PN" "2"
						( Origin gPackager )
					)
					( objectStatus "R1D46.2" )
				)
			)
			( gate "@baseboard_fab2_lib.baseboard_fab2(sch_1):page200_i49"
				( attribute "CDS_LIB" "mstr_discrete"
					( Origin gPackager )
				)
				( attribute "CDS_LMAN_SYM_OUTLINE" "-50,100,50,-100"
					( Origin gPackager )
				)
				( attribute "CDS_LOCATION" "R9R1"
					( Origin gPackager )
				)
				( attribute "CDS_SEC" "1"
					( Origin gPackager )
				)
				( attribute "LOCATION" "R9R1"
					( Origin gFrontEnd )
				)
				( attribute "MATERIAL" "CHIP"
					( Origin gFrontEnd )
				)
				( attribute "PACK_TYPE" "6PAD"
					( Origin gFrontEnd )
				)
				( attribute "PART_NUMBER" "E74391-005"
					( Origin gFrontEnd )
				)
				( attribute "PHYS_PAGE" "200"
					( Origin gFrontEnd )
				)
				( attribute "ROOM" "HOT_SWAP"
					( Origin gFrontEnd )
				)
				( attribute "ROT" "0"
					( Origin gFrontEnd )
				)
				( attribute "SEC" "1"
					( Origin gFrontEnd )
				)
				( attribute "SEC_TYPE" "6PAD"
					( Origin gFrontEnd )
				)
				( attribute "TOLERANCE" "1%"
					( Origin gFrontEnd )
				)
				( attribute "VALUE" "0.001"
					( Origin gFrontEnd )
				)
				( attribute "VER" "2"
					( Origin gFrontEnd )
				)
				( attribute "WATTAGE" "3W"
					( Origin gFrontEnd )
				)
				( attribute "XY" "(1125,3200)"
					( Origin gFrontEnd )
				)
				( attribute "CHIPS_PART_NAME" "RES_PWR"
					( Origin gPackager )
				)
				( attribute "CDS_PART_NAME" "RES_PWR_6PAD-0.001,1%,3W,CHIP,A"
					( Origin gPackager )
				)
				( objectStatus "R9R1" )
				( pin "\1\"
					( attribute "PN" "1"
						( Origin gPackager )
					)
					( objectStatus "R9R1.1" )
				)
				( pin "\2\"
					( attribute "PN" "2"
						( Origin gPackager )
					)
					( objectStatus "R9R1.2" )
				)
				( pin "\3\"
					( attribute "PN" "3"
						( Origin gPackager )
					)
					( objectStatus "R9R1.3" )
				)
				( pin "\4\"
					( attribute "PN" "4"
						( Origin gPackager )
					)
					( objectStatus "R9R1.4" )
				)
				( pin "\5\"
					( attribute "PN" "5"
						( Origin gPackager )
					)
					( objectStatus "R9R1.5" )
				)
				( pin "\6\"
					( attribute "PN" "6"
						( Origin gPackager )
					)
					( objectStatus "R9R1.6" )
				)
			)
			( gate "@baseboard_fab2_lib.baseboard_fab2(sch_1):page200_i50"
				( attribute "CDS_LIB" "mstr_discrete"
					( Origin gPackager )
				)
				( attribute "CDS_LMAN_SYM_OUTLINE" "-50,100,50,-100"
					( Origin gPackager )
				)
				( attribute "CDS_LOCATION" "R1D49"
					( Origin gPackager )
				)
				( attribute "CDS_SEC" "1"
					( Origin gPackager )
				)
				( attribute "LOCATION" "R1D49"
					( Origin gFrontEnd )
				)
				( attribute "MATERIAL" "CHIP"
					( Origin gFrontEnd )
				)
				( attribute "PACK_TYPE" "6PAD"
					( Origin gFrontEnd )
				)
				( attribute "PART_NUMBER" "E74391-005"
					( Origin gFrontEnd )
				)
				( attribute "PHYS_PAGE" "200"
					( Origin gFrontEnd )
				)
				( attribute "ROOM" "HOT_SWAP"
					( Origin gFrontEnd )
				)
				( attribute "ROT" "0"
					( Origin gFrontEnd )
				)
				( attribute "SEC" "1"
					( Origin gFrontEnd )
				)
				( attribute "SEC_TYPE" "6PAD"
					( Origin gFrontEnd )
				)
				( attribute "TOLERANCE" "1%"
					( Origin gFrontEnd )
				)
				( attribute "VALUE" "0.001"
					( Origin gFrontEnd )
				)
				( attribute "VER" "2"
					( Origin gFrontEnd )
				)
				( attribute "WATTAGE" "3W"
					( Origin gFrontEnd )
				)
				( attribute "XY" "(1125,3600)"
					( Origin gFrontEnd )
				)
				( attribute "CHIPS_PART_NAME" "RES_PWR"
					( Origin gPackager )
				)
				( attribute "CDS_PART_NAME" "RES_PWR_6PAD-0.001,1%,3W,CHIP,A"
					( Origin gPackager )
				)
				( objectStatus "R1D49" )
				( pin "\1\"
					( attribute "PN" "1"
						( Origin gPackager )
					)
					( objectStatus "R1D49.1" )
				)
				( pin "\2\"
					( attribute "PN" "2"
						( Origin gPackager )
					)
					( objectStatus "R1D49.2" )
				)
				( pin "\3\"
					( attribute "PN" "3"
						( Origin gPackager )
					)
					( objectStatus "R1D49.3" )
				)
				( pin "\4\"
					( attribute "PN" "4"
						( Origin gPackager )
					)
					( objectStatus "R1D49.4" )
				)
				( pin "\5\"
					( attribute "PN" "5"
						( Origin gPackager )
					)
					( objectStatus "R1D49.5" )
				)
				( pin "\6\"
					( attribute "PN" "6"
						( Origin gPackager )
					)
					( objectStatus "R1D49.6" )
				)
			)
			( gate "@baseboard_fab2_lib.baseboard_fab2(sch_1):page200_i51"
				( attribute "CDS_LIB" "mstr_discrete"
					( Origin gPackager )
				)
				( attribute "CDS_LOCATION" "R9P26"
					( Origin gPackager )
				)
				( attribute "CDS_SEC" "1"
					( Origin gPackager )
				)
				( attribute "LOCATION" "R9P26"
					( Origin gFrontEnd )
				)
				( attribute "MATERIAL" "CHIP"
					( Origin gFrontEnd )
				)
				( attribute "PACK_TYPE" "0402"
					( Origin gFrontEnd )
				)
				( attribute "PART_NUMBER" "G21796-066"
					( Origin gFrontEnd )
				)
				( attribute "PHYS_PAGE" "200"
					( Origin gFrontEnd )
				)
				( attribute "ROOM" "HOT_SWAP"
					( Origin gFrontEnd )
				)
				( attribute "ROT" "2"
					( Origin gFrontEnd )
				)
				( attribute "SEC" "1"
					( Origin gPackager )
				)
				( attribute "TOLERANCE" "1%"
					( Origin gFrontEnd )
				)
				( attribute "VALUE" "10.0"
					( Origin gFrontEnd )
				)
				( attribute "VER" "2"
					( Origin gFrontEnd )
				)
				( attribute "WATTAGE" "1/16W"
					( Origin gFrontEnd )
				)
				( attribute "XY" "(1350,2800)"
					( Origin gFrontEnd )
				)
				( attribute "CHIPS_PART_NAME" "RES"
					( Origin gPackager )
				)
				( attribute "CDS_PART_NAME" "RES_0402-10.0,1%,1/16W,CHIP,G2A"
					( Origin gPackager )
				)
				( objectStatus "R9P26" )
				( pin "a"
					( attribute "PN" "1"
						( Origin gPackager )
					)
					( objectStatus "R9P26.1" )
				)
				( pin "b"
					( attribute "PN" "2"
						( Origin gPackager )
					)
					( objectStatus "R9P26.2" )
				)
			)
			( gate "@baseboard_fab2_lib.baseboard_fab2(sch_1):page200_i52"
				( attribute "CDS_LIB" "mstr_discrete"
					( Origin gPackager )
				)
				( attribute "CDS_LOCATION" "R1D47"
					( Origin gPackager )
				)
				( attribute "CDS_SEC" "1"
					( Origin gPackager )
				)
				( attribute "LOCATION" "R1D47"
					( Origin gFrontEnd )
				)
				( attribute "MATERIAL" "CHIP"
					( Origin gFrontEnd )
				)
				( attribute "PACK_TYPE" "0402"
					( Origin gFrontEnd )
				)
				( attribute "PART_NUMBER" "G21796-066"
					( Origin gFrontEnd )
				)
				( attribute "PHYS_PAGE" "200"
					( Origin gFrontEnd )
				)
				( attribute "ROOM" "HOT_SWAP"
					( Origin gFrontEnd )
				)
				( attribute "ROT" "0"
					( Origin gFrontEnd )
				)
				( attribute "SEC" "1"
					( Origin gPackager )
				)
				( attribute "TOLERANCE" "1%"
					( Origin gFrontEnd )
				)
				( attribute "VALUE" "10.0"
					( Origin gFrontEnd )
				)
				( attribute "VER" "2"
					( Origin gFrontEnd )
				)
				( attribute "WATTAGE" "1/16W"
					( Origin gFrontEnd )
				)
				( attribute "XY" "(1475,2800)"
					( Origin gFrontEnd )
				)
				( attribute "CHIPS_PART_NAME" "RES"
					( Origin gPackager )
				)
				( attribute "CDS_PART_NAME" "RES_0402-10.0,1%,1/16W,CHIP,G2A"
					( Origin gPackager )
				)
				( objectStatus "R1D47" )
				( pin "a"
					( attribute "PN" "1"
						( Origin gPackager )
					)
					( objectStatus "R1D47.1" )
				)
				( pin "b"
					( attribute "PN" "2"
						( Origin gPackager )
					)
					( objectStatus "R1D47.2" )
				)
			)
			( gate "@baseboard_fab2_lib.baseboard_fab2(sch_1):page200_i54"
				( attribute "CDS_LIB" "mstr_discrete"
					( Origin gPackager )
				)
				( attribute "CDS_LOCATION" "EU1E3"
					( Origin gPackager )
				)
				( attribute "CDS_SEC" "1"
					( Origin gPackager )
				)
				( attribute "LOCATION" "EU1E3"
					( Origin gFrontEnd )
				)
				( attribute "MATERIAL" "IC"
					( Origin gFrontEnd )
				)
				( attribute "PACK_TYPE" "SOT5"
					( Origin gFrontEnd )
				)
				( attribute "PART_NUMBER" "G68777-001"
					( Origin gFrontEnd )
				)
				( attribute "PHYS_PAGE" "200"
					( Origin gFrontEnd )
				)
				( attribute "ROOM" "HOT_SWAP"
					( Origin gFrontEnd )
				)
				( attribute "ROT" "1"
					( Origin gFrontEnd )
				)
				( attribute "SEC" "1"
					( Origin gFrontEnd )
				)
				( attribute "SEC_TYPE" "SOT5"
					( Origin gFrontEnd )
				)
				( attribute "VER" "1"
					( Origin gFrontEnd )
				)
				( attribute "XY" "(2275,3375)"
					( Origin gFrontEnd )
				)
				( attribute "CHIPS_PART_NAME" "MOSFETN_1D3S"
					( Origin gPackager )
				)
				( attribute "CDS_PART_NAME" "MOSFETN_1D3S_SOT5-IC,G68777-001"
					( Origin gPackager )
				)
				( objectStatus "EU1E3" )
				( pin "d"
					( attribute "PN" "5"
						( Origin gPackager )
					)
					( objectStatus "EU1E3.5" )
				)
				( pin "g"
					( attribute "PN" "4"
						( Origin gPackager )
					)
					( objectStatus "EU1E3.4" )
				)
				( pin "s1"
					( attribute "PN" "1"
						( Origin gPackager )
					)
					( objectStatus "EU1E3.1" )
				)
				( pin "s2"
					( attribute "PN" "2"
						( Origin gPackager )
					)
					( objectStatus "EU1E3.2" )
				)
				( pin "s3"
					( attribute "PN" "3"
						( Origin gPackager )
					)
					( objectStatus "EU1E3.3" )
				)
			)
			( gate "@baseboard_fab2_lib.baseboard_fab2(sch_1):page200_i56"
				( attribute "CDS_LIB" "mstr_discrete"
					( Origin gPackager )
				)
				( attribute "CDS_LOCATION" "R1E1"
					( Origin gPackager )
				)
				( attribute "CDS_SEC" "1"
					( Origin gPackager )
				)
				( attribute "LOCATION" "R1E1"
					( Origin gFrontEnd )
				)
				( attribute "MATERIAL" "CHIP"
					( Origin gFrontEnd )
				)
				( attribute "PACK_TYPE" "0402"
					( Origin gFrontEnd )
				)
				( attribute "PART_NUMBER" "G21796-066"
					( Origin gFrontEnd )
				)
				( attribute "PHYS_PAGE" "200"
					( Origin gFrontEnd )
				)
				( attribute "ROOM" "HOT_SWAP"
					( Origin gFrontEnd )
				)
				( attribute "ROT" "0"
					( Origin gFrontEnd )
				)
				( attribute "SEC" "1"
					( Origin gFrontEnd )
				)
				( attribute "SEC_TYPE" "0402"
					( Origin gFrontEnd )
				)
				( attribute "TOLERANCE" "1%"
					( Origin gFrontEnd )
				)
				( attribute "VALUE" "10.0"
					( Origin gFrontEnd )
				)
				( attribute "VER" "1"
					( Origin gFrontEnd )
				)
				( attribute "WATTAGE" "1/16W"
					( Origin gFrontEnd )
				)
				( attribute "XY" "(2000,3075)"
					( Origin gFrontEnd )
				)
				( attribute "CHIPS_PART_NAME" "RES"
					( Origin gPackager )
				)
				( attribute "CDS_PART_NAME" "RES_0402-10.0,1%,1/16W,CHIP,G2A"
					( Origin gPackager )
				)
				( objectStatus "R1E1" )
				( pin "a"
					( attribute "PN" "1"
						( Origin gPackager )
					)
					( objectStatus "R1E1.1" )
				)
				( pin "b"
					( attribute "PN" "2"
						( Origin gPackager )
					)
					( objectStatus "R1E1.2" )
				)
			)
			( gate "@baseboard_fab2_lib.baseboard_fab2(sch_1):page200_i57"
				( attribute "CDS_LIB" "mstr_discrete"
					( Origin gPackager )
				)
				( attribute "CDS_LOCATION" "EU9R1"
					( Origin gPackager )
				)
				( attribute "CDS_SEC" "1"
					( Origin gPackager )
				)
				( attribute "LOCATION" "EU9R1"
					( Origin gFrontEnd )
				)
				( attribute "MATERIAL" "IC"
					( Origin gFrontEnd )
				)
				( attribute "PACK_TYPE" "SOT5"
					( Origin gFrontEnd )
				)
				( attribute "PART_NUMBER" "G68777-001"
					( Origin gFrontEnd )
				)
				( attribute "PHYS_PAGE" "200"
					( Origin gFrontEnd )
				)
				( attribute "ROOM" "HOT_SWAP"
					( Origin gFrontEnd )
				)
				( attribute "ROT" "1"
					( Origin gFrontEnd )
				)
				( attribute "SEC" "1"
					( Origin gFrontEnd )
				)
				( attribute "SEC_TYPE" "SOT5"
					( Origin gFrontEnd )
				)
				( attribute "VER" "1"
					( Origin gFrontEnd )
				)
				( attribute "XY" "(2300,2825)"
					( Origin gFrontEnd )
				)
				( attribute "CHIPS_PART_NAME" "MOSFETN_1D3S"
					( Origin gPackager )
				)
				( attribute "CDS_PART_NAME" "MOSFETN_1D3S_SOT5-IC,G68777-001"
					( Origin gPackager )
				)
				( objectStatus "EU9R1" )
				( pin "d"
					( attribute "PN" "5"
						( Origin gPackager )
					)
					( objectStatus "EU9R1.5" )
				)
				( pin "g"
					( attribute "PN" "4"
						( Origin gPackager )
					)
					( objectStatus "EU9R1.4" )
				)
				( pin "s1"
					( attribute "PN" "1"
						( Origin gPackager )
					)
					( objectStatus "EU9R1.1" )
				)
				( pin "s2"
					( attribute "PN" "2"
						( Origin gPackager )
					)
					( objectStatus "EU9R1.2" )
				)
				( pin "s3"
					( attribute "PN" "3"
						( Origin gPackager )
					)
					( objectStatus "EU9R1.3" )
				)
			)
			( gate "@baseboard_fab2_lib.baseboard_fab2(sch_1):page200_i58"
				( attribute "CDS_LIB" "mstr_discrete"
					( Origin gPackager )
				)
				( attribute "CDS_LOCATION" "R9R4"
					( Origin gPackager )
				)
				( attribute "CDS_SEC" "1"
					( Origin gPackager )
				)
				( attribute "LOCATION" "R9R4"
					( Origin gFrontEnd )
				)
				( attribute "MATERIAL" "CHIP"
					( Origin gFrontEnd )
				)
				( attribute "PACK_TYPE" "0402"
					( Origin gFrontEnd )
				)
				( attribute "PART_NUMBER" "G21796-066"
					( Origin gFrontEnd )
				)
				( attribute "PHYS_PAGE" "200"
					( Origin gFrontEnd )
				)
				( attribute "ROOM" "HOT_SWAP"
					( Origin gFrontEnd )
				)
				( attribute "ROT" "0"
					( Origin gFrontEnd )
				)
				( attribute "SEC" "1"
					( Origin gPackager )
				)
				( attribute "TOLERANCE" "1%"
					( Origin gFrontEnd )
				)
				( attribute "VALUE" "10.0"
					( Origin gFrontEnd )
				)
				( attribute "VER" "1"
					( Origin gFrontEnd )
				)
				( attribute "WATTAGE" "1/16W"
					( Origin gFrontEnd )
				)
				( attribute "XY" "(2000,2525)"
					( Origin gFrontEnd )
				)
				( attribute "CHIPS_PART_NAME" "RES"
					( Origin gPackager )
				)
				( attribute "CDS_PART_NAME" "RES_0402-10.0,1%,1/16W,CHIP,G2A"
					( Origin gPackager )
				)
				( objectStatus "R9R4" )
				( pin "a"
					( attribute "PN" "1"
						( Origin gPackager )
					)
					( objectStatus "R9R4.1" )
				)
				( pin "b"
					( attribute "PN" "2"
						( Origin gPackager )
					)
					( objectStatus "R9R4.2" )
				)
			)
			( gate "@baseboard_fab2_lib.baseboard_fab2(sch_1):page200_i59"
				( attribute "CDS_LIB" "mstr_discrete"
					( Origin gPackager )
				)
				( attribute "CDS_LOCATION" "EU1E1"
					( Origin gPackager )
				)
				( attribute "CDS_SEC" "1"
					( Origin gPackager )
				)
				( attribute "LOCATION" "EU1E1"
					( Origin gFrontEnd )
				)
				( attribute "MATERIAL" "IC"
					( Origin gFrontEnd )
				)
				( attribute "PACK_TYPE" "SOT5"
					( Origin gFrontEnd )
				)
				( attribute "PART_NUMBER" "G68777-001"
					( Origin gFrontEnd )
				)
				( attribute "PHYS_PAGE" "200"
					( Origin gFrontEnd )
				)
				( attribute "ROOM" "HOT_SWAP"
					( Origin gFrontEnd )
				)
				( attribute "ROT" "1"
					( Origin gFrontEnd )
				)
				( attribute "SEC" "1"
					( Origin gFrontEnd )
				)
				( attribute "SEC_TYPE" "SOT5"
					( Origin gFrontEnd )
				)
				( attribute "VER" "1"
					( Origin gFrontEnd )
				)
				( attribute "XY" "(2275,2100)"
					( Origin gFrontEnd )
				)
				( attribute "CHIPS_PART_NAME" "MOSFETN_1D3S"
					( Origin gPackager )
				)
				( attribute "CDS_PART_NAME" "MOSFETN_1D3S_SOT5-IC,G68777-001"
					( Origin gPackager )
				)
				( objectStatus "EU1E1" )
				( pin "d"
					( attribute "PN" "5"
						( Origin gPackager )
					)
					( objectStatus "EU1E1.5" )
				)
				( pin "g"
					( attribute "PN" "4"
						( Origin gPackager )
					)
					( objectStatus "EU1E1.4" )
				)
				( pin "s1"
					( attribute "PN" "1"
						( Origin gPackager )
					)
					( objectStatus "EU1E1.1" )
				)
				( pin "s2"
					( attribute "PN" "2"
						( Origin gPackager )
					)
					( objectStatus "EU1E1.2" )
				)
				( pin "s3"
					( attribute "PN" "3"
						( Origin gPackager )
					)
					( objectStatus "EU1E1.3" )
				)
			)
			( gate "@baseboard_fab2_lib.baseboard_fab2(sch_1):page200_i60"
				( attribute "CDS_LIB" "mstr_discrete"
					( Origin gPackager )
				)
				( attribute "CDS_LOCATION" "R1D48"
					( Origin gPackager )
				)
				( attribute "CDS_SEC" "1"
					( Origin gPackager )
				)
				( attribute "LOCATION" "R1D48"
					( Origin gFrontEnd )
				)
				( attribute "MATERIAL" "CHIP"
					( Origin gFrontEnd )
				)
				( attribute "PACK_TYPE" "0402"
					( Origin gFrontEnd )
				)
				( attribute "PART_NUMBER" "G21796-066"
					( Origin gFrontEnd )
				)
				( attribute "PHYS_PAGE" "200"
					( Origin gFrontEnd )
				)
				( attribute "ROOM" "HOT_SWAP"
					( Origin gFrontEnd )
				)
				( attribute "ROT" "0"
					( Origin gFrontEnd )
				)
				( attribute "SEC" "1"
					( Origin gFrontEnd )
				)
				( attribute "SEC_TYPE" "0402"
					( Origin gFrontEnd )
				)
				( attribute "TOLERANCE" "1%"
					( Origin gFrontEnd )
				)
				( attribute "VALUE" "10.0"
					( Origin gFrontEnd )
				)
				( attribute "VER" "1"
					( Origin gFrontEnd )
				)
				( attribute "WATTAGE" "1/16W"
					( Origin gFrontEnd )
				)
				( attribute "XY" "(1950,1775)"
					( Origin gFrontEnd )
				)
				( attribute "CHIPS_PART_NAME" "RES"
					( Origin gPackager )
				)
				( attribute "CDS_PART_NAME" "RES_0402-10.0,1%,1/16W,CHIP,G2A"
					( Origin gPackager )
				)
				( objectStatus "R1D48" )
				( pin "a"
					( attribute "PN" "1"
						( Origin gPackager )
					)
					( objectStatus "R1D48.1" )
				)
				( pin "b"
					( attribute "PN" "2"
						( Origin gPackager )
					)
					( objectStatus "R1D48.2" )
				)
			)
			( gate "@baseboard_fab2_lib.baseboard_fab2(sch_1):page200_i70"
				( attribute "CDS_LIB" "mstr_discrete"
					( Origin gPackager )
				)
				( attribute "CDS_LOCATION" "R9P19"
					( Origin gPackager )
				)
				( attribute "CDS_SEC" "1"
					( Origin gPackager )
				)
				( attribute "LOCATION" "R9P19"
					( Origin gFrontEnd )
				)
				( attribute "MATERIAL" "EMPTY"
					( Origin gFrontEnd )
				)
				( attribute "PACK_TYPE" "0402"
					( Origin gFrontEnd )
				)
				( attribute "PART_NUMBER" "G21796-016"
					( Origin gFrontEnd )
				)
				( attribute "PHYS_PAGE" "200"
					( Origin gFrontEnd )
				)
				( attribute "ROOM" "HOT_SWAP"
					( Origin gFrontEnd )
				)
				( attribute "ROT" "0"
					( Origin gFrontEnd )
				)
				( attribute "SEC" "1"
					( Origin gFrontEnd )
				)
				( attribute "SEC_TYPE" "0402"
					( Origin gFrontEnd )
				)
				( attribute "TOLERANCE" "1%"
					( Origin gFrontEnd )
				)
				( attribute "VALUE" "10.0K"
					( Origin gFrontEnd )
				)
				( attribute "VER" "2"
					( Origin gFrontEnd )
				)
				( attribute "WATTAGE" "1/16W"
					( Origin gFrontEnd )
				)
				( attribute "XY" "(-4400,-400)"
					( Origin gFrontEnd )
				)
				( attribute "CHIPS_PART_NAME" "RES"
					( Origin gPackager )
				)
				( attribute "CDS_PART_NAME" "RES_0402-10.0K,1%,1/16W,EMPTY,A"
					( Origin gPackager )
				)
				( objectStatus "R9P19" )
				( pin "a"
					( attribute "PN" "1"
						( Origin gPackager )
					)
					( objectStatus "R9P19.1" )
				)
				( pin "b"
					( attribute "PN" "2"
						( Origin gPackager )
					)
					( objectStatus "R9P19.2" )
				)
			)
			( gate "@baseboard_fab2_lib.baseboard_fab2(sch_1):page200_i71"
				( attribute "CDS_LIB" "mstr_discrete"
					( Origin gPackager )
				)
				( attribute "CDS_LOCATION" "R9P21"
					( Origin gPackager )
				)
				( attribute "CDS_SEC" "1"
					( Origin gPackager )
				)
				( attribute "LOCATION" "R9P21"
					( Origin gFrontEnd )
				)
				( attribute "MATERIAL" "CHIP"
					( Origin gFrontEnd )
				)
				( attribute "PACK_TYPE" "0402"
					( Origin gFrontEnd )
				)
				( attribute "PART_NUMBER" "G21497-005"
					( Origin gFrontEnd )
				)
				( attribute "PHYS_PAGE" "200"
					( Origin gFrontEnd )
				)
				( attribute "ROOM" "HOT_SWAP"
					( Origin gFrontEnd )
				)
				( attribute "ROT" "0"
					( Origin gFrontEnd )
				)
				( attribute "SEC" "1"
					( Origin gFrontEnd )
				)
				( attribute "SEC_TYPE" "0402"
					( Origin gFrontEnd )
				)
				( attribute "TOLERANCE" "5%"
					( Origin gFrontEnd )
				)
				( attribute "VALUE" "0.0"
					( Origin gFrontEnd )
				)
				( attribute "VER" "2"
					( Origin gFrontEnd )
				)
				( attribute "WATTAGE" "1/16W"
					( Origin gFrontEnd )
				)
				( attribute "XY" "(-4400,250)"
					( Origin gFrontEnd )
				)
				( attribute "CHIPS_PART_NAME" "RES"
					( Origin gPackager )
				)
				( attribute "CDS_PART_NAME" "RES_0402-0.0,5%,1/16W,CHIP,G21A"
					( Origin gPackager )
				)
				( objectStatus "R9P21" )
				( pin "a"
					( attribute "PN" "1"
						( Origin gPackager )
					)
					( objectStatus "R9P21.1" )
				)
				( pin "b"
					( attribute "PN" "2"
						( Origin gPackager )
					)
					( objectStatus "R9P21.2" )
				)
			)
			( gate "@baseboard_fab2_lib.baseboard_fab2(sch_1):page200_i86"
				( attribute "CDS_LIB" "mstr_discrete"
					( Origin gPackager )
				)
				( attribute "CDS_LOCATION" "R9P20"
					( Origin gPackager )
				)
				( attribute "CDS_SEC" "1"
					( Origin gPackager )
				)
				( attribute "LOCATION" "R9P20"
					( Origin gFrontEnd )
				)
				( attribute "MATERIAL" "CHIP"
					( Origin gFrontEnd )
				)
				( attribute "PACK_TYPE" "0402"
					( Origin gFrontEnd )
				)
				( attribute "PART_NUMBER" "G21796-344"
					( Origin gFrontEnd )
				)
				( attribute "PHYS_PAGE" "200"
					( Origin gFrontEnd )
				)
				( attribute "ROOM" "HOT_SWAP"
					( Origin gFrontEnd )
				)
				( attribute "ROT" "0"
					( Origin gFrontEnd )
				)
				( attribute "SEC" "1"
					( Origin gFrontEnd )
				)
				( attribute "SEC_TYPE" "0402"
					( Origin gFrontEnd )
				)
				( attribute "TOLERANCE" "1%"
					( Origin gFrontEnd )
				)
				( attribute "VALUE" "2.7K"
					( Origin gFrontEnd )
				)
				( attribute "VER" "2"
					( Origin gFrontEnd )
				)
				( attribute "WATTAGE" "1/16W"
					( Origin gFrontEnd )
				)
				( attribute "XY" "(-3300,450)"
					( Origin gFrontEnd )
				)
				( attribute "CHIPS_PART_NAME" "RES"
					( Origin gPackager )
				)
				( attribute "CDS_PART_NAME" "RES_0402-2.7K,1%,1/16W,CHIP,G2A"
					( Origin gPackager )
				)
				( objectStatus "R9P20" )
				( pin "a"
					( attribute "PN" "1"
						( Origin gPackager )
					)
					( objectStatus "R9P20.1" )
				)
				( pin "b"
					( attribute "PN" "2"
						( Origin gPackager )
					)
					( objectStatus "R9P20.2" )
				)
			)
			( gate "@baseboard_fab2_lib.baseboard_fab2(sch_1):page200_i103"
				( attribute "CDS_LIB" "mstr_ttl"
					( Origin gPackager )
				)
				( attribute "CDS_LOCATION" "U1D1"
					( Origin gPackager )
				)
				( attribute "CDS_SEC" "1"
					( Origin gPackager )
				)
				( attribute "LOCATION" "U1D1"
					( Origin gFrontEnd )
				)
				( attribute "MATERIAL" "IC"
					( Origin gFrontEnd )
				)
				( attribute "PACK_TYPE" "SOT"
					( Origin gFrontEnd )
				)
				( attribute "PART_NUMBER" "A79322-001"
					( Origin gFrontEnd )
				)
				( attribute "PHYS_PAGE" "200"
					( Origin gFrontEnd )
				)
				( attribute "ROOM" "HOT_SWAP"
					( Origin gFrontEnd )
				)
				( attribute "ROT" "0"
					( Origin gFrontEnd )
				)
				( attribute "SEC" "1"
					( Origin gFrontEnd )
				)
				( attribute "SEC_TYPE" "SOT"
					( Origin gFrontEnd )
				)
				( attribute "VALUE" "74HC1G126"
					( Origin gFrontEnd )
				)
				( attribute "VER" "1"
					( Origin gFrontEnd )
				)
				( attribute "XY" "(-2900,2225)"
					( Origin gFrontEnd )
				)
				( attribute "CHIPS_PART_NAME" "TTL1G126_A"
					( Origin gPackager )
				)
				( attribute "CDS_PART_NAME" "TTL1G126_A_SOT-74HC1G126,IC,A7B"
					( Origin gPackager )
				)
				( objectStatus "U1D1" )
				( pin "a"
					( attribute "PN" "2"
						( Origin gPackager )
					)
					( objectStatus "U1D1.2" )
				)
				( pin "oe"
					( attribute "PN" "1"
						( Origin gPackager )
					)
					( objectStatus "U1D1.1" )
				)
				( pin "y"
					( attribute "PN" "4"
						( Origin gPackager )
					)
					( objectStatus "U1D1.4" )
				)
			)
			( gate "@baseboard_fab2_lib.baseboard_fab2(sch_1):page200_i107"
				( attribute "CDS_LIB" "mstr_discrete"
					( Origin gPackager )
				)
				( attribute "CDS_LOCATION" "R9P13"
					( Origin gPackager )
				)
				( attribute "CDS_SEC" "1"
					( Origin gPackager )
				)
				( attribute "LOCATION" "R9P13"
					( Origin gFrontEnd )
				)
				( attribute "MATERIAL" "CHIP"
					( Origin gFrontEnd )
				)
				( attribute "PACK_TYPE" "0402"
					( Origin gFrontEnd )
				)
				( attribute "PART_NUMBER" "G21796-331"
					( Origin gFrontEnd )
				)
				( attribute "PHYS_PAGE" "200"
					( Origin gFrontEnd )
				)
				( attribute "ROOM" "HOT_SWAP"
					( Origin gFrontEnd )
				)
				( attribute "ROT" "0"
					( Origin gFrontEnd )
				)
				( attribute "SEC" "1"
					( Origin gFrontEnd )
				)
				( attribute "SEC_TYPE" "0402"
					( Origin gFrontEnd )
				)
				( attribute "TOLERANCE" "1.0%"
					( Origin gFrontEnd )
				)
				( attribute "VALUE" "274K"
					( Origin gFrontEnd )
				)
				( attribute "VER" "2"
					( Origin gFrontEnd )
				)
				( attribute "WATTAGE" "1/16W"
					( Origin gFrontEnd )
				)
				( attribute "XY" "(-1650,250)"
					( Origin gFrontEnd )
				)
				( attribute "CHIPS_PART_NAME" "RES"
					( Origin gPackager )
				)
				( attribute "CDS_PART_NAME" "RES_0402-274K,1.0%,1/16W,CHIP,A"
					( Origin gPackager )
				)
				( objectStatus "R9P13" )
				( pin "a"
					( attribute "PN" "1"
						( Origin gPackager )
					)
					( objectStatus "R9P13.1" )
				)
				( pin "b"
					( attribute "PN" "2"
						( Origin gPackager )
					)
					( objectStatus "R9P13.2" )
				)
			)
			( gate "@baseboard_fab2_lib.baseboard_fab2(sch_1):page200_i108"
				( attribute "CDS_LIB" "mstr_discrete"
					( Origin gPackager )
				)
				( attribute "CDS_LOCATION" "R9P11"
					( Origin gPackager )
				)
				( attribute "CDS_SEC" "1"
					( Origin gPackager )
				)
				( attribute "LOCATION" "R9P11"
					( Origin gFrontEnd )
				)
				( attribute "MATERIAL" "CHIP"
					( Origin gFrontEnd )
				)
				( attribute "PACK_TYPE" "0402"
					( Origin gFrontEnd )
				)
				( attribute "PART_NUMBER" "G21796-016"
					( Origin gFrontEnd )
				)
				( attribute "PHYS_PAGE" "200"
					( Origin gFrontEnd )
				)
				( attribute "ROOM" "HOT_SWAP"
					( Origin gFrontEnd )
				)
				( attribute "ROT" "0"
					( Origin gFrontEnd )
				)
				( attribute "SEC" "1"
					( Origin gFrontEnd )
				)
				( attribute "SEC_TYPE" "0402"
					( Origin gFrontEnd )
				)
				( attribute "TOLERANCE" "1%"
					( Origin gFrontEnd )
				)
				( attribute "VALUE" "10.0K"
					( Origin gFrontEnd )
				)
				( attribute "VER" "2"
					( Origin gFrontEnd )
				)
				( attribute "WATTAGE" "1/16W"
					( Origin gFrontEnd )
				)
				( attribute "XY" "(-1650,-150)"
					( Origin gFrontEnd )
				)
				( attribute "CHIPS_PART_NAME" "RES"
					( Origin gPackager )
				)
				( attribute "CDS_PART_NAME" "RES_0402-10.0K,1%,1/16W,CHIP,GA"
					( Origin gPackager )
				)
				( objectStatus "R9P11" )
				( pin "a"
					( attribute "PN" "1"
						( Origin gPackager )
					)
					( objectStatus "R9P11.1" )
				)
				( pin "b"
					( attribute "PN" "2"
						( Origin gPackager )
					)
					( objectStatus "R9P11.2" )
				)
			)
			( gate "@baseboard_fab2_lib.baseboard_fab2(sch_1):page200_i145"
				( attribute "CDS_LIB" "mstr_discrete"
					( Origin gPackager )
				)
				( attribute "CDS_LOCATION" "R9P7"
					( Origin gPackager )
				)
				( attribute "CDS_SEC" "1"
					( Origin gPackager )
				)
				( attribute "LOCATION" "R9P7"
					( Origin gFrontEnd )
				)
				( attribute "MATERIAL" "CHIP"
					( Origin gFrontEnd )
				)
				( attribute "PACK_TYPE" "0402"
					( Origin gFrontEnd )
				)
				( attribute "PART_NUMBER" "G21796-189"
					( Origin gFrontEnd )
				)
				( attribute "PHYS_PAGE" "200"
					( Origin gFrontEnd )
				)
				( attribute "ROOM" "HOT_SWAP"
					( Origin gFrontEnd )
				)
				( attribute "ROT" "0"
					( Origin gFrontEnd )
				)
				( attribute "SEC" "1"
					( Origin gFrontEnd )
				)
				( attribute "SEC_TYPE" "0402"
					( Origin gFrontEnd )
				)
				( attribute "TOLERANCE" "1.0%"
					( Origin gFrontEnd )
				)
				( attribute "VALUE" "249K"
					( Origin gFrontEnd )
				)
				( attribute "VER" "2"
					( Origin gFrontEnd )
				)
				( attribute "WATTAGE" "1/16W"
					( Origin gFrontEnd )
				)
				( attribute "XY" "(-1975,800)"
					( Origin gFrontEnd )
				)
				( attribute "CHIPS_PART_NAME" "RES"
					( Origin gPackager )
				)
				( attribute "CDS_PART_NAME" "RES_0402-249K,1.0%,1/16W,CHIP,A"
					( Origin gPackager )
				)
				( objectStatus "R9P7" )
				( pin "a"
					( attribute "PN" "1"
						( Origin gPackager )
					)
					( objectStatus "R9P7.1" )
				)
				( pin "b"
					( attribute "PN" "2"
						( Origin gPackager )
					)
					( objectStatus "R9P7.2" )
				)
			)
			( gate "@baseboard_fab2_lib.baseboard_fab2(sch_1):page200_i146"
				( attribute "CDS_LIB" "mstr_discrete"
					( Origin gPackager )
				)
				( attribute "CDS_LOCATION" "R9P9"
					( Origin gPackager )
				)
				( attribute "CDS_SEC" "1"
					( Origin gPackager )
				)
				( attribute "LOCATION" "R9P9"
					( Origin gFrontEnd )
				)
				( attribute "MATERIAL" "CHIP"
					( Origin gFrontEnd )
				)
				( attribute "PACK_TYPE" "0402"
					( Origin gFrontEnd )
				)
				( attribute "PART_NUMBER" "G21796-016"
					( Origin gFrontEnd )
				)
				( attribute "PHYS_PAGE" "200"
					( Origin gFrontEnd )
				)
				( attribute "ROOM" "HOT_SWAP"
					( Origin gFrontEnd )
				)
				( attribute "ROT" "0"
					( Origin gFrontEnd )
				)
				( attribute "SEC" "1"
					( Origin gFrontEnd )
				)
				( attribute "SEC_TYPE" "0402"
					( Origin gFrontEnd )
				)
				( attribute "TOLERANCE" "1%"
					( Origin gFrontEnd )
				)
				( attribute "VALUE" "10.0K"
					( Origin gFrontEnd )
				)
				( attribute "VER" "2"
					( Origin gFrontEnd )
				)
				( attribute "WATTAGE" "1/16W"
					( Origin gFrontEnd )
				)
				( attribute "XY" "(-1975,375)"
					( Origin gFrontEnd )
				)
				( attribute "CHIPS_PART_NAME" "RES"
					( Origin gPackager )
				)
				( attribute "CDS_PART_NAME" "RES_0402-10.0K,1%,1/16W,CHIP,GA"
					( Origin gPackager )
				)
				( objectStatus "R9P9" )
				( pin "a"
					( attribute "PN" "1"
						( Origin gPackager )
					)
					( objectStatus "R9P9.1" )
				)
				( pin "b"
					( attribute "PN" "2"
						( Origin gPackager )
					)
					( objectStatus "R9P9.2" )
				)
			)
			( gate "@baseboard_fab2_lib.baseboard_fab2(sch_1):page200_i149"
				( attribute "CDS_LIB" "mstr_discrete"
					( Origin gPackager )
				)
				( attribute "CDS_LOCATION" "R9P6"
					( Origin gPackager )
				)
				( attribute "CDS_SEC" "1"
					( Origin gPackager )
				)
				( attribute "LOCATION" "R9P6"
					( Origin gFrontEnd )
				)
				( attribute "MATERIAL" "CHIP"
					( Origin gFrontEnd )
				)
				( attribute "PACK_TYPE" "0402"
					( Origin gFrontEnd )
				)
				( attribute "PART_NUMBER" "G21796-016"
					( Origin gFrontEnd )
				)
				( attribute "PHYS_PAGE" "200"
					( Origin gFrontEnd )
				)
				( attribute "ROOM" "HOT_SWAP"
					( Origin gFrontEnd )
				)
				( attribute "ROT" "0"
					( Origin gFrontEnd )
				)
				( attribute "SEC" "1"
					( Origin gFrontEnd )
				)
				( attribute "SEC_TYPE" "0402"
					( Origin gFrontEnd )
				)
				( attribute "TOLERANCE" "1%"
					( Origin gFrontEnd )
				)
				( attribute "VALUE" "10.0K"
					( Origin gFrontEnd )
				)
				( attribute "VER" "2"
					( Origin gFrontEnd )
				)
				( attribute "WATTAGE" "1/16W"
					( Origin gFrontEnd )
				)
				( attribute "XY" "(600,1100)"
					( Origin gFrontEnd )
				)
				( attribute "CHIPS_PART_NAME" "RES"
					( Origin gPackager )
				)
				( attribute "CDS_PART_NAME" "RES_0402-10.0K,1%,1/16W,CHIP,GA"
					( Origin gPackager )
				)
				( objectStatus "R9P6" )
				( pin "a"
					( attribute "PN" "1"
						( Origin gPackager )
					)
					( objectStatus "R9P6.1" )
				)
				( pin "b"
					( attribute "PN" "2"
						( Origin gPackager )
					)
					( objectStatus "R9P6.2" )
				)
			)
			( gate "@baseboard_fab2_lib.baseboard_fab2(sch_1):page200_i154"
				( attribute "CDS_LIB" "mstr_discrete"
					( Origin gPackager )
				)
				( attribute "CDS_LOCATION" "R1D51"
					( Origin gPackager )
				)
				( attribute "CDS_SEC" "1"
					( Origin gPackager )
				)
				( attribute "LOCATION" "R1D51"
					( Origin gFrontEnd )
				)
				( attribute "MATERIAL" "CHIP"
					( Origin gFrontEnd )
				)
				( attribute "PACK_TYPE" "0402"
					( Origin gFrontEnd )
				)
				( attribute "PART_NUMBER" "G21796-066"
					( Origin gFrontEnd )
				)
				( attribute "PHYS_PAGE" "200"
					( Origin gFrontEnd )
				)
				( attribute "ROOM" "HOT_SWAP"
					( Origin gFrontEnd )
				)
				( attribute "ROT" "0"
					( Origin gFrontEnd )
				)
				( attribute "SEC" "1"
					( Origin gFrontEnd )
				)
				( attribute "SEC_TYPE" "0402"
					( Origin gFrontEnd )
				)
				( attribute "TOLERANCE" "1%"
					( Origin gFrontEnd )
				)
				( attribute "VALUE" "10.0"
					( Origin gFrontEnd )
				)
				( attribute "VER" "1"
					( Origin gFrontEnd )
				)
				( attribute "WATTAGE" "1/16W"
					( Origin gFrontEnd )
				)
				( attribute "XY" "(1350,1875)"
					( Origin gFrontEnd )
				)
				( attribute "CHIPS_PART_NAME" "RES"
					( Origin gPackager )
				)
				( attribute "CDS_PART_NAME" "RES_0402-10.0,1%,1/16W,CHIP,G2A"
					( Origin gPackager )
				)
				( objectStatus "R1D51" )
				( pin "a"
					( attribute "PN" "1"
						( Origin gPackager )
					)
					( objectStatus "R1D51.1" )
				)
				( pin "b"
					( attribute "PN" "2"
						( Origin gPackager )
					)
					( objectStatus "R1D51.2" )
				)
			)
			( gate "@baseboard_fab2_lib.baseboard_fab2(sch_1):page200_i155"
				( attribute "CDS_LIB" "mstr_discrete"
					( Origin gPackager )
				)
				( attribute "CDS_LOCATION" "C1E2"
					( Origin gPackager )
				)
				( attribute "CDS_SEC" "1"
					( Origin gPackager )
				)
				( attribute "LOCATION" "C1E2"
					( Origin gFrontEnd )
				)
				( attribute "MATERIAL" "X7R"
					( Origin gFrontEnd )
				)
				( attribute "PACK_TYPE" "1206"
					( Origin gFrontEnd )
				)
				( attribute "PART_NUMBER" "108427-047"
					( Origin gFrontEnd )
				)
				( attribute "PHYS_PAGE" "200"
					( Origin gFrontEnd )
				)
				( attribute "ROT" "0"
					( Origin gFrontEnd )
				)
				( attribute "SEC" "1"
					( Origin gFrontEnd )
				)
				( attribute "SEC_TYPE" "1206"
					( Origin gFrontEnd )
				)
				( attribute "TOLERANCE" "20%"
					( Origin gFrontEnd )
				)
				( attribute "VALUE" "0.068UF"
					( Origin gFrontEnd )
				)
				( attribute "VER" "1"
					( Origin gFrontEnd )
				)
				( attribute "VOLTAGE" "50V"
					( Units "uVoltage" "V" 1.000000)
					( Origin gFrontEnd )
				)
				( attribute "XY" "(900,1675)"
					( Origin gFrontEnd )
				)
				( attribute "CHIPS_PART_NAME" "CAP"
					( Origin gPackager )
				)
				( attribute "CDS_PART_NAME" "CAP_1206-0.068UF,50V,20%,X7R,1A"
					( Origin gPackager )
				)
				( objectStatus "C1E2" )
				( pin "a"
					( attribute "PN" "1"
						( Origin gPackager )
					)
					( objectStatus "C1E2.1" )
				)
				( pin "b"
					( attribute "PN" "2"
						( Origin gPackager )
					)
					( objectStatus "C1E2.2" )
				)
			)
			( gate "@baseboard_fab2_lib.baseboard_fab2(sch_1):page200_i158"
				( attribute "CDS_LIB" "mstr_discrete"
					( Origin gPackager )
				)
				( attribute "CDS_LOCATION" "R1D22"
					( Origin gPackager )
				)
				( attribute "CDS_SEC" "1"
					( Origin gPackager )
				)
				( attribute "LOCATION" "R1D22"
					( Origin gFrontEnd )
				)
				( attribute "MATERIAL" "CHIP"
					( Origin gFrontEnd )
				)
				( attribute "PACK_TYPE" "0402"
					( Origin gFrontEnd )
				)
				( attribute "PART_NUMBER" "G21796-016"
					( Origin gFrontEnd )
				)
				( attribute "PHYS_PAGE" "200"
					( Origin gFrontEnd )
				)
				( attribute "ROOM" "HOT_SWAP"
					( Origin gFrontEnd )
				)
				( attribute "ROT" "0"
					( Origin gFrontEnd )
				)
				( attribute "SEC" "1"
					( Origin gFrontEnd )
				)
				( attribute "SEC_TYPE" "0402"
					( Origin gFrontEnd )
				)
				( attribute "TOLERANCE" "1%"
					( Origin gFrontEnd )
				)
				( attribute "VALUE" "10.0K"
					( Origin gFrontEnd )
				)
				( attribute "VER" "2"
					( Origin gFrontEnd )
				)
				( attribute "WATTAGE" "1/16W"
					( Origin gFrontEnd )
				)
				( attribute "XY" "(-1650,2350)"
					( Origin gFrontEnd )
				)
				( attribute "CHIPS_PART_NAME" "RES"
					( Origin gPackager )
				)
				( attribute "CDS_PART_NAME" "RES_0402-10.0K,1%,1/16W,CHIP,GA"
					( Origin gPackager )
				)
				( objectStatus "R1D22" )
				( pin "a"
					( attribute "PN" "1"
						( Origin gPackager )
					)
					( objectStatus "R1D22.1" )
				)
				( pin "b"
					( attribute "PN" "2"
						( Origin gPackager )
					)
					( objectStatus "R1D22.2" )
				)
			)
			( gate "@baseboard_fab2_lib.baseboard_fab2(sch_1):page200_i163"
				( attribute "CDS_LIB" "mstr_vreg"
					( Origin gPackager )
				)
				( attribute "CDS_LMAN_SYM_OUTLINE" "-250,200,250,-200"
					( Origin gPackager )
				)
				( attribute "CDS_LOCATION" "U9P1"
					( Origin gPackager )
				)
				( attribute "CDS_SEC" "1"
					( Origin gPackager )
				)
				( attribute "LOCATION" "U9P1"
					( Origin gFrontEnd )
				)
				( attribute "MATERIAL" "IC"
					( Origin gFrontEnd )
				)
				( attribute "PACK_TYPE" "SM"
					( Origin gFrontEnd )
				)
				( attribute "PART_NUMBER" "H69492-001"
					( Origin gFrontEnd )
				)
				( attribute "PHYS_PAGE" "200"
					( Origin gFrontEnd )
				)
				( attribute "ROT" "0"
					( Origin gFrontEnd )
				)
				( attribute "SEC" "1"
					( Origin gFrontEnd )
				)
				( attribute "SEC_TYPE" "SM"
					( Origin gFrontEnd )
				)
				( attribute "VER" "1"
					( Origin gFrontEnd )
				)
				( attribute "XY" "(-350,350)"
					( Origin gFrontEnd )
				)
				( attribute "CHIPS_PART_NAME" "TPS3700"
					( Origin gPackager )
				)
				( attribute "CDS_PART_NAME" "TPS3700_SM-IC,H69492-001"
					( Origin gPackager )
				)
				( objectStatus "U9P1" )
				( pin "gnd"
					( attribute "PN" "5"
						( Origin gPackager )
					)
					( objectStatus "U9P1.5" )
				)
				( pin "inap"
					( attribute "PN" "4"
						( Origin gPackager )
					)
					( objectStatus "U9P1.4" )
				)
				( pin "inbn"
					( attribute "PN" "3"
						( Origin gPackager )
					)
					( objectStatus "U9P1.3" )
				)
				( pin "outa"
					( attribute "PN" "6"
						( Origin gPackager )
					)
					( objectStatus "U9P1.6" )
				)
				( pin "outb"
					( attribute "PN" "1"
						( Origin gPackager )
					)
					( objectStatus "U9P1.1" )
				)
				( pin "vdd"
					( attribute "PN" "2"
						( Origin gPackager )
					)
					( objectStatus "U9P1.2" )
				)
			)
			( gate "@baseboard_fab2_lib.baseboard_fab2(sch_1):page200_i170"
				( attribute "CDS_LIB" "mstr_vreg"
					( Origin gPackager )
				)
				( attribute "CDS_LMAN_SYM_OUTLINE" "-250,200,250,-200"
					( Origin gPackager )
				)
				( attribute "CDS_LOCATION" "U1D2"
					( Origin gPackager )
				)
				( attribute "CDS_SEC" "1"
					( Origin gPackager )
				)
				( attribute "LOCATION" "U1D2"
					( Origin gFrontEnd )
				)
				( attribute "MATERIAL" "IC"
					( Origin gFrontEnd )
				)
				( attribute "PACK_TYPE" "SM"
					( Origin gFrontEnd )
				)
				( attribute "PART_NUMBER" "H69492-001"
					( Origin gFrontEnd )
				)
				( attribute "PHYS_PAGE" "200"
					( Origin gFrontEnd )
				)
				( attribute "ROT" "0"
					( Origin gFrontEnd )
				)
				( attribute "SEC" "1"
					( Origin gFrontEnd )
				)
				( attribute "SEC_TYPE" "SM"
					( Origin gFrontEnd )
				)
				( attribute "VER" "1"
					( Origin gFrontEnd )
				)
				( attribute "XY" "(-3100,3125)"
					( Origin gFrontEnd )
				)
				( attribute "CHIPS_PART_NAME" "TPS3700"
					( Origin gPackager )
				)
				( attribute "CDS_PART_NAME" "TPS3700_SM-IC,H69492-001"
					( Origin gPackager )
				)
				( objectStatus "U1D2" )
				( pin "gnd"
					( attribute "PN" "5"
						( Origin gPackager )
					)
					( objectStatus "U1D2.5" )
				)
				( pin "inap"
					( attribute "PN" "4"
						( Origin gPackager )
					)
					( objectStatus "U1D2.4" )
				)
				( pin "inbn"
					( attribute "PN" "3"
						( Origin gPackager )
					)
					( objectStatus "U1D2.3" )
				)
				( pin "outa"
					( attribute "PN" "6"
						( Origin gPackager )
					)
					( objectStatus "U1D2.6" )
				)
				( pin "outb"
					( attribute "PN" "1"
						( Origin gPackager )
					)
					( objectStatus "U1D2.1" )
				)
				( pin "vdd"
					( attribute "PN" "2"
						( Origin gPackager )
					)
					( objectStatus "U1D2.2" )
				)
			)
			( gate "@baseboard_fab2_lib.baseboard_fab2(sch_1):page200_i172"
				( attribute "CDS_LIB" "mstr_discrete"
					( Origin gPackager )
				)
				( attribute "CDS_LOCATION" "R1D20"
					( Origin gPackager )
				)
				( attribute "CDS_SEC" "1"
					( Origin gPackager )
				)
				( attribute "LOCATION" "R1D20"
					( Origin gFrontEnd )
				)
				( attribute "MATERIAL" "CHIP"
					( Origin gFrontEnd )
				)
				( attribute "PACK_TYPE" "0402"
					( Origin gFrontEnd )
				)
				( attribute "PART_NUMBER" "G21796-109"
					( Origin gFrontEnd )
				)
				( attribute "PHYS_PAGE" "200"
					( Origin gFrontEnd )
				)
				( attribute "ROT" "0"
					( Origin gFrontEnd )
				)
				( attribute "SEC" "1"
					( Origin gFrontEnd )
				)
				( attribute "SEC_TYPE" "0402"
					( Origin gFrontEnd )
				)
				( attribute "TOLERANCE" "1%"
					( Origin gFrontEnd )
				)
				( attribute "VALUE" "150.0K"
					( Origin gFrontEnd )
				)
				( attribute "VER" "2"
					( Origin gFrontEnd )
				)
				( attribute "WATTAGE" "1/16W"
					( Origin gFrontEnd )
				)
				( attribute "XY" "(-4150,2825)"
					( Origin gFrontEnd )
				)
				( attribute "CHIPS_PART_NAME" "RES"
					( Origin gPackager )
				)
				( attribute "CDS_PART_NAME" "RES_0402-150.0K,1%,1/16W,CHIP,A"
					( Origin gPackager )
				)
				( objectStatus "R1D20" )
				( pin "a"
					( attribute "PN" "1"
						( Origin gPackager )
					)
					( objectStatus "R1D20.1" )
				)
				( pin "b"
					( attribute "PN" "2"
						( Origin gPackager )
					)
					( objectStatus "R1D20.2" )
				)
			)
			( gate "@baseboard_fab2_lib.baseboard_fab2(sch_1):page200_i173"
				( attribute "CDS_LIB" "mstr_discrete"
					( Origin gPackager )
				)
				( attribute "CDS_LOCATION" "R1D14"
					( Origin gPackager )
				)
				( attribute "CDS_SEC" "1"
					( Origin gPackager )
				)
				( attribute "LOCATION" "R1D14"
					( Origin gFrontEnd )
				)
				( attribute "MATERIAL" "CHIP"
					( Origin gFrontEnd )
				)
				( attribute "PACK_TYPE" "0402"
					( Origin gFrontEnd )
				)
				( attribute "PART_NUMBER" "G21796-099"
					( Origin gFrontEnd )
				)
				( attribute "PHYS_PAGE" "200"
					( Origin gFrontEnd )
				)
				( attribute "ROT" "0"
					( Origin gFrontEnd )
				)
				( attribute "SEC" "1"
					( Origin gFrontEnd )
				)
				( attribute "SEC_TYPE" "0402"
					( Origin gFrontEnd )
				)
				( attribute "TOLERANCE" "1%"
					( Origin gFrontEnd )
				)
				( attribute "VALUE" "105.0K"
					( Origin gFrontEnd )
				)
				( attribute "VER" "2"
					( Origin gFrontEnd )
				)
				( attribute "WATTAGE" "1/16W"
					( Origin gFrontEnd )
				)
				( attribute "XY" "(-4575,3400)"
					( Origin gFrontEnd )
				)
				( attribute "CHIPS_PART_NAME" "RES"
					( Origin gPackager )
				)
				( attribute "CDS_PART_NAME" "RES_0402-105.0K,1%,1/16W,CHIP,A"
					( Origin gPackager )
				)
				( objectStatus "R1D14" )
				( pin "a"
					( attribute "PN" "1"
						( Origin gPackager )
					)
					( objectStatus "R1D14.1" )
				)
				( pin "b"
					( attribute "PN" "2"
						( Origin gPackager )
					)
					( objectStatus "R1D14.2" )
				)
			)
			( gate "@baseboard_fab2_lib.baseboard_fab2(sch_1):page200_i174"
				( attribute "CDS_LIB" "mstr_discrete"
					( Origin gPackager )
				)
				( attribute "CDS_LOCATION" "R1D12"
					( Origin gPackager )
				)
				( attribute "CDS_SEC" "1"
					( Origin gPackager )
				)
				( attribute "LOCATION" "R1D12"
					( Origin gFrontEnd )
				)
				( attribute "MATERIAL" "CHIP"
					( Origin gFrontEnd )
				)
				( attribute "PACK_TYPE" "0402"
					( Origin gFrontEnd )
				)
				( attribute "PART_NUMBER" "G21796-016"
					( Origin gFrontEnd )
				)
				( attribute "PHYS_PAGE" "200"
					( Origin gFrontEnd )
				)
				( attribute "ROOM" "HOT_SWAP"
					( Origin gFrontEnd )
				)
				( attribute "ROT" "0"
					( Origin gFrontEnd )
				)
				( attribute "SEC" "1"
					( Origin gFrontEnd )
				)
				( attribute "SEC_TYPE" "0402"
					( Origin gFrontEnd )
				)
				( attribute "TOLERANCE" "1%"
					( Origin gFrontEnd )
				)
				( attribute "VALUE" "10.0K"
					( Origin gFrontEnd )
				)
				( attribute "VER" "2"
					( Origin gFrontEnd )
				)
				( attribute "WATTAGE" "1/16W"
					( Origin gFrontEnd )
				)
				( attribute "XY" "(-4575,2800)"
					( Origin gFrontEnd )
				)
				( attribute "CHIPS_PART_NAME" "RES"
					( Origin gPackager )
				)
				( attribute "CDS_PART_NAME" "RES_0402-10.0K,1%,1/16W,CHIP,GA"
					( Origin gPackager )
				)
				( objectStatus "R1D12" )
				( pin "a"
					( attribute "PN" "1"
						( Origin gPackager )
					)
					( objectStatus "R1D12.1" )
				)
				( pin "b"
					( attribute "PN" "2"
						( Origin gPackager )
					)
					( objectStatus "R1D12.2" )
				)
			)
			( gate "@baseboard_fab2_lib.baseboard_fab2(sch_1):page200_i175"
				( attribute "CDS_LIB" "mstr_discrete"
					( Origin gPackager )
				)
				( attribute "CDS_LOCATION" "R1D19"
					( Origin gPackager )
				)
				( attribute "CDS_SEC" "1"
					( Origin gPackager )
				)
				( attribute "LOCATION" "R1D19"
					( Origin gFrontEnd )
				)
				( attribute "MATERIAL" "CHIP"
					( Origin gFrontEnd )
				)
				( attribute "PACK_TYPE" "0402"
					( Origin gFrontEnd )
				)
				( attribute "PART_NUMBER" "G21796-016"
					( Origin gFrontEnd )
				)
				( attribute "PHYS_PAGE" "200"
					( Origin gFrontEnd )
				)
				( attribute "ROOM" "HOT_SWAP"
					( Origin gFrontEnd )
				)
				( attribute "ROT" "0"
					( Origin gFrontEnd )
				)
				( attribute "SEC" "1"
					( Origin gFrontEnd )
				)
				( attribute "SEC_TYPE" "0402"
					( Origin gFrontEnd )
				)
				( attribute "TOLERANCE" "1%"
					( Origin gFrontEnd )
				)
				( attribute "VALUE" "10.0K"
					( Origin gFrontEnd )
				)
				( attribute "VER" "2"
					( Origin gFrontEnd )
				)
				( attribute "WATTAGE" "1/16W"
					( Origin gFrontEnd )
				)
				( attribute "XY" "(-4150,2450)"
					( Origin gFrontEnd )
				)
				( attribute "CHIPS_PART_NAME" "RES"
					( Origin gPackager )
				)
				( attribute "CDS_PART_NAME" "RES_0402-10.0K,1%,1/16W,CHIP,GA"
					( Origin gPackager )
				)
				( objectStatus "R1D19" )
				( pin "a"
					( attribute "PN" "1"
						( Origin gPackager )
					)
					( objectStatus "R1D19.1" )
				)
				( pin "b"
					( attribute "PN" "2"
						( Origin gPackager )
					)
					( objectStatus "R1D19.2" )
				)
			)
			( gate "@baseboard_fab2_lib.baseboard_fab2(sch_1):page200_i185"
				( attribute "CDS_LIB" "dev_discrete"
					( Origin gPackager )
				)
				( attribute "CDS_LOCATION" "C9P6"
					( Origin gPackager )
				)
				( attribute "CDS_SEC" "1"
					( Origin gPackager )
				)
				( attribute "LOCATION" "C9P6"
					( Origin gFrontEnd )
				)
				( attribute "MATERIAL" "X7R"
					( Origin gFrontEnd )
				)
				( attribute "PACK_TYPE" "0402V"
					( Origin gFrontEnd )
				)
				( attribute "PART_NUMBER" "A36096-030"
					( Origin gFrontEnd )
				)
				( attribute "PHYS_PAGE" "200"
					( Origin gFrontEnd )
				)
				( attribute "ROOM" "HOT_SWAP"
					( Origin gFrontEnd )
				)
				( attribute "ROT" "2"
					( Origin gFrontEnd )
				)
				( attribute "SEC" "1"
					( Origin gFrontEnd )
				)
				( attribute "SEC_TYPE" "0402V"
					( Origin gFrontEnd )
				)
				( attribute "TOLERANCE" "10%"
					( Origin gFrontEnd )
				)
				( attribute "VALUE" "0.1UF"
					( Origin gFrontEnd )
				)
				( attribute "VER" "1"
					( Origin gFrontEnd )
				)
				( attribute "VOLTAGE" "16V"
					( Units "uVoltage" "V" 1.000000)
					( Origin gFrontEnd )
				)
				( attribute "XY" "(-825,775)"
					( Origin gFrontEnd )
				)
				( attribute "CHIPS_PART_NAME" "CAP_A"
					( Origin gPackager )
				)
				( attribute "CDS_PART_NAME" "CAP_A_0402V-0.1UF,16V,10%,X7R,A"
					( Origin gPackager )
				)
				( objectStatus "C9P6" )
				( pin "a"
					( attribute "PN" "1"
						( Origin gPackager )
					)
					( objectStatus "C9P6.1" )
				)
				( pin "b"
					( attribute "PN" "2"
						( Origin gPackager )
					)
					( objectStatus "C9P6.2" )
				)
			)
			( gate "@baseboard_fab2_lib.baseboard_fab2(sch_1):page200_i187"
				( attribute "CDS_LIB" "dev_discrete"
					( Origin gPackager )
				)
				( attribute "CDS_LOCATION" "C1D9"
					( Origin gPackager )
				)
				( attribute "CDS_SEC" "1"
					( Origin gPackager )
				)
				( attribute "LOCATION" "C1D9"
					( Origin gFrontEnd )
				)
				( attribute "MATERIAL" "X7R"
					( Origin gFrontEnd )
				)
				( attribute "PACK_TYPE" "0402V"
					( Origin gFrontEnd )
				)
				( attribute "PART_NUMBER" "A36096-030"
					( Origin gFrontEnd )
				)
				( attribute "PHYS_PAGE" "200"
					( Origin gFrontEnd )
				)
				( attribute "ROOM" "HOT_SWAP"
					( Origin gFrontEnd )
				)
				( attribute "ROT" "2"
					( Origin gFrontEnd )
				)
				( attribute "SEC" "1"
					( Origin gFrontEnd )
				)
				( attribute "SEC_TYPE" "0402V"
					( Origin gFrontEnd )
				)
				( attribute "TOLERANCE" "10%"
					( Origin gFrontEnd )
				)
				( attribute "VALUE" "0.1UF"
					( Origin gFrontEnd )
				)
				( attribute "VER" "1"
					( Origin gFrontEnd )
				)
				( attribute "VOLTAGE" "16V"
					( Units "uVoltage" "V" 1.000000)
					( Origin gFrontEnd )
				)
				( attribute "XY" "(-3800,3425)"
					( Origin gFrontEnd )
				)
				( attribute "CHIPS_PART_NAME" "CAP_A"
					( Origin gPackager )
				)
				( attribute "CDS_PART_NAME" "CAP_A_0402V-0.1UF,16V,10%,X7R,A"
					( Origin gPackager )
				)
				( objectStatus "C1D9" )
				( pin "a"
					( attribute "PN" "1"
						( Origin gPackager )
					)
					( objectStatus "C1D9.1" )
				)
				( pin "b"
					( attribute "PN" "2"
						( Origin gPackager )
					)
					( objectStatus "C1D9.2" )
				)
			)
			( gate "@baseboard_fab2_lib.baseboard_fab2(sch_1):page200_i189"
				( attribute "CDS_LIB" "mstr_discrete"
					( Origin gPackager )
				)
				( attribute "CDS_LOCATION" "R1D10"
					( Origin gPackager )
				)
				( attribute "CDS_SEC" "1"
					( Origin gPackager )
				)
				( attribute "LOCATION" "R1D10"
					( Origin gFrontEnd )
				)
				( attribute "MATERIAL" "CHIP"
					( Origin gFrontEnd )
				)
				( attribute "PACK_TYPE" "0402"
					( Origin gFrontEnd )
				)
				( attribute "PART_NUMBER" "G21796-016"
					( Origin gFrontEnd )
				)
				( attribute "PHYS_PAGE" "200"
					( Origin gFrontEnd )
				)
				( attribute "ROOM" "HOT_SWAP"
					( Origin gFrontEnd )
				)
				( attribute "ROT" "0"
					( Origin gFrontEnd )
				)
				( attribute "SEC" "1"
					( Origin gFrontEnd )
				)
				( attribute "SEC_TYPE" "0402"
					( Origin gFrontEnd )
				)
				( attribute "TOLERANCE" "1%"
					( Origin gFrontEnd )
				)
				( attribute "VALUE" "10.0K"
					( Origin gFrontEnd )
				)
				( attribute "VER" "2"
					( Origin gFrontEnd )
				)
				( attribute "WATTAGE" "1/16W"
					( Origin gFrontEnd )
				)
				( attribute "XY" "(-2600,3525)"
					( Origin gFrontEnd )
				)
				( attribute "CHIPS_PART_NAME" "RES"
					( Origin gPackager )
				)
				( attribute "CDS_PART_NAME" "RES_0402-10.0K,1%,1/16W,CHIP,GA"
					( Origin gPackager )
				)
				( objectStatus "R1D10" )
				( pin "a"
					( attribute "PN" "1"
						( Origin gPackager )
					)
					( objectStatus "R1D10.1" )
				)
				( pin "b"
					( attribute "PN" "2"
						( Origin gPackager )
					)
					( objectStatus "R1D10.2" )
				)
			)
			( gate "@baseboard_fab2_lib.baseboard_fab2(sch_1):page200_i191"
				( attribute "CDS_LIB" "mstr_discrete"
					( Origin gPackager )
				)
				( attribute "CDS_LOCATION" "R1D23"
					( Origin gPackager )
				)
				( attribute "CDS_SEC" "1"
					( Origin gPackager )
				)
				( attribute "LOCATION" "R1D23"
					( Origin gFrontEnd )
				)
				( attribute "MATERIAL" "CHIP"
					( Origin gFrontEnd )
				)
				( attribute "PACK_TYPE" "0402"
					( Origin gFrontEnd )
				)
				( attribute "PART_NUMBER" "G21796-016"
					( Origin gFrontEnd )
				)
				( attribute "PHYS_PAGE" "200"
					( Origin gFrontEnd )
				)
				( attribute "ROOM" "HOT_SWAP"
					( Origin gFrontEnd )
				)
				( attribute "ROT" "0"
					( Origin gFrontEnd )
				)
				( attribute "SEC" "1"
					( Origin gFrontEnd )
				)
				( attribute "SEC_TYPE" "0402"
					( Origin gFrontEnd )
				)
				( attribute "TOLERANCE" "1%"
					( Origin gFrontEnd )
				)
				( attribute "VALUE" "10.0K"
					( Origin gFrontEnd )
				)
				( attribute "VER" "2"
					( Origin gFrontEnd )
				)
				( attribute "WATTAGE" "1/16W"
					( Origin gFrontEnd )
				)
				( attribute "XY" "(-2825,3500)"
					( Origin gFrontEnd )
				)
				( attribute "CHIPS_PART_NAME" "RES"
					( Origin gPackager )
				)
				( attribute "CDS_PART_NAME" "RES_0402-10.0K,1%,1/16W,CHIP,GA"
					( Origin gPackager )
				)
				( objectStatus "R1D23" )
				( pin "a"
					( attribute "PN" "1"
						( Origin gPackager )
					)
					( objectStatus "R1D23.1" )
				)
				( pin "b"
					( attribute "PN" "2"
						( Origin gPackager )
					)
					( objectStatus "R1D23.2" )
				)
			)
			( gate "@baseboard_fab2_lib.baseboard_fab2(sch_1):page200_i192"
				( attribute "CDS_LIB" "mstr_discrete"
					( Origin gPackager )
				)
				( attribute "CDS_LOCATION" "R9P10"
					( Origin gPackager )
				)
				( attribute "CDS_SEC" "1"
					( Origin gPackager )
				)
				( attribute "LOCATION" "R9P10"
					( Origin gFrontEnd )
				)
				( attribute "MATERIAL" "CHIP"
					( Origin gFrontEnd )
				)
				( attribute "PACK_TYPE" "0402"
					( Origin gFrontEnd )
				)
				( attribute "PART_NUMBER" "G21796-016"
					( Origin gFrontEnd )
				)
				( attribute "PHYS_PAGE" "200"
					( Origin gFrontEnd )
				)
				( attribute "ROOM" "HOT_SWAP"
					( Origin gFrontEnd )
				)
				( attribute "ROT" "0"
					( Origin gFrontEnd )
				)
				( attribute "SEC" "1"
					( Origin gFrontEnd )
				)
				( attribute "SEC_TYPE" "0402"
					( Origin gFrontEnd )
				)
				( attribute "TOLERANCE" "1%"
					( Origin gFrontEnd )
				)
				( attribute "VALUE" "10.0K"
					( Origin gFrontEnd )
				)
				( attribute "VER" "2"
					( Origin gFrontEnd )
				)
				( attribute "WATTAGE" "1/16W"
					( Origin gFrontEnd )
				)
				( attribute "XY" "(275,1075)"
					( Origin gFrontEnd )
				)
				( attribute "CHIPS_PART_NAME" "RES"
					( Origin gPackager )
				)
				( attribute "CDS_PART_NAME" "RES_0402-10.0K,1%,1/16W,CHIP,GA"
					( Origin gPackager )
				)
				( objectStatus "R9P10" )
				( pin "a"
					( attribute "PN" "1"
						( Origin gPackager )
					)
					( objectStatus "R9P10.1" )
				)
				( pin "b"
					( attribute "PN" "2"
						( Origin gPackager )
					)
					( objectStatus "R9P10.2" )
				)
			)
			( gate "@baseboard_fab2_lib.baseboard_fab2(sch_1):page200_i196"
				( attribute "CDS_LIB" "mstr_discrete"
					( Origin gPackager )
				)
				( attribute "CDS_LOCATION" "Q9P1"
					( Origin gPackager )
				)
				( attribute "CDS_SEC" "1"
					( Origin gPackager )
				)
				( attribute "LOCATION" "Q9P1"
					( Origin gFrontEnd )
				)
				( attribute "MATERIAL" "FET"
					( Origin gFrontEnd )
				)
				( attribute "PACK_TYPE" "SMLF"
					( Origin gFrontEnd )
				)
				( attribute "PART_NUMBER" "D24280-001"
					( Origin gFrontEnd )
				)
				( attribute "PHYS_PAGE" "200"
					( Origin gFrontEnd )
				)
				( attribute "ROOM" "HOT_SWAP"
					( Origin gFrontEnd )
				)
				( attribute "ROT" "0"
					( Origin gFrontEnd )
				)
				( attribute "SEC" "1"
					( Origin gFrontEnd )
				)
				( attribute "SEC_TYPE" "SMLF"
					( Origin gFrontEnd )
				)
				( attribute "VALUE" "2N7002DW"
					( Origin gFrontEnd )
				)
				( attribute "VER" "5"
					( Origin gFrontEnd )
				)
				( attribute "XY" "(-2150,3325)"
					( Origin gFrontEnd )
				)
				( attribute "CHIPS_PART_NAME" "FET_N_DUAL"
					( Origin gPackager )
				)
				( attribute "CDS_PART_NAME" "FET_N_DUAL_SMLF-2N7002DW,FET,DA"
					( Origin gPackager )
				)
				( objectStatus "Q9P1" )
				( pin "drain(0)"
					( attribute "PN" "6"
						( Origin gPackager )
					)
					( objectStatus "Q9P1.6" )
				)
				( pin "gate(0)"
					( attribute "PN" "2"
						( Origin gPackager )
					)
					( objectStatus "Q9P1.2" )
				)
				( pin "source(0)"
					( attribute "PN" "1"
						( Origin gPackager )
					)
					( objectStatus "Q9P1.1" )
				)
			)
			( gate "@baseboard_fab2_lib.baseboard_fab2(sch_1):page200_i198"
				( attribute "CDS_LIB" "mstr_discrete"
					( Origin gPackager )
				)
				( attribute "CDS_LOCATION" "R9P15"
					( Origin gPackager )
				)
				( attribute "CDS_SEC" "1"
					( Origin gPackager )
				)
				( attribute "LOCATION" "R9P15"
					( Origin gFrontEnd )
				)
				( attribute "MATERIAL" "EMPTY"
					( Origin gFrontEnd )
				)
				( attribute "PACK_TYPE" "0402"
					( Origin gFrontEnd )
				)
				( attribute "PART_NUMBER" "G21497-005"
					( Origin gFrontEnd )
				)
				( attribute "PHYS_PAGE" "200"
					( Origin gFrontEnd )
				)
				( attribute "ROOM" "HOT_SWAP"
					( Origin gFrontEnd )
				)
				( attribute "ROT" "0"
					( Origin gFrontEnd )
				)
				( attribute "SEC" "1"
					( Origin gFrontEnd )
				)
				( attribute "SEC_TYPE" "0402"
					( Origin gFrontEnd )
				)
				( attribute "TOLERANCE" "5%"
					( Origin gFrontEnd )
				)
				( attribute "VALUE" "0.0"
					( Origin gFrontEnd )
				)
				( attribute "VER" "1"
					( Origin gFrontEnd )
				)
				( attribute "WATTAGE" "1/16W"
					( Origin gFrontEnd )
				)
				( attribute "XY" "(-1900,3850)"
					( Origin gFrontEnd )
				)
				( attribute "CHIPS_PART_NAME" "RES"
					( Origin gPackager )
				)
				( attribute "CDS_PART_NAME" "RES_0402-0.0,5%,1/16W,EMPTY,G2A"
					( Origin gPackager )
				)
				( objectStatus "R9P15" )
				( pin "a"
					( attribute "PN" "1"
						( Origin gPackager )
					)
					( objectStatus "R9P15.1" )
				)
				( pin "b"
					( attribute "PN" "2"
						( Origin gPackager )
					)
					( objectStatus "R9P15.2" )
				)
			)
			( gate "@baseboard_fab2_lib.baseboard_fab2(sch_1):page200_i199"
				( attribute "CDS_LIB" "mstr_discrete"
					( Origin gPackager )
				)
				( attribute "CDS_LOCATION" "Q9P1"
					( Origin gPackager )
				)
				( attribute "CDS_SEC" "2"
					( Origin gPackager )
				)
				( attribute "LOCATION" "Q9P1"
					( Origin gFrontEnd )
				)
				( attribute "MATERIAL" "FET"
					( Origin gFrontEnd )
				)
				( attribute "PACK_TYPE" "SMLF"
					( Origin gFrontEnd )
				)
				( attribute "PART_NUMBER" "D24280-001"
					( Origin gFrontEnd )
				)
				( attribute "PHYS_PAGE" "200"
					( Origin gFrontEnd )
				)
				( attribute "ROOM" "HOT_SWAP"
					( Origin gFrontEnd )
				)
				( attribute "ROT" "0"
					( Origin gFrontEnd )
				)
				( attribute "SEC" "2"
					( Origin gFrontEnd )
				)
				( attribute "SEC_TYPE" "SMLF"
					( Origin gFrontEnd )
				)
				( attribute "VALUE" "2N7002DW"
					( Origin gFrontEnd )
				)
				( attribute "VER" "5"
					( Origin gFrontEnd )
				)
				( attribute "XY" "(550,-100)"
					( Origin gFrontEnd )
				)
				( attribute "CHIPS_PART_NAME" "FET_N_DUAL"
					( Origin gPackager )
				)
				( attribute "CDS_PART_NAME" "FET_N_DUAL_SMLF-2N7002DW,FET,DA"
					( Origin gPackager )
				)
				( objectStatus "Q9P1" )
				( pin "drain(0)"
					( attribute "PN" "3"
						( Origin gPackager )
					)
					( objectStatus "Q9P1.3" )
				)
				( pin "gate(0)"
					( attribute "PN" "5"
						( Origin gPackager )
					)
					( objectStatus "Q9P1.5" )
				)
				( pin "source(0)"
					( attribute "PN" "4"
						( Origin gPackager )
					)
					( objectStatus "Q9P1.4" )
				)
			)
			( gate "@baseboard_fab2_lib.baseboard_fab2(sch_1):page200_i200"
				( attribute "CDS_LIB" "mstr_vreg"
					( Origin gPackager )
				)
				( attribute "CDS_LMAN_SYM_OUTLINE" "-250,200,250,-200"
					( Origin gPackager )
				)
				( attribute "CDS_LOCATION" "U9P2"
					( Origin gPackager )
				)
				( attribute "CDS_SEC" "1"
					( Origin gPackager )
				)
				( attribute "LOCATION" "U9P2"
					( Origin gFrontEnd )
				)
				( attribute "MATERIAL" "IC"
					( Origin gFrontEnd )
				)
				( attribute "PACK_TYPE" "SM"
					( Origin gFrontEnd )
				)
				( attribute "PART_NUMBER" "H69492-001"
					( Origin gFrontEnd )
				)
				( attribute "PHYS_PAGE" "200"
					( Origin gFrontEnd )
				)
				( attribute "ROT" "0"
					( Origin gFrontEnd )
				)
				( attribute "SEC" "1"
					( Origin gPackager )
				)
				( attribute "VER" "1"
					( Origin gFrontEnd )
				)
				( attribute "XY" "(-3425,-150)"
					( Origin gFrontEnd )
				)
				( attribute "CHIPS_PART_NAME" "TPS3700"
					( Origin gPackager )
				)
				( attribute "CDS_PART_NAME" "TPS3700_SM-IC,H69492-001"
					( Origin gPackager )
				)
				( objectStatus "U9P2" )
				( pin "gnd"
					( attribute "PN" "5"
						( Origin gPackager )
					)
					( objectStatus "U9P2.5" )
				)
				( pin "inap"
					( attribute "PN" "4"
						( Origin gPackager )
					)
					( objectStatus "U9P2.4" )
				)
				( pin "inbn"
					( attribute "PN" "3"
						( Origin gPackager )
					)
					( objectStatus "U9P2.3" )
				)
				( pin "outa"
					( attribute "PN" "6"
						( Origin gPackager )
					)
					( objectStatus "U9P2.6" )
				)
				( pin "outb"
					( attribute "PN" "1"
						( Origin gPackager )
					)
					( objectStatus "U9P2.1" )
				)
				( pin "vdd"
					( attribute "PN" "2"
						( Origin gPackager )
					)
					( objectStatus "U9P2.2" )
				)
			)
			( gate "@baseboard_fab2_lib.baseboard_fab2(sch_1):page200_i201"
				( attribute "CDS_LIB" "dev_discrete"
					( Origin gPackager )
				)
				( attribute "CDS_LOCATION" "C9P11"
					( Origin gPackager )
				)
				( attribute "CDS_SEC" "1"
					( Origin gPackager )
				)
				( attribute "LOCATION" "C9P11"
					( Origin gFrontEnd )
				)
				( attribute "MATERIAL" "X7R"
					( Origin gFrontEnd )
				)
				( attribute "PACK_TYPE" "0402V"
					( Origin gFrontEnd )
				)
				( attribute "PART_NUMBER" "A36096-030"
					( Origin gFrontEnd )
				)
				( attribute "PHYS_PAGE" "200"
					( Origin gFrontEnd )
				)
				( attribute "ROOM" "HOT_SWAP"
					( Origin gFrontEnd )
				)
				( attribute "ROT" "2"
					( Origin gFrontEnd )
				)
				( attribute "SEC" "1"
					( Origin gFrontEnd )
				)
				( attribute "SEC_TYPE" "0402V"
					( Origin gFrontEnd )
				)
				( attribute "TOLERANCE" "10%"
					( Origin gFrontEnd )
				)
				( attribute "VALUE" "0.1UF"
					( Origin gFrontEnd )
				)
				( attribute "VER" "1"
					( Origin gFrontEnd )
				)
				( attribute "VOLTAGE" "16V"
					( Units "uVoltage" "V" 1.000000)
					( Origin gFrontEnd )
				)
				( attribute "XY" "(-3450,500)"
					( Origin gFrontEnd )
				)
				( attribute "CHIPS_PART_NAME" "CAP_A"
					( Origin gPackager )
				)
				( attribute "CDS_PART_NAME" "CAP_A_0402V-0.1UF,16V,10%,X7R,A"
					( Origin gPackager )
				)
				( objectStatus "C9P11" )
				( pin "a"
					( attribute "PN" "1"
						( Origin gPackager )
					)
					( objectStatus "C9P11.1" )
				)
				( pin "b"
					( attribute "PN" "2"
						( Origin gPackager )
					)
					( objectStatus "C9P11.2" )
				)
			)
			( gate "@baseboard_fab2_lib.baseboard_fab2(sch_1):page200_i203"
				( attribute "CDS_LIB" "mstr_discrete"
					( Origin gPackager )
				)
				( attribute "CDS_LOCATION" "Q1D2"
					( Origin gPackager )
				)
				( attribute "CDS_SEC" "1"
					( Origin gPackager )
				)
				( attribute "LOCATION" "Q1D2"
					( Origin gFrontEnd )
				)
				( attribute "MATERIAL" "FET"
					( Origin gFrontEnd )
				)
				( attribute "PACK_TYPE" "SOT23LF"
					( Origin gFrontEnd )
				)
				( attribute "PART_NUMBER" "C79254-001"
					( Origin gFrontEnd )
				)
				( attribute "PHYS_PAGE" "200"
					( Origin gFrontEnd )
				)
				( attribute "ROOM" "HOT_SWAP"
					( Origin gFrontEnd )
				)
				( attribute "ROT" "0"
					( Origin gFrontEnd )
				)
				( attribute "SEC" "1"
					( Origin gFrontEnd )
				)
				( attribute "SEC_TYPE" "SOT23LF"
					( Origin gFrontEnd )
				)
				( attribute "VALUE" "2N7002"
					( Origin gFrontEnd )
				)
				( attribute "VER" "8"
					( Origin gFrontEnd )
				)
				( attribute "XY" "(-3500,1300)"
					( Origin gFrontEnd )
				)
				( attribute "CHIPS_PART_NAME" "FET_N"
					( Origin gPackager )
				)
				( attribute "CDS_PART_NAME" "FET_N_SOT23LF-2N7002,FET,C7925A"
					( Origin gPackager )
				)
				( objectStatus "Q1D2" )
				( pin "drn"
					( attribute "PN" "3"
						( Origin gPackager )
					)
					( objectStatus "Q1D2.3" )
				)
				( pin "gate"
					( attribute "PN" "1"
						( Origin gPackager )
					)
					( objectStatus "Q1D2.1" )
				)
				( pin "src"
					( attribute "PN" "2"
						( Origin gPackager )
					)
					( objectStatus "Q1D2.2" )
				)
			)
			( gate "@baseboard_fab2_lib.baseboard_fab2(sch_1):page200_i204"
				( attribute "CDS_LIB" "mstr_discrete"
					( Origin gPackager )
				)
				( attribute "CDS_LOCATION" "R1D21"
					( Origin gPackager )
				)
				( attribute "CDS_SEC" "1"
					( Origin gPackager )
				)
				( attribute "LOCATION" "R1D21"
					( Origin gFrontEnd )
				)
				( attribute "MATERIAL" "CHIP"
					( Origin gFrontEnd )
				)
				( attribute "PACK_TYPE" "0402"
					( Origin gFrontEnd )
				)
				( attribute "PART_NUMBER" "G21796-072"
					( Origin gFrontEnd )
				)
				( attribute "PHYS_PAGE" "200"
					( Origin gFrontEnd )
				)
				( attribute "ROOM" "HOT_SWAP"
					( Origin gFrontEnd )
				)
				( attribute "ROT" "0"
					( Origin gFrontEnd )
				)
				( attribute "SEC" "1"
					( Origin gFrontEnd )
				)
				( attribute "SEC_TYPE" "0402"
					( Origin gFrontEnd )
				)
				( attribute "TOLERANCE" "1%"
					( Origin gFrontEnd )
				)
				( attribute "VALUE" "4.75K"
					( Origin gFrontEnd )
				)
				( attribute "VER" "2"
					( Origin gFrontEnd )
				)
				( attribute "WATTAGE" "1/16W"
					( Origin gFrontEnd )
				)
				( attribute "XY" "(-3500,1750)"
					( Origin gFrontEnd )
				)
				( attribute "CHIPS_PART_NAME" "RES"
					( Origin gPackager )
				)
				( attribute "CDS_PART_NAME" "RES_0402-4.75K,1%,1/16W,CHIP,GA"
					( Origin gPackager )
				)
				( objectStatus "R1D21" )
				( pin "a"
					( attribute "PN" "1"
						( Origin gPackager )
					)
					( objectStatus "R1D21.1" )
				)
				( pin "b"
					( attribute "PN" "2"
						( Origin gPackager )
					)
					( objectStatus "R1D21.2" )
				)
			)
			( gate "@baseboard_fab2_lib.baseboard_fab2(sch_1):page200_i210"
				( attribute "CDS_LIB" "mstr_discrete"
					( Origin gPackager )
				)
				( attribute "CDS_LOCATION" "R9P4"
					( Origin gPackager )
				)
				( attribute "CDS_SEC" "1"
					( Origin gPackager )
				)
				( attribute "LOCATION" "R9P4"
					( Origin gFrontEnd )
				)
				( attribute "MATERIAL" "CHIP"
					( Origin gFrontEnd )
				)
				( attribute "PACK_TYPE" "0402"
					( Origin gFrontEnd )
				)
				( attribute "PART_NUMBER" "G21796-344"
					( Origin gFrontEnd )
				)
				( attribute "PHYS_PAGE" "200"
					( Origin gFrontEnd )
				)
				( attribute "ROOM" "HOT_SWAP"
					( Origin gFrontEnd )
				)
				( attribute "ROT" "0"
					( Origin gFrontEnd )
				)
				( attribute "SEC" "1"
					( Origin gFrontEnd )
				)
				( attribute "SEC_TYPE" "0402"
					( Origin gFrontEnd )
				)
				( attribute "TOLERANCE" "1%"
					( Origin gFrontEnd )
				)
				( attribute "VALUE" "2.7K"
					( Origin gFrontEnd )
				)
				( attribute "VER" "2"
					( Origin gFrontEnd )
				)
				( attribute "WATTAGE" "1/16W"
					( Origin gFrontEnd )
				)
				( attribute "XY" "(1750,225)"
					( Origin gFrontEnd )
				)
				( attribute "CHIPS_PART_NAME" "RES"
					( Origin gPackager )
				)
				( attribute "CDS_PART_NAME" "RES_0402-2.7K,1%,1/16W,CHIP,G2A"
					( Origin gPackager )
				)
				( objectStatus "R9P4" )
				( pin "a"
					( attribute "PN" "1"
						( Origin gPackager )
					)
					( objectStatus "R9P4.1" )
				)
				( pin "b"
					( attribute "PN" "2"
						( Origin gPackager )
					)
					( objectStatus "R9P4.2" )
				)
			)
			( gate "@baseboard_fab2_lib.baseboard_fab2(sch_1):page200_i213"
				( attribute "CDS_LIB" "mstr_discrete"
					( Origin gPackager )
				)
				( attribute "CDS_LOCATION" "CR9P2"
					( Origin gPackager )
				)
				( attribute "CDS_SEC" "1"
					( Origin gPackager )
				)
				( attribute "LOCATION" "CR9P2"
					( Origin gFrontEnd )
				)
				( attribute "MATERIAL" "IC"
					( Origin gFrontEnd )
				)
				( attribute "PACK_TYPE" "SMLF"
					( Origin gFrontEnd )
				)
				( attribute "PART_NUMBER" "C73510-001"
					( Origin gFrontEnd )
				)
				( attribute "PHYS_PAGE" "200"
					( Origin gFrontEnd )
				)
				( attribute "ROT" "2"
					( Origin gFrontEnd )
				)
				( attribute "SEC" "1"
					( Origin gFrontEnd )
				)
				( attribute "SEC_TYPE" "SMLF"
					( Origin gFrontEnd )
				)
				( attribute "VALUE" "BAT54WS"
					( Origin gFrontEnd )
				)
				( attribute "VER" "1"
					( Origin gFrontEnd )
				)
				( attribute "XY" "(1000,675)"
					( Origin gFrontEnd )
				)
				( attribute "CHIPS_PART_NAME" "DIODE"
					( Origin gPackager )
				)
				( attribute "CDS_PART_NAME" "DIODE_SMLF-BAT54WS,IC,C73510-0A"
					( Origin gPackager )
				)
				( objectStatus "CR9P2" )
				( pin "a"
					( attribute "PN" "2"
						( Origin gPackager )
					)
					( objectStatus "CR9P2.2" )
				)
				( pin "c"
					( attribute "PN" "1"
						( Origin gPackager )
					)
					( objectStatus "CR9P2.1" )
				)
			)
			( gate "@baseboard_fab2_lib.baseboard_fab2(sch_1):page200_i214"
				( attribute "CDS_LIB" "mstr_discrete"
					( Origin gPackager )
				)
				( attribute "CDS_LOCATION" "CR9P1"
					( Origin gPackager )
				)
				( attribute "CDS_SEC" "1"
					( Origin gPackager )
				)
				( attribute "LOCATION" "CR9P1"
					( Origin gFrontEnd )
				)
				( attribute "MATERIAL" "IC"
					( Origin gFrontEnd )
				)
				( attribute "PACK_TYPE" "SMLF"
					( Origin gFrontEnd )
				)
				( attribute "PART_NUMBER" "C73510-001"
					( Origin gFrontEnd )
				)
				( attribute "PHYS_PAGE" "200"
					( Origin gFrontEnd )
				)
				( attribute "ROT" "2"
					( Origin gFrontEnd )
				)
				( attribute "SEC" "1"
					( Origin gFrontEnd )
				)
				( attribute "SEC_TYPE" "SMLF"
					( Origin gFrontEnd )
				)
				( attribute "VALUE" "BAT54WS"
					( Origin gFrontEnd )
				)
				( attribute "VER" "1"
					( Origin gFrontEnd )
				)
				( attribute "XY" "(1050,175)"
					( Origin gFrontEnd )
				)
				( attribute "CHIPS_PART_NAME" "DIODE"
					( Origin gPackager )
				)
				( attribute "CDS_PART_NAME" "DIODE_SMLF-BAT54WS,IC,C73510-0A"
					( Origin gPackager )
				)
				( objectStatus "CR9P1" )
				( pin "a"
					( attribute "PN" "2"
						( Origin gPackager )
					)
					( objectStatus "CR9P1.2" )
				)
				( pin "c"
					( attribute "PN" "1"
						( Origin gPackager )
					)
					( objectStatus "CR9P1.1" )
				)
			)
			( gate "@baseboard_fab2_lib.baseboard_fab2(sch_1):page200_i215"
				( attribute "CDS_LIB" "mstr_discrete"
					( Origin gPackager )
				)
				( attribute "CDS_LOCATION" "R9P5"
					( Origin gPackager )
				)
				( attribute "CDS_SEC" "1"
					( Origin gPackager )
				)
				( attribute "LOCATION" "R9P5"
					( Origin gFrontEnd )
				)
				( attribute "MATERIAL" "CHIP"
					( Origin gFrontEnd )
				)
				( attribute "PACK_TYPE" "0402"
					( Origin gFrontEnd )
				)
				( attribute "PART_NUMBER" "G21796-016"
					( Origin gFrontEnd )
				)
				( attribute "PHYS_PAGE" "200"
					( Origin gFrontEnd )
				)
				( attribute "ROOM" "HOT_SWAP"
					( Origin gFrontEnd )
				)
				( attribute "ROT" "0"
					( Origin gFrontEnd )
				)
				( attribute "SEC" "1"
					( Origin gFrontEnd )
				)
				( attribute "SEC_TYPE" "0402"
					( Origin gFrontEnd )
				)
				( attribute "TOLERANCE" "1%"
					( Origin gFrontEnd )
				)
				( attribute "VALUE" "10.0K"
					( Origin gFrontEnd )
				)
				( attribute "VER" "2"
					( Origin gFrontEnd )
				)
				( attribute "WATTAGE" "1/16W"
					( Origin gFrontEnd )
				)
				( attribute "XY" "(1500,1125)"
					( Origin gFrontEnd )
				)
				( attribute "CHIPS_PART_NAME" "RES"
					( Origin gPackager )
				)
				( attribute "CDS_PART_NAME" "RES_0402-10.0K,1%,1/16W,CHIP,GA"
					( Origin gPackager )
				)
				( objectStatus "R9P5" )
				( pin "a"
					( attribute "PN" "1"
						( Origin gPackager )
					)
					( objectStatus "R9P5.1" )
				)
				( pin "b"
					( attribute "PN" "2"
						( Origin gPackager )
					)
					( objectStatus "R9P5.2" )
				)
			)
			( gate "@baseboard_fab2_lib.baseboard_fab2(sch_1):page200_i218"
				( attribute "CDS_LIB" "mstr_discrete"
					( Origin gPackager )
				)
				( attribute "CDS_LOCATION" "R9P12"
					( Origin gPackager )
				)
				( attribute "CDS_SEC" "1"
					( Origin gPackager )
				)
				( attribute "LOCATION" "R9P12"
					( Origin gFrontEnd )
				)
				( attribute "MATERIAL" "CHIP"
					( Origin gFrontEnd )
				)
				( attribute "PACK_TYPE" "0402"
					( Origin gFrontEnd )
				)
				( attribute "PART_NUMBER" "G21796-013"
					( Origin gFrontEnd )
				)
				( attribute "PHYS_PAGE" "200"
					( Origin gFrontEnd )
				)
				( attribute "ROOM" "HOT_SWAP"
					( Origin gFrontEnd )
				)
				( attribute "ROT" "0"
					( Origin gFrontEnd )
				)
				( attribute "SEC" "1"
					( Origin gFrontEnd )
				)
				( attribute "SEC_TYPE" "0402"
					( Origin gFrontEnd )
				)
				( attribute "TOLERANCE" "1%"
					( Origin gFrontEnd )
				)
				( attribute "VALUE" "4.99K"
					( Origin gFrontEnd )
				)
				( attribute "VER" "2"
					( Origin gFrontEnd )
				)
				( attribute "WATTAGE" "1/16W"
					( Origin gFrontEnd )
				)
				( attribute "XY" "(-3950,-475)"
					( Origin gFrontEnd )
				)
				( attribute "CHIPS_PART_NAME" "RES"
					( Origin gPackager )
				)
				( attribute "CDS_PART_NAME" "RES_0402-4.99K,1%,1/16W,CHIP,GA"
					( Origin gPackager )
				)
				( objectStatus "R9P12" )
				( pin "a"
					( attribute "PN" "1"
						( Origin gPackager )
					)
					( objectStatus "R9P12.1" )
				)
				( pin "b"
					( attribute "PN" "2"
						( Origin gPackager )
					)
					( objectStatus "R9P12.2" )
				)
			)
			( gate "@baseboard_fab2_lib.baseboard_fab2(sch_1):page200_i220"
				( attribute "CDS_LIB" "mstr_discrete"
					( Origin gPackager )
				)
				( attribute "CDS_LOCATION" "CR1F5"
					( Origin gPackager )
				)
				( attribute "CDS_SEC" "1"
					( Origin gPackager )
				)
				( attribute "LOCATION" "CR1F5"
					( Origin gFrontEnd )
				)
				( attribute "MATERIAL" "EMPTY"
					( Origin gFrontEnd )
				)
				( attribute "PACK_TYPE" "SM"
					( Origin gFrontEnd )
				)
				( attribute "PART_NUMBER" "C81983-002"
					( Origin gFrontEnd )
				)
				( attribute "PHYS_PAGE" "200"
					( Origin gFrontEnd )
				)
				( attribute "ROT" "1"
					( Origin gFrontEnd )
				)
				( attribute "SEC" "1"
					( Origin gFrontEnd )
				)
				( attribute "SEC_TYPE" "SM"
					( Origin gFrontEnd )
				)
				( attribute "VALUE" "MBRS340T3G"
					( Origin gFrontEnd )
				)
				( attribute "VER" "1"
					( Origin gFrontEnd )
				)
				( attribute "XY" "(2750,3275)"
					( Origin gFrontEnd )
				)
				( attribute "CHIPS_PART_NAME" "DIODE"
					( Origin gPackager )
				)
				( attribute "CDS_PART_NAME" "DIODE_SM-MBRS340T3G,EMPTY,C819A"
					( Origin gPackager )
				)
				( objectStatus "CR1F5" )
				( pin "a"
					( attribute "PN" "2"
						( Origin gPackager )
					)
					( objectStatus "CR1F5.2" )
				)
				( pin "c"
					( attribute "PN" "1"
						( Origin gPackager )
					)
					( objectStatus "CR1F5.1" )
				)
			)
			( gate "@baseboard_fab2_lib.baseboard_fab2(sch_1):page200_i222"
				( attribute "CDS_LIB" "mstr_discrete"
					( Origin gPackager )
				)
				( attribute "CDS_LOCATION" "R9P33"
					( Origin gPackager )
				)
				( attribute "CDS_SEC" "1"
					( Origin gPackager )
				)
				( attribute "LOCATION" "R9P33"
					( Origin gFrontEnd )
				)
				( attribute "MATERIAL" "CHIP"
					( Origin gFrontEnd )
				)
				( attribute "PACK_TYPE" "0402"
					( Origin gFrontEnd )
				)
				( attribute "PART_NUMBER" "G21796-010"
					( Origin gFrontEnd )
				)
				( attribute "PHYS_PAGE" "200"
					( Origin gFrontEnd )
				)
				( attribute "ROOM" "HOT_SWAP"
					( Origin gFrontEnd )
				)
				( attribute "ROT" "2"
					( Origin gFrontEnd )
				)
				( attribute "SEC" "1"
					( Origin gPackager )
				)
				( attribute "TOLERANCE" "1%"
					( Origin gFrontEnd )
				)
				( attribute "VALUE" "100.0K"
					( Origin gFrontEnd )
				)
				( attribute "VER" "2"
					( Origin gFrontEnd )
				)
				( attribute "WATTAGE" "1/16W"
					( Origin gFrontEnd )
				)
				( attribute "XY" "(-3950,200)"
					( Origin gFrontEnd )
				)
				( attribute "CHIPS_PART_NAME" "RES"
					( Origin gPackager )
				)
				( attribute "CDS_PART_NAME" "RES_0402-100.0K,1%,1/16W,CHIP,A"
					( Origin gPackager )
				)
				( objectStatus "R9P33" )
				( pin "a"
					( attribute "PN" "1"
						( Origin gPackager )
					)
					( objectStatus "R9P33.1" )
				)
				( pin "b"
					( attribute "PN" "2"
						( Origin gPackager )
					)
					( objectStatus "R9P33.2" )
				)
			)
			( gate "@baseboard_fab2_lib.baseboard_fab2(sch_1):page201_i19"
				( attribute "CDS_LIB" "mstr_discrete"
					( Origin gPackager )
				)
				( attribute "CDS_LOCATION" "R4E4"
					( Origin gPackager )
				)
				( attribute "CDS_SEC" "1"
					( Origin gPackager )
				)
				( attribute "LOCATION" "R4E4"
					( Origin gFrontEnd )
				)
				( attribute "MATERIAL" "CHIP"
					( Origin gFrontEnd )
				)
				( attribute "PACK_TYPE" "0402"
					( Origin gFrontEnd )
				)
				( attribute "PART_NUMBER" "G21796-311"
					( Origin gFrontEnd )
				)
				( attribute "PHYS_PAGE" "201"
					( Origin gFrontEnd )
				)
				( attribute "ROOM" "PVCCIN_CPU0_VR"
					( Origin gFrontEnd )
				)
				( attribute "ROT" "0"
					( Origin gFrontEnd )
				)
				( attribute "SEC" "1"
					( Origin gFrontEnd )
				)
				( attribute "SEC_TYPE" "0402"
					( Origin gFrontEnd )
				)
				( attribute "TOLERANCE" "1.0%"
					( Origin gFrontEnd )
				)
				( attribute "VALUE" "2.26K"
					( Origin gFrontEnd )
				)
				( attribute "VER" "2"
					( Origin gFrontEnd )
				)
				( attribute "WATTAGE" "1/16W"
					( Origin gFrontEnd )
				)
				( attribute "XY" "(-1925,4100)"
					( Origin gFrontEnd )
				)
				( attribute "CHIPS_PART_NAME" "RES"
					( Origin gPackager )
				)
				( attribute "CDS_PART_NAME" "RES_0402-2.26K,1.0%,1/16W,CHIPA"
					( Origin gPackager )
				)
				( objectStatus "R4E4" )
				( pin "a"
					( attribute "PN" "1"
						( Origin gPackager )
					)
					( objectStatus "R4E4.1" )
				)
				( pin "b"
					( attribute "PN" "2"
						( Origin gPackager )
					)
					( objectStatus "R4E4.2" )
				)
			)
			( gate "@baseboard_fab2_lib.baseboard_fab2(sch_1):page201_i20"
				( attribute "CDS_LIB" "mstr_discrete"
					( Origin gPackager )
				)
				( attribute "CDS_LOCATION" "R4E10"
					( Origin gPackager )
				)
				( attribute "CDS_SEC" "1"
					( Origin gPackager )
				)
				( attribute "LOCATION" "R4E10"
					( Origin gFrontEnd )
				)
				( attribute "MATERIAL" "CHIP"
					( Origin gFrontEnd )
				)
				( attribute "PACK_TYPE" "0402"
					( Origin gFrontEnd )
				)
				( attribute "PART_NUMBER" "G21796-017"
					( Origin gFrontEnd )
				)
				( attribute "PHYS_PAGE" "201"
					( Origin gFrontEnd )
				)
				( attribute "ROOM" "PVCCIN_CPU0_VR"
					( Origin gFrontEnd )
				)
				( attribute "ROT" "0"
					( Origin gFrontEnd )
				)
				( attribute "SEC" "1"
					( Origin gFrontEnd )
				)
				( attribute "SEC_TYPE" "0402"
					( Origin gFrontEnd )
				)
				( attribute "TOLERANCE" "1%"
					( Origin gFrontEnd )
				)
				( attribute "VALUE" "100.0"
					( Origin gFrontEnd )
				)
				( attribute "VER" "2"
					( Origin gFrontEnd )
				)
				( attribute "WATTAGE" "1/16W"
					( Origin gFrontEnd )
				)
				( attribute "XY" "(-1275,3750)"
					( Origin gFrontEnd )
				)
				( attribute "CHIPS_PART_NAME" "RES"
					( Origin gPackager )
				)
				( attribute "CDS_PART_NAME" "RES_0402-100.0,1%,1/16W,CHIP,GA"
					( Origin gPackager )
				)
				( objectStatus "R4E10" )
				( pin "a"
					( attribute "PN" "1"
						( Origin gPackager )
					)
					( objectStatus "R4E10.1" )
				)
				( pin "b"
					( attribute "PN" "2"
						( Origin gPackager )
					)
					( objectStatus "R4E10.2" )
				)
			)
			( gate "@baseboard_fab2_lib.baseboard_fab2(sch_1):page201_i22"
				( attribute "CDS_LIB" "mstr_discrete"
					( Origin gPackager )
				)
				( attribute "CDS_LOCATION" "R4D31"
					( Origin gPackager )
				)
				( attribute "CDS_SEC" "1"
					( Origin gPackager )
				)
				( attribute "LOCATION" "R4D31"
					( Origin gFrontEnd )
				)
				( attribute "MATERIAL" "EMPTY"
					( Origin gFrontEnd )
				)
				( attribute "PACK_TYPE" "0402"
					( Origin gFrontEnd )
				)
				( attribute "PART_NUMBER" "G21796-311"
					( Origin gFrontEnd )
				)
				( attribute "PHYS_PAGE" "201"
					( Origin gFrontEnd )
				)
				( attribute "ROOM" "PVCCIN_CPU0_VR"
					( Origin gFrontEnd )
				)
				( attribute "ROT" "0"
					( Origin gFrontEnd )
				)
				( attribute "SEC" "1"
					( Origin gFrontEnd )
				)
				( attribute "SEC_TYPE" "0402"
					( Origin gFrontEnd )
				)
				( attribute "TOLERANCE" "1.0%"
					( Origin gFrontEnd )
				)
				( attribute "VALUE" "2.26K"
					( Origin gFrontEnd )
				)
				( attribute "VER" "2"
					( Origin gFrontEnd )
				)
				( attribute "WATTAGE" "1/16W"
					( Origin gFrontEnd )
				)
				( attribute "XY" "(-2075,3750)"
					( Origin gFrontEnd )
				)
				( attribute "CHIPS_PART_NAME" "RES"
					( Origin gPackager )
				)
				( attribute "CDS_PART_NAME" "RES_0402-2.26K,1.0%,1/16W,EMPTA"
					( Origin gPackager )
				)
				( objectStatus "R4D31" )
				( pin "a"
					( attribute "PN" "1"
						( Origin gPackager )
					)
					( objectStatus "R4D31.1" )
				)
				( pin "b"
					( attribute "PN" "2"
						( Origin gPackager )
					)
					( objectStatus "R4D31.2" )
				)
			)
			( gate "@baseboard_fab2_lib.baseboard_fab2(sch_1):page201_i25"
				( attribute "CDS_LIB" "mstr_discrete"
					( Origin gPackager )
				)
				( attribute "CDS_LOCATION" "R4D58"
					( Origin gPackager )
				)
				( attribute "CDS_SEC" "1"
					( Origin gPackager )
				)
				( attribute "LOCATION" "R4D58"
					( Origin gFrontEnd )
				)
				( attribute "MATERIAL" "CHIP"
					( Origin gFrontEnd )
				)
				( attribute "PACK_TYPE" "0402"
					( Origin gFrontEnd )
				)
				( attribute "PART_NUMBER" "G21796-026"
					( Origin gFrontEnd )
				)
				( attribute "PHYS_PAGE" "201"
					( Origin gFrontEnd )
				)
				( attribute "ROOM" "PVCCIN_CPU0_VR"
					( Origin gFrontEnd )
				)
				( attribute "ROT" "0"
					( Origin gFrontEnd )
				)
				( attribute "SEC" "1"
					( Origin gFrontEnd )
				)
				( attribute "SEC_TYPE" "0402"
					( Origin gFrontEnd )
				)
				( attribute "TOLERANCE" "1%"
					( Origin gFrontEnd )
				)
				( attribute "VALUE" "1.00K"
					( Origin gFrontEnd )
				)
				( attribute "VER" "2"
					( Origin gFrontEnd )
				)
				( attribute "WATTAGE" "1/16W"
					( Origin gFrontEnd )
				)
				( attribute "XY" "(-2500,3925)"
					( Origin gFrontEnd )
				)
				( attribute "CHIPS_PART_NAME" "RES"
					( Origin gPackager )
				)
				( attribute "CDS_PART_NAME" "RES_0402-1.00K,1%,1/16W,CHIP,GA"
					( Origin gPackager )
				)
				( objectStatus "R4D58" )
				( pin "a"
					( attribute "PN" "1"
						( Origin gPackager )
					)
					( objectStatus "R4D58.1" )
				)
				( pin "b"
					( attribute "PN" "2"
						( Origin gPackager )
					)
					( objectStatus "R4D58.2" )
				)
			)
			( gate "@baseboard_fab2_lib.baseboard_fab2(sch_1):page201_i26"
				( attribute "CDS_LIB" "mstr_discrete"
					( Origin gPackager )
				)
				( attribute "CDS_LOCATION" "R4D67"
					( Origin gPackager )
				)
				( attribute "CDS_SEC" "1"
					( Origin gPackager )
				)
				( attribute "LOCATION" "R4D67"
					( Origin gFrontEnd )
				)
				( attribute "MATERIAL" "CHIP"
					( Origin gFrontEnd )
				)
				( attribute "PACK_TYPE" "0402"
					( Origin gFrontEnd )
				)
				( attribute "PART_NUMBER" "G21497-005"
					( Origin gFrontEnd )
				)
				( attribute "PHYS_PAGE" "201"
					( Origin gFrontEnd )
				)
				( attribute "ROOM" "PVCCIN_CPU0_VR"
					( Origin gFrontEnd )
				)
				( attribute "ROT" "0"
					( Origin gFrontEnd )
				)
				( attribute "SEC" "1"
					( Origin gFrontEnd )
				)
				( attribute "SEC_TYPE" "0402"
					( Origin gFrontEnd )
				)
				( attribute "TOLERANCE" "5%"
					( Origin gFrontEnd )
				)
				( attribute "VALUE" "0.0"
					( Origin gFrontEnd )
				)
				( attribute "VER" "1"
					( Origin gFrontEnd )
				)
				( attribute "WATTAGE" "1/16W"
					( Origin gFrontEnd )
				)
				( attribute "XY" "(-2025,2875)"
					( Origin gFrontEnd )
				)
				( attribute "CHIPS_PART_NAME" "RES"
					( Origin gPackager )
				)
				( attribute "CDS_PART_NAME" "RES_0402-0.0,5%,1/16W,CHIP,G21A"
					( Origin gPackager )
				)
				( objectStatus "R4D67" )
				( pin "a"
					( attribute "PN" "1"
						( Origin gPackager )
					)
					( objectStatus "R4D67.1" )
				)
				( pin "b"
					( attribute "PN" "2"
						( Origin gPackager )
					)
					( objectStatus "R4D67.2" )
				)
			)
			( gate "@baseboard_fab2_lib.baseboard_fab2(sch_1):page201_i27"
				( attribute "CDS_LIB" "mstr_discrete"
					( Origin gPackager )
				)
				( attribute "CDS_LOCATION" "R4E5"
					( Origin gPackager )
				)
				( attribute "CDS_SEC" "1"
					( Origin gPackager )
				)
				( attribute "LOCATION" "R4E5"
					( Origin gFrontEnd )
				)
				( attribute "MATERIAL" "CHIP"
					( Origin gFrontEnd )
				)
				( attribute "PACK_TYPE" "0402"
					( Origin gFrontEnd )
				)
				( attribute "PART_NUMBER" "G21796-026"
					( Origin gFrontEnd )
				)
				( attribute "PHYS_PAGE" "201"
					( Origin gFrontEnd )
				)
				( attribute "ROOM" "PVCCIN_CPU0_VR"
					( Origin gFrontEnd )
				)
				( attribute "ROT" "2"
					( Origin gFrontEnd )
				)
				( attribute "SEC" "1"
					( Origin gFrontEnd )
				)
				( attribute "SEC_TYPE" "0402"
					( Origin gFrontEnd )
				)
				( attribute "TOLERANCE" "1%"
					( Origin gFrontEnd )
				)
				( attribute "VALUE" "1.00K"
					( Origin gFrontEnd )
				)
				( attribute "VER" "2"
					( Origin gFrontEnd )
				)
				( attribute "WATTAGE" "1/16W"
					( Origin gFrontEnd )
				)
				( attribute "XY" "(-2775,3925)"
					( Origin gFrontEnd )
				)
				( attribute "CHIPS_PART_NAME" "RES"
					( Origin gPackager )
				)
				( attribute "CDS_PART_NAME" "RES_0402-1.00K,1%,1/16W,CHIP,GA"
					( Origin gPackager )
				)
				( objectStatus "R4E5" )
				( pin "a"
					( attribute "PN" "1"
						( Origin gPackager )
					)
					( objectStatus "R4E5.1" )
				)
				( pin "b"
					( attribute "PN" "2"
						( Origin gPackager )
					)
					( objectStatus "R4E5.2" )
				)
			)
			( gate "@baseboard_fab2_lib.baseboard_fab2(sch_1):page201_i28"
				( attribute "CDS_LIB" "mstr_discrete"
					( Origin gPackager )
				)
				( attribute "CDS_LOCATION" "R4D50"
					( Origin gPackager )
				)
				( attribute "CDS_SEC" "1"
					( Origin gPackager )
				)
				( attribute "LOCATION" "R4D50"
					( Origin gFrontEnd )
				)
				( attribute "MATERIAL" "CHIP"
					( Origin gFrontEnd )
				)
				( attribute "PACK_TYPE" "0402"
					( Origin gFrontEnd )
				)
				( attribute "PART_NUMBER" "G21497-005"
					( Origin gFrontEnd )
				)
				( attribute "PHYS_PAGE" "201"
					( Origin gFrontEnd )
				)
				( attribute "ROOM" "PVCCIN_CPU0_VR"
					( Origin gFrontEnd )
				)
				( attribute "ROT" "0"
					( Origin gFrontEnd )
				)
				( attribute "SEC" "1"
					( Origin gFrontEnd )
				)
				( attribute "SEC_TYPE" "0402"
					( Origin gFrontEnd )
				)
				( attribute "TOLERANCE" "5%"
					( Origin gFrontEnd )
				)
				( attribute "VALUE" "0.0"
					( Origin gFrontEnd )
				)
				( attribute "VER" "1"
					( Origin gFrontEnd )
				)
				( attribute "WATTAGE" "1/16W"
					( Origin gFrontEnd )
				)
				( attribute "XY" "(-1900,1775)"
					( Origin gFrontEnd )
				)
				( attribute "CHIPS_PART_NAME" "RES"
					( Origin gPackager )
				)
				( attribute "CDS_PART_NAME" "RES_0402-0.0,5%,1/16W,CHIP,G21A"
					( Origin gPackager )
				)
				( objectStatus "R4D50" )
				( pin "a"
					( attribute "PN" "1"
						( Origin gPackager )
					)
					( objectStatus "R4D50.1" )
				)
				( pin "b"
					( attribute "PN" "2"
						( Origin gPackager )
					)
					( objectStatus "R4D50.2" )
				)
			)
			( gate "@baseboard_fab2_lib.baseboard_fab2(sch_1):page201_i30"
				( attribute "CDS_LIB" "dev_discrete"
					( Origin gPackager )
				)
				( attribute "CDS_LOCATION" "C4D25"
					( Origin gPackager )
				)
				( attribute "CDS_SEC" "1"
					( Origin gPackager )
				)
				( attribute "LOCATION" "C4D25"
					( Origin gFrontEnd )
				)
				( attribute "MATERIAL" "X6S"
					( Origin gFrontEnd )
				)
				( attribute "PACK_TYPE" "0402V"
					( Origin gFrontEnd )
				)
				( attribute "PART_NUMBER" "D97712-004"
					( Origin gFrontEnd )
				)
				( attribute "PHYS_PAGE" "201"
					( Origin gFrontEnd )
				)
				( attribute "ROOM" "PVCCIN_CPU0_VR"
					( Origin gFrontEnd )
				)
				( attribute "ROT" "0"
					( Origin gFrontEnd )
				)
				( attribute "SEC" "1"
					( Origin gFrontEnd )
				)
				( attribute "SEC_TYPE" "0402V"
					( Origin gFrontEnd )
				)
				( attribute "TOLERANCE" "10%"
					( Origin gFrontEnd )
				)
				( attribute "VALUE" "1.0UF"
					( Origin gFrontEnd )
				)
				( attribute "VER" "1"
					( Origin gFrontEnd )
				)
				( attribute "VOLTAGE" "6.3V"
					( Units "uVoltage" "V" 1.000000)
					( Origin gFrontEnd )
				)
				( attribute "XY" "(-1475,1000)"
					( Origin gFrontEnd )
				)
				( attribute "CHIPS_PART_NAME" "CAP_A"
					( Origin gPackager )
				)
				( attribute "CDS_PART_NAME" "CAP_A_0402V-1.0UF,6.3V,10%,X6SA"
					( Origin gPackager )
				)
				( objectStatus "C4D25" )
				( pin "a"
					( attribute "PN" "1"
						( Origin gPackager )
					)
					( objectStatus "C4D25.1" )
				)
				( pin "b"
					( attribute "PN" "2"
						( Origin gPackager )
					)
					( objectStatus "C4D25.2" )
				)
			)
			( gate "@baseboard_fab2_lib.baseboard_fab2(sch_1):page201_i31"
				( attribute "CDS_LIB" "mstr_discrete"
					( Origin gPackager )
				)
				( attribute "CDS_LOCATION" "R4D53"
					( Origin gPackager )
				)
				( attribute "CDS_SEC" "1"
					( Origin gPackager )
				)
				( attribute "LOCATION" "R4D53"
					( Origin gFrontEnd )
				)
				( attribute "MATERIAL" "CHIP"
					( Origin gFrontEnd )
				)
				( attribute "PACK_TYPE" "0402"
					( Origin gFrontEnd )
				)
				( attribute "PART_NUMBER" "G21497-005"
					( Origin gFrontEnd )
				)
				( attribute "PHYS_PAGE" "201"
					( Origin gFrontEnd )
				)
				( attribute "ROOM" "PVCCIN_CPU0_VR"
					( Origin gFrontEnd )
				)
				( attribute "ROT" "0"
					( Origin gFrontEnd )
				)
				( attribute "SEC" "1"
					( Origin gFrontEnd )
				)
				( attribute "SEC_TYPE" "0402"
					( Origin gFrontEnd )
				)
				( attribute "TOLERANCE" "5%"
					( Origin gFrontEnd )
				)
				( attribute "VALUE" "0.0"
					( Origin gFrontEnd )
				)
				( attribute "VER" "1"
					( Origin gFrontEnd )
				)
				( attribute "WATTAGE" "1/16W"
					( Origin gFrontEnd )
				)
				( attribute "XY" "(-1900,1525)"
					( Origin gFrontEnd )
				)
				( attribute "CHIPS_PART_NAME" "RES"
					( Origin gPackager )
				)
				( attribute "CDS_PART_NAME" "RES_0402-0.0,5%,1/16W,CHIP,G21A"
					( Origin gPackager )
				)
				( objectStatus "R4D53" )
				( pin "a"
					( attribute "PN" "1"
						( Origin gPackager )
					)
					( objectStatus "R4D53.1" )
				)
				( pin "b"
					( attribute "PN" "2"
						( Origin gPackager )
					)
					( objectStatus "R4D53.2" )
				)
			)
			( gate "@baseboard_fab2_lib.baseboard_fab2(sch_1):page201_i32"
				( attribute "CDS_LIB" "dev_discrete"
					( Origin gPackager )
				)
				( attribute "CDS_LOCATION" "C4D26"
					( Origin gPackager )
				)
				( attribute "CDS_SEC" "1"
					( Origin gPackager )
				)
				( attribute "LOCATION" "C4D26"
					( Origin gFrontEnd )
				)
				( attribute "MATERIAL" "X7R"
					( Origin gFrontEnd )
				)
				( attribute "PACK_TYPE" "0402V"
					( Origin gFrontEnd )
				)
				( attribute "PART_NUMBER" "A36096-030"
					( Origin gFrontEnd )
				)
				( attribute "PHYS_PAGE" "201"
					( Origin gFrontEnd )
				)
				( attribute "ROOM" "PVCCIN_CPU0_VR"
					( Origin gFrontEnd )
				)
				( attribute "ROT" "0"
					( Origin gFrontEnd )
				)
				( attribute "SEC" "1"
					( Origin gFrontEnd )
				)
				( attribute "SEC_TYPE" "0402V"
					( Origin gFrontEnd )
				)
				( attribute "TOLERANCE" "10%"
					( Origin gFrontEnd )
				)
				( attribute "VALUE" "0.1UF"
					( Origin gFrontEnd )
				)
				( attribute "VER" "1"
					( Origin gFrontEnd )
				)
				( attribute "VOLTAGE" "16V"
					( Units "uVoltage" "V" 1.000000)
					( Origin gFrontEnd )
				)
				( attribute "XY" "(-1875,1000)"
					( Origin gFrontEnd )
				)
				( attribute "CHIPS_PART_NAME" "CAP_A"
					( Origin gPackager )
				)
				( attribute "CDS_PART_NAME" "CAP_A_0402V-0.1UF,16V,10%,X7R,A"
					( Origin gPackager )
				)
				( objectStatus "C4D26" )
				( pin "a"
					( attribute "PN" "1"
						( Origin gPackager )
					)
					( objectStatus "C4D26.1" )
				)
				( pin "b"
					( attribute "PN" "2"
						( Origin gPackager )
					)
					( objectStatus "C4D26.2" )
				)
			)
			( gate "@baseboard_fab2_lib.baseboard_fab2(sch_1):page201_i37"
				( attribute "CDS_LIB" "dev_discrete"
					( Origin gPackager )
				)
				( attribute "CDS_LOCATION" "C4D15"
					( Origin gPackager )
				)
				( attribute "CDS_SEC" "1"
					( Origin gPackager )
				)
				( attribute "LOCATION" "C4D15"
					( Origin gFrontEnd )
				)
				( attribute "MATERIAL" "X6S"
					( Origin gFrontEnd )
				)
				( attribute "PACK_TYPE" "0402V"
					( Origin gFrontEnd )
				)
				( attribute "PART_NUMBER" "D97712-004"
					( Origin gFrontEnd )
				)
				( attribute "PHYS_PAGE" "201"
					( Origin gFrontEnd )
				)
				( attribute "ROOM" "PVCCIN_CPU0_VR"
					( Origin gFrontEnd )
				)
				( attribute "ROT" "0"
					( Origin gFrontEnd )
				)
				( attribute "SEC" "1"
					( Origin gFrontEnd )
				)
				( attribute "SEC_TYPE" "0402V"
					( Origin gFrontEnd )
				)
				( attribute "TOLERANCE" "10%"
					( Origin gFrontEnd )
				)
				( attribute "VALUE" "1.0UF"
					( Origin gFrontEnd )
				)
				( attribute "VER" "1"
					( Origin gFrontEnd )
				)
				( attribute "VOLTAGE" "6.3V"
					( Units "uVoltage" "V" 1.000000)
					( Origin gFrontEnd )
				)
				( attribute "XY" "(-3550,3925)"
					( Origin gFrontEnd )
				)
				( attribute "CHIPS_PART_NAME" "CAP_A"
					( Origin gPackager )
				)
				( attribute "CDS_PART_NAME" "CAP_A_0402V-1.0UF,6.3V,10%,X6SA"
					( Origin gPackager )
				)
				( objectStatus "C4D15" )
				( pin "a"
					( attribute "PN" "1"
						( Origin gPackager )
					)
					( objectStatus "C4D15.1" )
				)
				( pin "b"
					( attribute "PN" "2"
						( Origin gPackager )
					)
					( objectStatus "C4D15.2" )
				)
			)
			( gate "@baseboard_fab2_lib.baseboard_fab2(sch_1):page201_i39"
				( attribute "CDS_LIB" "dev_discrete"
					( Origin gPackager )
				)
				( attribute "CDS_LOCATION" "C4D19"
					( Origin gPackager )
				)
				( attribute "CDS_SEC" "1"
					( Origin gPackager )
				)
				( attribute "LOCATION" "C4D19"
					( Origin gFrontEnd )
				)
				( attribute "MATERIAL" "X7R"
					( Origin gFrontEnd )
				)
				( attribute "PACK_TYPE" "0402V"
					( Origin gFrontEnd )
				)
				( attribute "PART_NUMBER" "A36096-030"
					( Origin gFrontEnd )
				)
				( attribute "PHYS_PAGE" "201"
					( Origin gFrontEnd )
				)
				( attribute "ROOM" "PVCCIN_CPU0_VR"
					( Origin gFrontEnd )
				)
				( attribute "ROT" "0"
					( Origin gFrontEnd )
				)
				( attribute "SEC" "1"
					( Origin gFrontEnd )
				)
				( attribute "SEC_TYPE" "0402V"
					( Origin gFrontEnd )
				)
				( attribute "TOLERANCE" "10%"
					( Origin gFrontEnd )
				)
				( attribute "VALUE" "0.1UF"
					( Origin gFrontEnd )
				)
				( attribute "VER" "1"
					( Origin gFrontEnd )
				)
				( attribute "VOLTAGE" "16V"
					( Units "uVoltage" "V" 1.000000)
					( Origin gFrontEnd )
				)
				( attribute "XY" "(-3950,3925)"
					( Origin gFrontEnd )
				)
				( attribute "CHIPS_PART_NAME" "CAP_A"
					( Origin gPackager )
				)
				( attribute "CDS_PART_NAME" "CAP_A_0402V-0.1UF,16V,10%,X7R,A"
					( Origin gPackager )
				)
				( objectStatus "C4D19" )
				( pin "a"
					( attribute "PN" "1"
						( Origin gPackager )
					)
					( objectStatus "C4D19.1" )
				)
				( pin "b"
					( attribute "PN" "2"
						( Origin gPackager )
					)
					( objectStatus "C4D19.2" )
				)
			)
			( gate "@baseboard_fab2_lib.baseboard_fab2(sch_1):page201_i40"
				( attribute "CDS_LIB" "mstr_discrete"
					( Origin gPackager )
				)
				( attribute "CDS_LOCATION" "R4D26"
					( Origin gPackager )
				)
				( attribute "CDS_SEC" "1"
					( Origin gPackager )
				)
				( attribute "LOCATION" "R4D26"
					( Origin gFrontEnd )
				)
				( attribute "MATERIAL" "CHIP"
					( Origin gFrontEnd )
				)
				( attribute "PACK_TYPE" "0402"
					( Origin gFrontEnd )
				)
				( attribute "PART_NUMBER" "G21497-005"
					( Origin gFrontEnd )
				)
				( attribute "PHYS_PAGE" "201"
					( Origin gFrontEnd )
				)
				( attribute "ROOM" "PVCCIN_CPU0_VR"
					( Origin gFrontEnd )
				)
				( attribute "ROT" "0"
					( Origin gFrontEnd )
				)
				( attribute "SEC" "1"
					( Origin gFrontEnd )
				)
				( attribute "SEC_TYPE" "0402"
					( Origin gFrontEnd )
				)
				( attribute "TOLERANCE" "5%"
					( Origin gFrontEnd )
				)
				( attribute "VALUE" "0.0"
					( Origin gFrontEnd )
				)
				( attribute "VER" "2"
					( Origin gFrontEnd )
				)
				( attribute "WATTAGE" "1/16W"
					( Origin gFrontEnd )
				)
				( attribute "XY" "(-4250,4275)"
					( Origin gFrontEnd )
				)
				( attribute "CHIPS_PART_NAME" "RES"
					( Origin gPackager )
				)
				( attribute "CDS_PART_NAME" "RES_0402-0.0,5%,1/16W,CHIP,G21A"
					( Origin gPackager )
				)
				( objectStatus "R4D26" )
				( pin "a"
					( attribute "PN" "1"
						( Origin gPackager )
					)
					( objectStatus "R4D26.1" )
				)
				( pin "b"
					( attribute "PN" "2"
						( Origin gPackager )
					)
					( objectStatus "R4D26.2" )
				)
			)
			( gate "@baseboard_fab2_lib.baseboard_fab2(sch_1):page201_i52"
				( attribute "CDS_LIB" "mstr_discrete"
					( Origin gPackager )
				)
				( attribute "CDS_LOCATION" "R4E9"
					( Origin gPackager )
				)
				( attribute "CDS_SEC" "1"
					( Origin gPackager )
				)
				( attribute "LOCATION" "R4E9"
					( Origin gFrontEnd )
				)
				( attribute "MATERIAL" "CHIP"
					( Origin gFrontEnd )
				)
				( attribute "PACK_TYPE" "0402"
					( Origin gFrontEnd )
				)
				( attribute "PART_NUMBER" "G21796-047"
					( Origin gFrontEnd )
				)
				( attribute "PHYS_PAGE" "201"
					( Origin gFrontEnd )
				)
				( attribute "ROOM" "PVCCIN_CPU0_VR"
					( Origin gFrontEnd )
				)
				( attribute "ROT" "0"
					( Origin gFrontEnd )
				)
				( attribute "SEC" "1"
					( Origin gFrontEnd )
				)
				( attribute "SEC_TYPE" "0402"
					( Origin gFrontEnd )
				)
				( attribute "TOLERANCE" "1%"
					( Origin gFrontEnd )
				)
				( attribute "VALUE" "49.9"
					( Origin gFrontEnd )
				)
				( attribute "VER" "2"
					( Origin gFrontEnd )
				)
				( attribute "WATTAGE" "1/16W"
					( Origin gFrontEnd )
				)
				( attribute "XY" "(-5650,4275)"
					( Origin gFrontEnd )
				)
				( attribute "CHIPS_PART_NAME" "RES"
					( Origin gPackager )
				)
				( attribute "CDS_PART_NAME" "RES_0402-49.9,1%,1/16W,CHIP,G2A"
					( Origin gPackager )
				)
				( objectStatus "R4E9" )
				( pin "a"
					( attribute "PN" "1"
						( Origin gPackager )
					)
					( objectStatus "R4E9.1" )
				)
				( pin "b"
					( attribute "PN" "2"
						( Origin gPackager )
					)
					( objectStatus "R4E9.2" )
				)
			)
			( gate "@baseboard_fab2_lib.baseboard_fab2(sch_1):page201_i54"
				( attribute "CDS_LIB" "mstr_discrete"
					( Origin gPackager )
				)
				( attribute "CDS_LOCATION" "R4D27"
					( Origin gPackager )
				)
				( attribute "CDS_SEC" "1"
					( Origin gPackager )
				)
				( attribute "LOCATION" "R4D27"
					( Origin gFrontEnd )
				)
				( attribute "MATERIAL" "CHIP"
					( Origin gFrontEnd )
				)
				( attribute "PACK_TYPE" "0402"
					( Origin gFrontEnd )
				)
				( attribute "PART_NUMBER" "G21796-160"
					( Origin gFrontEnd )
				)
				( attribute "PHYS_PAGE" "201"
					( Origin gFrontEnd )
				)
				( attribute "ROOM" "PVCCIN_CPU0_VR"
					( Origin gFrontEnd )
				)
				( attribute "ROT" "0"
					( Origin gFrontEnd )
				)
				( attribute "SEC" "1"
					( Origin gFrontEnd )
				)
				( attribute "SEC_TYPE" "0402"
					( Origin gFrontEnd )
				)
				( attribute "TOLERANCE" "1%"
					( Origin gFrontEnd )
				)
				( attribute "VALUE" "100.0K"
					( Origin gFrontEnd )
				)
				( attribute "VER" "2"
					( Origin gFrontEnd )
				)
				( attribute "WATTAGE" "1/16W"
					( Origin gFrontEnd )
				)
				( attribute "XY" "(-6050,4625)"
					( Origin gFrontEnd )
				)
				( attribute "CHIPS_PART_NAME" "RES"
					( Origin gPackager )
				)
				( attribute "CDS_PART_NAME" "RES_0402-100.0K,1%,1/16W,CHIP,B"
					( Origin gPackager )
				)
				( objectStatus "R4D27" )
				( pin "a"
					( attribute "PN" "1"
						( Origin gPackager )
					)
					( objectStatus "R4D27.1" )
				)
				( pin "b"
					( attribute "PN" "2"
						( Origin gPackager )
					)
					( objectStatus "R4D27.2" )
				)
			)
			( gate "@baseboard_fab2_lib.baseboard_fab2(sch_1):page201_i55"
				( attribute "CDS_LIB" "mstr_discrete"
					( Origin gPackager )
				)
				( attribute "CDS_LOCATION" "R4D32"
					( Origin gPackager )
				)
				( attribute "CDS_SEC" "1"
					( Origin gPackager )
				)
				( attribute "LOCATION" "R4D32"
					( Origin gFrontEnd )
				)
				( attribute "MATERIAL" "CHIP"
					( Origin gFrontEnd )
				)
				( attribute "PACK_TYPE" "0402"
					( Origin gFrontEnd )
				)
				( attribute "PART_NUMBER" "G21796-003"
					( Origin gFrontEnd )
				)
				( attribute "PHYS_PAGE" "201"
					( Origin gFrontEnd )
				)
				( attribute "ROOM" "PVCCIN_CPU0_VR"
					( Origin gFrontEnd )
				)
				( attribute "ROT" "0"
					( Origin gFrontEnd )
				)
				( attribute "SEC" "1"
					( Origin gFrontEnd )
				)
				( attribute "SEC_TYPE" "0402"
					( Origin gFrontEnd )
				)
				( attribute "TOLERANCE" "1%"
					( Origin gFrontEnd )
				)
				( attribute "VALUE" "1.5K"
					( Origin gFrontEnd )
				)
				( attribute "VER" "2"
					( Origin gFrontEnd )
				)
				( attribute "WATTAGE" "1/16W"
					( Origin gFrontEnd )
				)
				( attribute "XY" "(-6050,4200)"
					( Origin gFrontEnd )
				)
				( attribute "CHIPS_PART_NAME" "RES"
					( Origin gPackager )
				)
				( attribute "CDS_PART_NAME" "RES_0402-1.5K,1%,1/16W,CHIP,G2A"
					( Origin gPackager )
				)
				( objectStatus "R4D32" )
				( pin "a"
					( attribute "PN" "1"
						( Origin gPackager )
					)
					( objectStatus "R4D32.1" )
				)
				( pin "b"
					( attribute "PN" "2"
						( Origin gPackager )
					)
					( objectStatus "R4D32.2" )
				)
			)
			( gate "@baseboard_fab2_lib.baseboard_fab2(sch_1):page201_i56"
				( attribute "CDS_LIB" "mstr_discrete"
					( Origin gPackager )
				)
				( attribute "CDS_LOCATION" "R4E6"
					( Origin gPackager )
				)
				( attribute "CDS_SEC" "1"
					( Origin gPackager )
				)
				( attribute "LOCATION" "R4E6"
					( Origin gFrontEnd )
				)
				( attribute "MATERIAL" "CHIP"
					( Origin gFrontEnd )
				)
				( attribute "PACK_TYPE" "0402"
					( Origin gFrontEnd )
				)
				( attribute "PART_NUMBER" "G21796-009"
					( Origin gFrontEnd )
				)
				( attribute "PHYS_PAGE" "201"
					( Origin gFrontEnd )
				)
				( attribute "ROOM" "PVCCIN_CPU0_VR"
					( Origin gFrontEnd )
				)
				( attribute "ROT" "0"
					( Origin gFrontEnd )
				)
				( attribute "SEC" "1"
					( Origin gFrontEnd )
				)
				( attribute "SEC_TYPE" "0402"
					( Origin gFrontEnd )
				)
				( attribute "TOLERANCE" "1%"
					( Origin gFrontEnd )
				)
				( attribute "VALUE" "150.0"
					( Origin gFrontEnd )
				)
				( attribute "VER" "1"
					( Origin gFrontEnd )
				)
				( attribute "WATTAGE" "1/16W"
					( Origin gFrontEnd )
				)
				( attribute "XY" "(-5400,3950)"
					( Origin gFrontEnd )
				)
				( attribute "CHIPS_PART_NAME" "RES"
					( Origin gPackager )
				)
				( attribute "CDS_PART_NAME" "RES_0402-150.0,1%,1/16W,CHIP,GA"
					( Origin gPackager )
				)
				( objectStatus "R4E6" )
				( pin "a"
					( attribute "PN" "1"
						( Origin gPackager )
					)
					( objectStatus "R4E6.1" )
				)
				( pin "b"
					( attribute "PN" "2"
						( Origin gPackager )
					)
					( objectStatus "R4E6.2" )
				)
			)
			( gate "@baseboard_fab2_lib.baseboard_fab2(sch_1):page201_i60"
				( attribute "CDS_LIB" "mstr_discrete"
					( Origin gPackager )
				)
				( attribute "CDS_LOCATION" "C4D20"
					( Origin gPackager )
				)
				( attribute "CDS_SEC" "1"
					( Origin gPackager )
				)
				( attribute "LOCATION" "C4D20"
					( Origin gFrontEnd )
				)
				( attribute "MATERIAL" "X7R"
					( Origin gFrontEnd )
				)
				( attribute "PACK_TYPE" "0402LF"
					( Origin gFrontEnd )
				)
				( attribute "PART_NUMBER" "A36096-046"
					( Origin gFrontEnd )
				)
				( attribute "PHYS_PAGE" "201"
					( Origin gFrontEnd )
				)
				( attribute "ROOM" "PVCCIN_CPU0_VR"
					( Origin gFrontEnd )
				)
				( attribute "ROT" "2"
					( Origin gFrontEnd )
				)
				( attribute "SEC" "1"
					( Origin gFrontEnd )
				)
				( attribute "SEC_TYPE" "0402LF"
					( Origin gFrontEnd )
				)
				( attribute "TOLERANCE" "10%"
					( Origin gFrontEnd )
				)
				( attribute "VALUE" "1000PF"
					( Origin gFrontEnd )
				)
				( attribute "VER" "1"
					( Origin gFrontEnd )
				)
				( attribute "VOLTAGE" "50V"
					( Units "uVoltage" "V" 1.000000)
					( Origin gFrontEnd )
				)
				( attribute "XY" "(-6300,4225)"
					( Origin gFrontEnd )
				)
				( attribute "CHIPS_PART_NAME" "CAP"
					( Origin gPackager )
				)
				( attribute "CDS_PART_NAME" "CAP_0402LF-1000PF,50V,10%,X7R,A"
					( Origin gPackager )
				)
				( objectStatus "C4D20" )
				( pin "a"
					( attribute "PN" "1"
						( Origin gPackager )
					)
					( objectStatus "C4D20.1" )
				)
				( pin "b"
					( attribute "PN" "2"
						( Origin gPackager )
					)
					( objectStatus "C4D20.2" )
				)
			)
			( gate "@baseboard_fab2_lib.baseboard_fab2(sch_1):page201_i64"
				( attribute "CDS_LIB" "mstr_discrete"
					( Origin gPackager )
				)
				( attribute "CDS_LOCATION" "C4D29"
					( Origin gPackager )
				)
				( attribute "CDS_SEC" "1"
					( Origin gPackager )
				)
				( attribute "LOCATION" "C4D29"
					( Origin gFrontEnd )
				)
				( attribute "MATERIAL" "X7R"
					( Origin gFrontEnd )
				)
				( attribute "NO_XNET_CONNECTION" "1"
					( Origin gFrontEnd )
				)
				( attribute "PACK_TYPE" "0402LF"
					( Origin gFrontEnd )
				)
				( attribute "PART_NUMBER" "A36096-050"
					( Origin gFrontEnd )
				)
				( attribute "PHYS_PAGE" "201"
					( Origin gFrontEnd )
				)
				( attribute "ROOM" "PVCCIN_CPU0_VR"
					( Origin gFrontEnd )
				)
				( attribute "ROT" "0"
					( Origin gFrontEnd )
				)
				( attribute "SEC" "1"
					( Origin gFrontEnd )
				)
				( attribute "SEC_TYPE" "0402LF"
					( Origin gFrontEnd )
				)
				( attribute "TOLERANCE" "10%"
					( Origin gFrontEnd )
				)
				( attribute "VALUE" "220PF"
					( Origin gFrontEnd )
				)
				( attribute "VER" "1"
					( Origin gFrontEnd )
				)
				( attribute "VOLTAGE" "50V"
					( Units "uVoltage" "V" 1.000000)
					( Origin gFrontEnd )
				)
				( attribute "XY" "(-5550,2075)"
					( Origin gFrontEnd )
				)
				( attribute "CHIPS_PART_NAME" "CAP"
					( Origin gPackager )
				)
				( attribute "CDS_PART_NAME" "CAP_0402LF-220PF,50V,10%,X7R,AA"
					( Origin gPackager )
				)
				( objectStatus "C4D29" )
				( pin "a"
					( attribute "PN" "1"
						( Origin gPackager )
					)
					( objectStatus "C4D29.1" )
				)
				( pin "b"
					( attribute "PN" "2"
						( Origin gPackager )
					)
					( objectStatus "C4D29.2" )
				)
			)
			( gate "@baseboard_fab2_lib.baseboard_fab2(sch_1):page201_i66"
				( attribute "CDS_LIB" "mstr_discrete"
					( Origin gPackager )
				)
				( attribute "CDS_LOCATION" "C4D17"
					( Origin gPackager )
				)
				( attribute "CDS_SEC" "1"
					( Origin gPackager )
				)
				( attribute "LOCATION" "C4D17"
					( Origin gFrontEnd )
				)
				( attribute "MATERIAL" "X7R"
					( Origin gFrontEnd )
				)
				( attribute "PACK_TYPE" "0402LF"
					( Origin gFrontEnd )
				)
				( attribute "PART_NUMBER" "A36096-050"
					( Origin gFrontEnd )
				)
				( attribute "PHYS_PAGE" "201"
					( Origin gFrontEnd )
				)
				( attribute "ROOM" "PVCCIN_CPU0_VR"
					( Origin gFrontEnd )
				)
				( attribute "ROT" "0"
					( Origin gFrontEnd )
				)
				( attribute "SEC" "1"
					( Origin gFrontEnd )
				)
				( attribute "SEC_TYPE" "0402LF"
					( Origin gFrontEnd )
				)
				( attribute "TOLERANCE" "10%"
					( Origin gFrontEnd )
				)
				( attribute "VALUE" "220PF"
					( Origin gFrontEnd )
				)
				( attribute "VER" "1"
					( Origin gFrontEnd )
				)
				( attribute "VOLTAGE" "50V"
					( Units "uVoltage" "V" 1.000000)
					( Origin gFrontEnd )
				)
				( attribute "XY" "(-5450,1275)"
					( Origin gFrontEnd )
				)
				( attribute "CHIPS_PART_NAME" "CAP"
					( Origin gPackager )
				)
				( attribute "CDS_PART_NAME" "CAP_0402LF-220PF,50V,10%,X7R,AA"
					( Origin gPackager )
				)
				( objectStatus "C4D17" )
				( pin "a"
					( attribute "PN" "1"
						( Origin gPackager )
					)
					( objectStatus "C4D17.1" )
				)
				( pin "b"
					( attribute "PN" "2"
						( Origin gPackager )
					)
					( objectStatus "C4D17.2" )
				)
			)
			( gate "@baseboard_fab2_lib.baseboard_fab2(sch_1):page201_i68"
				( attribute "CDS_LIB" "mstr_discrete"
					( Origin gPackager )
				)
				( attribute "CDS_LOCATION" "C4D18"
					( Origin gPackager )
				)
				( attribute "CDS_SEC" "1"
					( Origin gPackager )
				)
				( attribute "LOCATION" "C4D18"
					( Origin gFrontEnd )
				)
				( attribute "MATERIAL" "X7R"
					( Origin gFrontEnd )
				)
				( attribute "PACK_TYPE" "0402LF"
					( Origin gFrontEnd )
				)
				( attribute "PART_NUMBER" "A36096-050"
					( Origin gFrontEnd )
				)
				( attribute "PHYS_PAGE" "201"
					( Origin gFrontEnd )
				)
				( attribute "ROOM" "PVCCIN_CPU0_VR"
					( Origin gFrontEnd )
				)
				( attribute "ROT" "2"
					( Origin gFrontEnd )
				)
				( attribute "SEC" "1"
					( Origin gFrontEnd )
				)
				( attribute "SEC_TYPE" "0402LF"
					( Origin gFrontEnd )
				)
				( attribute "TOLERANCE" "10%"
					( Origin gFrontEnd )
				)
				( attribute "VALUE" "220PF"
					( Origin gFrontEnd )
				)
				( attribute "VER" "1"
					( Origin gFrontEnd )
				)
				( attribute "VOLTAGE" "50V"
					( Units "uVoltage" "V" 1.000000)
					( Origin gFrontEnd )
				)
				( attribute "XY" "(-5125,1000)"
					( Origin gFrontEnd )
				)
				( attribute "CHIPS_PART_NAME" "CAP"
					( Origin gPackager )
				)
				( attribute "CDS_PART_NAME" "CAP_0402LF-220PF,50V,10%,X7R,AA"
					( Origin gPackager )
				)
				( objectStatus "C4D18" )
				( pin "a"
					( attribute "PN" "1"
						( Origin gPackager )
					)
					( objectStatus "C4D18.1" )
				)
				( pin "b"
					( attribute "PN" "2"
						( Origin gPackager )
					)
					( objectStatus "C4D18.2" )
				)
			)
			( gate "@baseboard_fab2_lib.baseboard_fab2(sch_1):page201_i70"
				( attribute "CDS_LIB" "mstr_discrete"
					( Origin gPackager )
				)
				( attribute "CDS_LOCATION" "C4D45"
					( Origin gPackager )
				)
				( attribute "CDS_SEC" "1"
					( Origin gPackager )
				)
				( attribute "LOCATION" "C4D45"
					( Origin gFrontEnd )
				)
				( attribute "MATERIAL" "X7R"
					( Origin gFrontEnd )
				)
				( attribute "NO_XNET_CONNECTION" "1"
					( Origin gFrontEnd )
				)
				( attribute "PACK_TYPE" "0402LF"
					( Origin gFrontEnd )
				)
				( attribute "PART_NUMBER" "A36096-050"
					( Origin gFrontEnd )
				)
				( attribute "PHYS_PAGE" "201"
					( Origin gFrontEnd )
				)
				( attribute "ROOM" "PVCCIN_CPU0_VR"
					( Origin gFrontEnd )
				)
				( attribute "ROT" "0"
					( Origin gFrontEnd )
				)
				( attribute "SEC" "1"
					( Origin gFrontEnd )
				)
				( attribute "SEC_TYPE" "0402LF"
					( Origin gFrontEnd )
				)
				( attribute "TOLERANCE" "10%"
					( Origin gFrontEnd )
				)
				( attribute "VALUE" "220PF"
					( Origin gFrontEnd )
				)
				( attribute "VER" "1"
					( Origin gFrontEnd )
				)
				( attribute "VOLTAGE" "50V"
					( Units "uVoltage" "V" 1.000000)
					( Origin gFrontEnd )
				)
				( attribute "XY" "(-6450,2375)"
					( Origin gFrontEnd )
				)
				( attribute "CHIPS_PART_NAME" "CAP"
					( Origin gPackager )
				)
				( attribute "CDS_PART_NAME" "CAP_0402LF-220PF,50V,10%,X7R,AA"
					( Origin gPackager )
				)
				( objectStatus "C4D45" )
				( pin "a"
					( attribute "PN" "1"
						( Origin gPackager )
					)
					( objectStatus "C4D45.1" )
				)
				( pin "b"
					( attribute "PN" "2"
						( Origin gPackager )
					)
					( objectStatus "C4D45.2" )
				)
			)
			( gate "@baseboard_fab2_lib.baseboard_fab2(sch_1):page201_i98"
				( attribute "CDS_LIB" "mstr_discrete"
					( Origin gPackager )
				)
				( attribute "CDS_LOCATION" "R4D66"
					( Origin gPackager )
				)
				( attribute "CDS_SEC" "1"
					( Origin gPackager )
				)
				( attribute "LOCATION" "R4D66"
					( Origin gFrontEnd )
				)
				( attribute "MATERIAL" "CHIP"
					( Origin gFrontEnd )
				)
				( attribute "PACK_TYPE" "0402"
					( Origin gFrontEnd )
				)
				( attribute "PART_NUMBER" "G21497-005"
					( Origin gFrontEnd )
				)
				( attribute "PHYS_PAGE" "201"
					( Origin gFrontEnd )
				)
				( attribute "ROOM" "PVCCIN_CPU0_VR"
					( Origin gFrontEnd )
				)
				( attribute "ROT" "0"
					( Origin gFrontEnd )
				)
				( attribute "SEC" "1"
					( Origin gFrontEnd )
				)
				( attribute "SEC_TYPE" "0402"
					( Origin gFrontEnd )
				)
				( attribute "TOLERANCE" "5%"
					( Origin gFrontEnd )
				)
				( attribute "VALUE" "0.0"
					( Origin gFrontEnd )
				)
				( attribute "VER" "1"
					( Origin gFrontEnd )
				)
				( attribute "WATTAGE" "1/16W"
					( Origin gFrontEnd )
				)
				( attribute "XY" "(-2400,2725)"
					( Origin gFrontEnd )
				)
				( attribute "CHIPS_PART_NAME" "RES"
					( Origin gPackager )
				)
				( attribute "CDS_PART_NAME" "RES_0402-0.0,5%,1/16W,CHIP,G21A"
					( Origin gPackager )
				)
				( objectStatus "R4D66" )
				( pin "a"
					( attribute "PN" "1"
						( Origin gPackager )
					)
					( objectStatus "R4D66.1" )
				)
				( pin "b"
					( attribute "PN" "2"
						( Origin gPackager )
					)
					( objectStatus "R4D66.2" )
				)
			)
			( gate "@baseboard_fab2_lib.baseboard_fab2(sch_1):page201_i102"
				( attribute "CDS_LIB" "mstr_discrete"
					( Origin gPackager )
				)
				( attribute "CDS_LOCATION" "R6P32"
					( Origin gPackager )
				)
				( attribute "CDS_SEC" "1"
					( Origin gPackager )
				)
				( attribute "LOCATION" "R6P32"
					( Origin gFrontEnd )
				)
				( attribute "MATERIAL" "EMPTY"
					( Origin gFrontEnd )
				)
				( attribute "PACK_TYPE" "0402"
					( Origin gFrontEnd )
				)
				( attribute "PART_NUMBER" "G21796-001"
					( Origin gFrontEnd )
				)
				( attribute "PHYS_PAGE" "201"
					( Origin gFrontEnd )
				)
				( attribute "ROOM" "PVCCIN_CPU0_VR"
					( Origin gFrontEnd )
				)
				( attribute "ROT" "0"
					( Origin gFrontEnd )
				)
				( attribute "SEC" "1"
					( Origin gPackager )
				)
				( attribute "TOLERANCE" "1%"
					( Origin gFrontEnd )
				)
				( attribute "VALUE" "2.0K"
					( Origin gFrontEnd )
				)
				( attribute "VER" "2"
					( Origin gFrontEnd )
				)
				( attribute "WATTAGE" "1/16W"
					( Origin gFrontEnd )
				)
				( attribute "XY" "(-1100,2000)"
					( Origin gFrontEnd )
				)
				( attribute "CHIPS_PART_NAME" "RES"
					( Origin gPackager )
				)
				( attribute "CDS_PART_NAME" "RES_0402-2.0K,1%,1/16W,EMPTY,GA"
					( Origin gPackager )
				)
				( objectStatus "R6P32" )
				( pin "a"
					( attribute "PN" "1"
						( Origin gPackager )
					)
					( objectStatus "R6P32.1" )
				)
				( pin "b"
					( attribute "PN" "2"
						( Origin gPackager )
					)
					( objectStatus "R6P32.2" )
				)
			)
			( gate "@baseboard_fab2_lib.baseboard_fab2(sch_1):page201_i103"
				( attribute "CDS_LIB" "mstr_discrete"
					( Origin gPackager )
				)
				( attribute "CDS_LOCATION" "R6P37"
					( Origin gPackager )
				)
				( attribute "CDS_SEC" "1"
					( Origin gPackager )
				)
				( attribute "LOCATION" "R6P37"
					( Origin gFrontEnd )
				)
				( attribute "MATERIAL" "EMPTY"
					( Origin gFrontEnd )
				)
				( attribute "PACK_TYPE" "0402"
					( Origin gFrontEnd )
				)
				( attribute "PART_NUMBER" "G21796-001"
					( Origin gFrontEnd )
				)
				( attribute "PHYS_PAGE" "201"
					( Origin gFrontEnd )
				)
				( attribute "ROOM" "PVCCIN_CPU0_VR"
					( Origin gFrontEnd )
				)
				( attribute "ROT" "0"
					( Origin gFrontEnd )
				)
				( attribute "SEC" "1"
					( Origin gPackager )
				)
				( attribute "TOLERANCE" "1%"
					( Origin gFrontEnd )
				)
				( attribute "VALUE" "2.0K"
					( Origin gFrontEnd )
				)
				( attribute "VER" "2"
					( Origin gFrontEnd )
				)
				( attribute "WATTAGE" "1/16W"
					( Origin gFrontEnd )
				)
				( attribute "XY" "(-850,2000)"
					( Origin gFrontEnd )
				)
				( attribute "CHIPS_PART_NAME" "RES"
					( Origin gPackager )
				)
				( attribute "CDS_PART_NAME" "RES_0402-2.0K,1%,1/16W,EMPTY,GA"
					( Origin gPackager )
				)
				( objectStatus "R6P37" )
				( pin "a"
					( attribute "PN" "1"
						( Origin gPackager )
					)
					( objectStatus "R6P37.1" )
				)
				( pin "b"
					( attribute "PN" "2"
						( Origin gPackager )
					)
					( objectStatus "R6P37.2" )
				)
			)
			( gate "@baseboard_fab2_lib.baseboard_fab2(sch_1):page201_i109"
				( attribute "CDS_LIB" "mstr_discrete"
					( Origin gPackager )
				)
				( attribute "CDS_LOCATION" "R4E8"
					( Origin gPackager )
				)
				( attribute "CDS_SEC" "1"
					( Origin gPackager )
				)
				( attribute "LOCATION" "R4E8"
					( Origin gFrontEnd )
				)
				( attribute "MATERIAL" "CHIP"
					( Origin gFrontEnd )
				)
				( attribute "NO_XNET_CONNECTION" "1"
					( Origin gFrontEnd )
				)
				( attribute "PACK_TYPE" "0402"
					( Origin gFrontEnd )
				)
				( attribute "PART_NUMBER" "G21796-066"
					( Origin gFrontEnd )
				)
				( attribute "PHYS_PAGE" "201"
					( Origin gFrontEnd )
				)
				( attribute "ROOM" "PVCCIN_CPU0_VR"
					( Origin gFrontEnd )
				)
				( attribute "ROT" "0"
					( Origin gFrontEnd )
				)
				( attribute "SEC" "1"
					( Origin gFrontEnd )
				)
				( attribute "SEC_TYPE" "0402"
					( Origin gFrontEnd )
				)
				( attribute "TOLERANCE" "1%"
					( Origin gFrontEnd )
				)
				( attribute "VALUE" "10.0"
					( Origin gFrontEnd )
				)
				( attribute "VER" "1"
					( Origin gFrontEnd )
				)
				( attribute "WATTAGE" "1/16W"
					( Origin gFrontEnd )
				)
				( attribute "XY" "(-6675,2525)"
					( Origin gFrontEnd )
				)
				( attribute "CHIPS_PART_NAME" "RES"
					( Origin gPackager )
				)
				( attribute "CDS_PART_NAME" "RES_0402-10.0,1%,1/16W,CHIP,G2A"
					( Origin gPackager )
				)
				( objectStatus "R4E8" )
				( pin "a"
					( attribute "PN" "1"
						( Origin gPackager )
					)
					( objectStatus "R4E8.1" )
				)
				( pin "b"
					( attribute "PN" "2"
						( Origin gPackager )
					)
					( objectStatus "R4E8.2" )
				)
			)
			( gate "@baseboard_fab2_lib.baseboard_fab2(sch_1):page201_i110"
				( attribute "CDS_LIB" "mstr_discrete"
					( Origin gPackager )
				)
				( attribute "CDS_LOCATION" "R4D39"
					( Origin gPackager )
				)
				( attribute "CDS_SEC" "1"
					( Origin gPackager )
				)
				( attribute "LOCATION" "R4D39"
					( Origin gFrontEnd )
				)
				( attribute "MATERIAL" "CHIP"
					( Origin gFrontEnd )
				)
				( attribute "NO_XNET_CONNECTION" "1"
					( Origin gFrontEnd )
				)
				( attribute "PACK_TYPE" "0402"
					( Origin gFrontEnd )
				)
				( attribute "PART_NUMBER" "G21796-066"
					( Origin gFrontEnd )
				)
				( attribute "PHYS_PAGE" "201"
					( Origin gFrontEnd )
				)
				( attribute "ROOM" "PVCCIN_CPU0_VR"
					( Origin gFrontEnd )
				)
				( attribute "ROT" "0"
					( Origin gFrontEnd )
				)
				( attribute "SEC" "1"
					( Origin gFrontEnd )
				)
				( attribute "SEC_TYPE" "0402"
					( Origin gFrontEnd )
				)
				( attribute "TOLERANCE" "1%"
					( Origin gFrontEnd )
				)
				( attribute "VALUE" "10.0"
					( Origin gFrontEnd )
				)
				( attribute "VER" "1"
					( Origin gFrontEnd )
				)
				( attribute "WATTAGE" "1/16W"
					( Origin gFrontEnd )
				)
				( attribute "XY" "(-6250,2075)"
					( Origin gFrontEnd )
				)
				( attribute "CHIPS_PART_NAME" "RES"
					( Origin gPackager )
				)
				( attribute "CDS_PART_NAME" "RES_0402-10.0,1%,1/16W,CHIP,G2A"
					( Origin gPackager )
				)
				( objectStatus "R4D39" )
				( pin "a"
					( attribute "PN" "1"
						( Origin gPackager )
					)
					( objectStatus "R4D39.1" )
				)
				( pin "b"
					( attribute "PN" "2"
						( Origin gPackager )
					)
					( objectStatus "R4D39.2" )
				)
			)
			( gate "@baseboard_fab2_lib.baseboard_fab2(sch_1):page201_i111"
				( attribute "CDS_LIB" "mstr_discrete"
					( Origin gPackager )
				)
				( attribute "CDS_LOCATION" "R4E3"
					( Origin gPackager )
				)
				( attribute "CDS_SEC" "1"
					( Origin gPackager )
				)
				( attribute "LOCATION" "R4E3"
					( Origin gFrontEnd )
				)
				( attribute "MATERIAL" "CHIP"
					( Origin gFrontEnd )
				)
				( attribute "PACK_TYPE" "0402"
					( Origin gFrontEnd )
				)
				( attribute "PART_NUMBER" "G21796-026"
					( Origin gFrontEnd )
				)
				( attribute "PHYS_PAGE" "201"
					( Origin gFrontEnd )
				)
				( attribute "ROOM" "PVCCIN_CPU0_VR"
					( Origin gFrontEnd )
				)
				( attribute "ROT" "2"
					( Origin gFrontEnd )
				)
				( attribute "SEC" "1"
					( Origin gFrontEnd )
				)
				( attribute "SEC_TYPE" "0402"
					( Origin gFrontEnd )
				)
				( attribute "TOLERANCE" "1%"
					( Origin gFrontEnd )
				)
				( attribute "VALUE" "1.00K"
					( Origin gFrontEnd )
				)
				( attribute "VER" "2"
					( Origin gFrontEnd )
				)
				( attribute "WATTAGE" "1/16W"
					( Origin gFrontEnd )
				)
				( attribute "XY" "(-3050,4125)"
					( Origin gFrontEnd )
				)
				( attribute "CHIPS_PART_NAME" "RES"
					( Origin gPackager )
				)
				( attribute "CDS_PART_NAME" "RES_0402-1.00K,1%,1/16W,CHIP,GA"
					( Origin gPackager )
				)
				( objectStatus "R4E3" )
				( pin "a"
					( attribute "PN" "1"
						( Origin gPackager )
					)
					( objectStatus "R4E3.1" )
				)
				( pin "b"
					( attribute "PN" "2"
						( Origin gPackager )
					)
					( objectStatus "R4E3.2" )
				)
			)
			( gate "@baseboard_fab2_lib.baseboard_fab2(sch_1):page201_i116"
				( attribute "CDS_LIB" "mstr_discrete"
					( Origin gPackager )
				)
				( attribute "CDS_LOCATION" "R4E20"
					( Origin gPackager )
				)
				( attribute "CDS_SEC" "1"
					( Origin gPackager )
				)
				( attribute "LOCATION" "R4E20"
					( Origin gFrontEnd )
				)
				( attribute "MATERIAL" "EMPTY"
					( Origin gFrontEnd )
				)
				( attribute "PACK_TYPE" "0402"
					( Origin gFrontEnd )
				)
				( attribute "PART_NUMBER" "G21796-311"
					( Origin gFrontEnd )
				)
				( attribute "PHYS_PAGE" "201"
					( Origin gFrontEnd )
				)
				( attribute "ROOM" "PVCCIN_CPU0_VR"
					( Origin gFrontEnd )
				)
				( attribute "ROT" "0"
					( Origin gFrontEnd )
				)
				( attribute "SEC" "1"
					( Origin gFrontEnd )
				)
				( attribute "SEC_TYPE" "0402"
					( Origin gFrontEnd )
				)
				( attribute "TOLERANCE" "1.0%"
					( Origin gFrontEnd )
				)
				( attribute "VALUE" "2.26K"
					( Origin gFrontEnd )
				)
				( attribute "VER" "2"
					( Origin gFrontEnd )
				)
				( attribute "WATTAGE" "1/16W"
					( Origin gFrontEnd )
				)
				( attribute "XY" "(-1575,4200)"
					( Origin gFrontEnd )
				)
				( attribute "CHIPS_PART_NAME" "RES"
					( Origin gPackager )
				)
				( attribute "CDS_PART_NAME" "RES_0402-2.26K,1.0%,1/16W,EMPTA"
					( Origin gPackager )
				)
				( objectStatus "R4E20" )
				( pin "a"
					( attribute "PN" "1"
						( Origin gPackager )
					)
					( objectStatus "R4E20.1" )
				)
				( pin "b"
					( attribute "PN" "2"
						( Origin gPackager )
					)
					( objectStatus "R4E20.2" )
				)
			)
			( gate "@baseboard_fab2_lib.baseboard_fab2(sch_1):page201_i120"
				( attribute "CDS_LIB" "mstr_discrete"
					( Origin gPackager )
				)
				( attribute "CDS_LOCATION" "R6P27"
					( Origin gPackager )
				)
				( attribute "CDS_SEC" "1"
					( Origin gPackager )
				)
				( attribute "LOCATION" "R6P27"
					( Origin gFrontEnd )
				)
				( attribute "MATERIAL" "CHIP"
					( Origin gFrontEnd )
				)
				( attribute "PACK_TYPE" "0402"
					( Origin gFrontEnd )
				)
				( attribute "PART_NUMBER" "G21796-082"
					( Origin gFrontEnd )
				)
				( attribute "PHYS_PAGE" "201"
					( Origin gFrontEnd )
				)
				( attribute "ROOM" "PVCCIN_CPU0_VR"
					( Origin gFrontEnd )
				)
				( attribute "ROT" "0"
					( Origin gFrontEnd )
				)
				( attribute "SEC" "1"
					( Origin gFrontEnd )
				)
				( attribute "SEC_TYPE" "0402"
					( Origin gFrontEnd )
				)
				( attribute "TOLERANCE" "1%"
					( Origin gFrontEnd )
				)
				( attribute "VALUE" "4.02K"
					( Origin gFrontEnd )
				)
				( attribute "VER" "2"
					( Origin gFrontEnd )
				)
				( attribute "WATTAGE" "1/16W"
					( Origin gFrontEnd )
				)
				( attribute "XY" "(-4400,925)"
					( Origin gFrontEnd )
				)
				( attribute "CHIPS_PART_NAME" "RES"
					( Origin gPackager )
				)
				( attribute "CDS_PART_NAME" "RES_0402-4.02K,1%,1/16W,CHIP,GA"
					( Origin gPackager )
				)
				( objectStatus "R6P27" )
				( pin "a"
					( attribute "PN" "1"
						( Origin gPackager )
					)
					( objectStatus "R6P27.1" )
				)
				( pin "b"
					( attribute "PN" "2"
						( Origin gPackager )
					)
					( objectStatus "R6P27.2" )
				)
			)
			( gate "@baseboard_fab2_lib.baseboard_fab2(sch_1):page201_i121"
				( attribute "CDS_LIB" "mstr_discrete"
					( Origin gPackager )
				)
				( attribute "CDS_LOCATION" "R6P28"
					( Origin gPackager )
				)
				( attribute "CDS_SEC" "1"
					( Origin gPackager )
				)
				( attribute "LOCATION" "R6P28"
					( Origin gFrontEnd )
				)
				( attribute "MATERIAL" "CHIP"
					( Origin gFrontEnd )
				)
				( attribute "PACK_TYPE" "0402"
					( Origin gFrontEnd )
				)
				( attribute "PART_NUMBER" "G21796-082"
					( Origin gFrontEnd )
				)
				( attribute "PHYS_PAGE" "201"
					( Origin gFrontEnd )
				)
				( attribute "ROOM" "PVCCIN_CPU0_VR"
					( Origin gFrontEnd )
				)
				( attribute "ROT" "0"
					( Origin gFrontEnd )
				)
				( attribute "SEC" "1"
					( Origin gFrontEnd )
				)
				( attribute "SEC_TYPE" "0402"
					( Origin gFrontEnd )
				)
				( attribute "TOLERANCE" "1%"
					( Origin gFrontEnd )
				)
				( attribute "VALUE" "4.02K"
					( Origin gFrontEnd )
				)
				( attribute "VER" "2"
					( Origin gFrontEnd )
				)
				( attribute "WATTAGE" "1/16W"
					( Origin gFrontEnd )
				)
				( attribute "XY" "(-4725,900)"
					( Origin gFrontEnd )
				)
				( attribute "CHIPS_PART_NAME" "RES"
					( Origin gPackager )
				)
				( attribute "CDS_PART_NAME" "RES_0402-4.02K,1%,1/16W,CHIP,GA"
					( Origin gPackager )
				)
				( objectStatus "R6P28" )
				( pin "a"
					( attribute "PN" "1"
						( Origin gPackager )
					)
					( objectStatus "R6P28.1" )
				)
				( pin "b"
					( attribute "PN" "2"
						( Origin gPackager )
					)
					( objectStatus "R6P28.2" )
				)
			)
			( gate "@baseboard_fab2_lib.baseboard_fab2(sch_1):page201_i122"
				( attribute "BOM_COST" "SM_CONTROLLER"
					( Origin gFrontEnd )
				)
				( attribute "CDS_LIB" "mstr_conn"
					( Origin gPackager )
				)
				( attribute "CDS_LOCATION" "J8D4"
					( Origin gPackager )
				)
				( attribute "CDS_SEC" "1"
					( Origin gPackager )
				)
				( attribute "LOCATION" "J8D4"
					( Origin gFrontEnd )
				)
				( attribute "MATERIAL" "CONN"
					( Origin gFrontEnd )
				)
				( attribute "PACK_TYPE" "PIP"
					( Origin gFrontEnd )
				)
				( attribute "PART_NUMBER" "C95678-002"
					( Origin gFrontEnd )
				)
				( attribute "PHYS_PAGE" "201"
					( Origin gFrontEnd )
				)
				( attribute "ROOM" "SMBUS"
					( Origin gFrontEnd )
				)
				( attribute "ROT" "0"
					( Origin gFrontEnd )
				)
				( attribute "SEC" "1"
					( Origin gFrontEnd )
				)
				( attribute "SEC_TYPE" "PIP"
					( Origin gFrontEnd )
				)
				( attribute "VER" "1"
					( Origin gFrontEnd )
				)
				( attribute "XY" "(-3150,825)"
					( Origin gFrontEnd )
				)
				( attribute "CHIPS_PART_NAME" "CONN3_C95678002"
					( Origin gPackager )
				)
				( attribute "CDS_PART_NAME" "CONN3_C95678002_PIP-CONN,C9567A"
					( Origin gPackager )
				)
				( objectStatus "J8D4" )
				( pin "io1"
					( attribute "PN" "1"
						( Origin gPackager )
					)
					( objectStatus "J8D4.1" )
				)
				( pin "io2"
					( attribute "PN" "2"
						( Origin gPackager )
					)
					( objectStatus "J8D4.2" )
				)
				( pin "io3"
					( attribute "PN" "3"
						( Origin gPackager )
					)
					( objectStatus "J8D4.3" )
				)
			)
			( gate "@baseboard_fab2_lib.baseboard_fab2(sch_1):page201_i124"
				( attribute "CDS_LIB" "mstr_discrete"
					( Origin gPackager )
				)
				( attribute "CDS_LOCATION" "R4D63"
					( Origin gPackager )
				)
				( attribute "CDS_SEC" "1"
					( Origin gPackager )
				)
				( attribute "LOCATION" "R4D63"
					( Origin gFrontEnd )
				)
				( attribute "MATERIAL" "CHIP"
					( Origin gFrontEnd )
				)
				( attribute "PACK_TYPE" "0402"
					( Origin gFrontEnd )
				)
				( attribute "PART_NUMBER" "G21796-250"
					( Origin gFrontEnd )
				)
				( attribute "PHYS_PAGE" "201"
					( Origin gFrontEnd )
				)
				( attribute "ROOM" "PVCCIN_CPU0_VR"
					( Origin gFrontEnd )
				)
				( attribute "ROT" "0"
					( Origin gFrontEnd )
				)
				( attribute "SEC" "1"
					( Origin gPackager )
				)
				( attribute "TOLERANCE" "1.0%"
					( Origin gFrontEnd )
				)
				( attribute "VALUE" "22.1"
					( Origin gFrontEnd )
				)
				( attribute "VER" "1"
					( Origin gFrontEnd )
				)
				( attribute "WATTAGE" "1/16W"
					( Origin gFrontEnd )
				)
				( attribute "XY" "(-1125,3325)"
					( Origin gFrontEnd )
				)
				( attribute "CHIPS_PART_NAME" "RES"
					( Origin gPackager )
				)
				( attribute "CDS_PART_NAME" "RES_0402-22.1,1.0%,1/16W,CHIP,A"
					( Origin gPackager )
				)
				( objectStatus "R4D63" )
				( pin "a"
					( attribute "PN" "1"
						( Origin gPackager )
					)
					( objectStatus "R4D63.1" )
				)
				( pin "b"
					( attribute "PN" "2"
						( Origin gPackager )
					)
					( objectStatus "R4D63.2" )
				)
			)
			( gate "@baseboard_fab2_lib.baseboard_fab2(sch_1):page201_i125"
				( attribute "CDS_LIB" "mstr_discrete"
					( Origin gPackager )
				)
				( attribute "CDS_LOCATION" "C4D42"
					( Origin gPackager )
				)
				( attribute "CDS_SEC" "1"
					( Origin gPackager )
				)
				( attribute "LOCATION" "C4D42"
					( Origin gFrontEnd )
				)
				( attribute "MATERIAL" "X7R"
					( Origin gFrontEnd )
				)
				( attribute "PACK_TYPE" "0402LF"
					( Origin gFrontEnd )
				)
				( attribute "PART_NUMBER" "A36096-046"
					( Origin gFrontEnd )
				)
				( attribute "PHYS_PAGE" "201"
					( Origin gFrontEnd )
				)
				( attribute "ROOM" "PVCCIN_CPU0_VR"
					( Origin gFrontEnd )
				)
				( attribute "ROT" "0"
					( Origin gFrontEnd )
				)
				( attribute "SEC" "1"
					( Origin gFrontEnd )
				)
				( attribute "SEC_TYPE" "0402LF"
					( Origin gFrontEnd )
				)
				( attribute "TOLERANCE" "10%"
					( Origin gFrontEnd )
				)
				( attribute "VALUE" "1000PF"
					( Origin gFrontEnd )
				)
				( attribute "VER" "1"
					( Origin gFrontEnd )
				)
				( attribute "VOLTAGE" "50V"
					( Units "uVoltage" "V" 1.000000)
					( Origin gFrontEnd )
				)
				( attribute "XY" "(-1450,2075)"
					( Origin gFrontEnd )
				)
				( attribute "CHIPS_PART_NAME" "CAP"
					( Origin gPackager )
				)
				( attribute "CDS_PART_NAME" "CAP_0402LF-1000PF,50V,10%,X7R,A"
					( Origin gPackager )
				)
				( objectStatus "C4D42" )
				( pin "a"
					( attribute "PN" "1"
						( Origin gPackager )
					)
					( objectStatus "C4D42.1" )
				)
				( pin "b"
					( attribute "PN" "2"
						( Origin gPackager )
					)
					( objectStatus "C4D42.2" )
				)
			)
			( gate "@baseboard_fab2_lib.baseboard_fab2(sch_1):page201_i127"
				( attribute "CDS_LIB" "mstr_discrete"
					( Origin gPackager )
				)
				( attribute "CDS_LOCATION" "R4D65"
					( Origin gPackager )
				)
				( attribute "CDS_SEC" "1"
					( Origin gPackager )
				)
				( attribute "LOCATION" "R4D65"
					( Origin gFrontEnd )
				)
				( attribute "MATERIAL" "CHIP"
					( Origin gFrontEnd )
				)
				( attribute "PACK_TYPE" "0402"
					( Origin gFrontEnd )
				)
				( attribute "PART_NUMBER" "G21796-074"
					( Origin gFrontEnd )
				)
				( attribute "PHYS_PAGE" "201"
					( Origin gFrontEnd )
				)
				( attribute "ROT" "0"
					( Origin gFrontEnd )
				)
				( attribute "SEC" "1"
					( Origin gFrontEnd )
				)
				( attribute "SEC_TYPE" "0402"
					( Origin gFrontEnd )
				)
				( attribute "TOLERANCE" "1%"
					( Origin gFrontEnd )
				)
				( attribute "VALUE" "33.2"
					( Origin gFrontEnd )
				)
				( attribute "VER" "1"
					( Origin gFrontEnd )
				)
				( attribute "WATTAGE" "1/16W"
					( Origin gFrontEnd )
				)
				( attribute "XY" "(-1800,2675)"
					( Origin gFrontEnd )
				)
				( attribute "CHIPS_PART_NAME" "RES"
					( Origin gPackager )
				)
				( attribute "CDS_PART_NAME" "RES_0402-33.2,1%,1/16W,CHIP,G2A"
					( Origin gPackager )
				)
				( objectStatus "R4D65" )
				( pin "a"
					( attribute "PN" "1"
						( Origin gPackager )
					)
					( objectStatus "R4D65.1" )
				)
				( pin "b"
					( attribute "PN" "2"
						( Origin gPackager )
					)
					( objectStatus "R4D65.2" )
				)
			)
			( gate "@baseboard_fab2_lib.baseboard_fab2(sch_1):page201_i128"
				( attribute "CDS_LIB" "mstr_discrete"
					( Origin gPackager )
				)
				( attribute "CDS_LOCATION" "R6P45"
					( Origin gPackager )
				)
				( attribute "CDS_SEC" "1"
					( Origin gPackager )
				)
				( attribute "LOCATION" "R6P45"
					( Origin gFrontEnd )
				)
				( attribute "MATERIAL" "CHIP"
					( Origin gFrontEnd )
				)
				( attribute "PACK_TYPE" "0402"
					( Origin gFrontEnd )
				)
				( attribute "PART_NUMBER" "G21796-074"
					( Origin gFrontEnd )
				)
				( attribute "PHYS_PAGE" "201"
					( Origin gFrontEnd )
				)
				( attribute "ROT" "0"
					( Origin gFrontEnd )
				)
				( attribute "SEC" "1"
					( Origin gFrontEnd )
				)
				( attribute "SEC_TYPE" "0402"
					( Origin gFrontEnd )
				)
				( attribute "TOLERANCE" "1%"
					( Origin gFrontEnd )
				)
				( attribute "VALUE" "33.2"
					( Origin gFrontEnd )
				)
				( attribute "VER" "1"
					( Origin gFrontEnd )
				)
				( attribute "WATTAGE" "1/16W"
					( Origin gFrontEnd )
				)
				( attribute "XY" "(-2400,2975)"
					( Origin gFrontEnd )
				)
				( attribute "CHIPS_PART_NAME" "RES"
					( Origin gPackager )
				)
				( attribute "CDS_PART_NAME" "RES_0402-33.2,1%,1/16W,CHIP,G2A"
					( Origin gPackager )
				)
				( objectStatus "R6P45" )
				( pin "a"
					( attribute "PN" "1"
						( Origin gPackager )
					)
					( objectStatus "R6P45.1" )
				)
				( pin "b"
					( attribute "PN" "2"
						( Origin gPackager )
					)
					( objectStatus "R6P45.2" )
				)
			)
			( gate "@baseboard_fab2_lib.baseboard_fab2(sch_1):page201_i131"
				( attribute "CDS_LIB" "mstr_discrete"
					( Origin gPackager )
				)
				( attribute "CDS_LOCATION" "R6P18"
					( Origin gPackager )
				)
				( attribute "CDS_SEC" "1"
					( Origin gPackager )
				)
				( attribute "LOCATION" "R6P18"
					( Origin gFrontEnd )
				)
				( attribute "MATERIAL" "CHIP"
					( Origin gFrontEnd )
				)
				( attribute "PACK_TYPE" "0402"
					( Origin gFrontEnd )
				)
				( attribute "PART_NUMBER" "G21497-005"
					( Origin gFrontEnd )
				)
				( attribute "PHYS_PAGE" "201"
					( Origin gFrontEnd )
				)
				( attribute "ROOM" "PVCCIN_CPU0_VR"
					( Origin gFrontEnd )
				)
				( attribute "ROT" "0"
					( Origin gFrontEnd )
				)
				( attribute "SEC" "1"
					( Origin gFrontEnd )
				)
				( attribute "SEC_TYPE" "0402"
					( Origin gFrontEnd )
				)
				( attribute "TOLERANCE" "5%"
					( Origin gFrontEnd )
				)
				( attribute "VALUE" "0.0"
					( Origin gFrontEnd )
				)
				( attribute "VER" "1"
					( Origin gFrontEnd )
				)
				( attribute "WATTAGE" "1/16W"
					( Origin gFrontEnd )
				)
				( attribute "XY" "(-5100,2225)"
					( Origin gFrontEnd )
				)
				( attribute "CHIPS_PART_NAME" "RES"
					( Origin gPackager )
				)
				( attribute "CDS_PART_NAME" "RES_0402-0.0,5%,1/16W,CHIP,G21A"
					( Origin gPackager )
				)
				( objectStatus "R6P18" )
				( pin "a"
					( attribute "PN" "1"
						( Origin gPackager )
					)
					( objectStatus "R6P18.1" )
				)
				( pin "b"
					( attribute "PN" "2"
						( Origin gPackager )
					)
					( objectStatus "R6P18.2" )
				)
			)
			( gate "@baseboard_fab2_lib.baseboard_fab2(sch_1):page201_i132"
				( attribute "BOM_COST" "SM_CONTROLLER"
					( Origin gFrontEnd )
				)
				( attribute "CDS_LIB" "mstr_discrete"
					( Origin gPackager )
				)
				( attribute "CDS_LOCATION" "R6P16"
					( Origin gPackager )
				)
				( attribute "CDS_SEC" "1"
					( Origin gPackager )
				)
				( attribute "LOCATION" "R6P16"
					( Origin gFrontEnd )
				)
				( attribute "MATERIAL" "CHIP"
					( Origin gFrontEnd )
				)
				( attribute "PACK_TYPE" "0402"
					( Origin gFrontEnd )
				)
				( attribute "PART_NUMBER" "G21796-026"
					( Origin gFrontEnd )
				)
				( attribute "PHYS_PAGE" "201"
					( Origin gFrontEnd )
				)
				( attribute "ROOM" "BMC"
					( Origin gFrontEnd )
				)
				( attribute "ROT" "0"
					( Origin gFrontEnd )
				)
				( attribute "SEC" "1"
					( Origin gPackager )
				)
				( attribute "TOLERANCE" "1%"
					( Origin gFrontEnd )
				)
				( attribute "VALUE" "1.00K"
					( Origin gFrontEnd )
				)
				( attribute "VER" "2"
					( Origin gFrontEnd )
				)
				( attribute "WATTAGE" "1/16W"
					( Origin gFrontEnd )
				)
				( attribute "XY" "(-4775,4350)"
					( Origin gFrontEnd )
				)
				( attribute "CHIPS_PART_NAME" "RES"
					( Origin gPackager )
				)
				( attribute "CDS_PART_NAME" "RES_0402-1.00K,1%,1/16W,CHIP,GA"
					( Origin gPackager )
				)
				( objectStatus "R6P16" )
				( pin "a"
					( attribute "PN" "1"
						( Origin gPackager )
					)
					( objectStatus "R6P16.1" )
				)
				( pin "b"
					( attribute "PN" "2"
						( Origin gPackager )
					)
					( objectStatus "R6P16.2" )
				)
			)
			( gate "@baseboard_fab2_lib.baseboard_fab2(sch_1):page201_i139"
				( attribute "CDS_LIB" "mstr_discrete"
					( Origin gPackager )
				)
				( attribute "CDS_LOCATION" "R6P42"
					( Origin gPackager )
				)
				( attribute "CDS_SEC" "1"
					( Origin gPackager )
				)
				( attribute "LOCATION" "R6P42"
					( Origin gFrontEnd )
				)
				( attribute "MATERIAL" "CHIP"
					( Origin gFrontEnd )
				)
				( attribute "PACK_TYPE" "0402"
					( Origin gFrontEnd )
				)
				( attribute "PART_NUMBER" "G21497-005"
					( Origin gFrontEnd )
				)
				( attribute "PHYS_PAGE" "201"
					( Origin gFrontEnd )
				)
				( attribute "ROOM" "PVCCIN_CPU0_VR"
					( Origin gFrontEnd )
				)
				( attribute "ROT" "0"
					( Origin gFrontEnd )
				)
				( attribute "SEC" "1"
					( Origin gFrontEnd )
				)
				( attribute "SEC_TYPE" "0402"
					( Origin gFrontEnd )
				)
				( attribute "TOLERANCE" "5%"
					( Origin gFrontEnd )
				)
				( attribute "VALUE" "0.0"
					( Origin gFrontEnd )
				)
				( attribute "VER" "2"
					( Origin gFrontEnd )
				)
				( attribute "WATTAGE" "1/16W"
					( Origin gFrontEnd )
				)
				( attribute "XY" "(-6475,3625)"
					( Origin gFrontEnd )
				)
				( attribute "CHIPS_PART_NAME" "RES"
					( Origin gPackager )
				)
				( attribute "CDS_PART_NAME" "RES_0402-0.0,5%,1/16W,CHIP,G21A"
					( Origin gPackager )
				)
				( objectStatus "R6P42" )
				( pin "a"
					( attribute "PN" "1"
						( Origin gPackager )
					)
					( objectStatus "R6P42.1" )
				)
				( pin "b"
					( attribute "PN" "2"
						( Origin gPackager )
					)
					( objectStatus "R6P42.2" )
				)
			)
			( gate "@baseboard_fab2_lib.baseboard_fab2(sch_1):page201_i147"
				( attribute "CDS_LIB" "mstr_discrete"
					( Origin gPackager )
				)
				( attribute "CDS_LOCATION" "R6P38"
					( Origin gPackager )
				)
				( attribute "CDS_SEC" "1"
					( Origin gPackager )
				)
				( attribute "LOCATION" "R6P38"
					( Origin gFrontEnd )
				)
				( attribute "MATERIAL" "CHIP"
					( Origin gFrontEnd )
				)
				( attribute "PACK_TYPE" "0402"
					( Origin gFrontEnd )
				)
				( attribute "PART_NUMBER" "G21497-005"
					( Origin gFrontEnd )
				)
				( attribute "PHYS_PAGE" "201"
					( Origin gFrontEnd )
				)
				( attribute "ROOM" "PVCCIN_CPU0_VR"
					( Origin gFrontEnd )
				)
				( attribute "ROT" "0"
					( Origin gFrontEnd )
				)
				( attribute "SEC" "1"
					( Origin gFrontEnd )
				)
				( attribute "SEC_TYPE" "0402"
					( Origin gFrontEnd )
				)
				( attribute "TOLERANCE" "5%"
					( Origin gFrontEnd )
				)
				( attribute "VALUE" "0.0"
					( Origin gFrontEnd )
				)
				( attribute "VER" "2"
					( Origin gFrontEnd )
				)
				( attribute "WATTAGE" "1/16W"
					( Origin gFrontEnd )
				)
				( attribute "XY" "(-6000,3625)"
					( Origin gFrontEnd )
				)
				( attribute "CHIPS_PART_NAME" "RES"
					( Origin gPackager )
				)
				( attribute "CDS_PART_NAME" "RES_0402-0.0,5%,1/16W,CHIP,G21A"
					( Origin gPackager )
				)
				( objectStatus "R6P38" )
				( pin "a"
					( attribute "PN" "1"
						( Origin gPackager )
					)
					( objectStatus "R6P38.1" )
				)
				( pin "b"
					( attribute "PN" "2"
						( Origin gPackager )
					)
					( objectStatus "R6P38.2" )
				)
			)
			( gate "@baseboard_fab2_lib.baseboard_fab2(sch_1):page201_i148"
				( attribute "CDS_LIB" "mstr_discrete"
					( Origin gPackager )
				)
				( attribute "CDS_LOCATION" "R6P34"
					( Origin gPackager )
				)
				( attribute "CDS_SEC" "1"
					( Origin gPackager )
				)
				( attribute "LOCATION" "R6P34"
					( Origin gFrontEnd )
				)
				( attribute "MATERIAL" "CHIP"
					( Origin gFrontEnd )
				)
				( attribute "PACK_TYPE" "0402"
					( Origin gFrontEnd )
				)
				( attribute "PART_NUMBER" "G21497-005"
					( Origin gFrontEnd )
				)
				( attribute "PHYS_PAGE" "201"
					( Origin gFrontEnd )
				)
				( attribute "ROOM" "PVCCIN_CPU0_VR"
					( Origin gFrontEnd )
				)
				( attribute "ROT" "0"
					( Origin gFrontEnd )
				)
				( attribute "SEC" "1"
					( Origin gFrontEnd )
				)
				( attribute "SEC_TYPE" "0402"
					( Origin gFrontEnd )
				)
				( attribute "TOLERANCE" "5%"
					( Origin gFrontEnd )
				)
				( attribute "VALUE" "0.0"
					( Origin gFrontEnd )
				)
				( attribute "VER" "2"
					( Origin gFrontEnd )
				)
				( attribute "WATTAGE" "1/16W"
					( Origin gFrontEnd )
				)
				( attribute "XY" "(-5575,3625)"
					( Origin gFrontEnd )
				)
				( attribute "CHIPS_PART_NAME" "RES"
					( Origin gPackager )
				)
				( attribute "CDS_PART_NAME" "RES_0402-0.0,5%,1/16W,CHIP,G21A"
					( Origin gPackager )
				)
				( objectStatus "R6P34" )
				( pin "a"
					( attribute "PN" "1"
						( Origin gPackager )
					)
					( objectStatus "R6P34.1" )
				)
				( pin "b"
					( attribute "PN" "2"
						( Origin gPackager )
					)
					( objectStatus "R6P34.2" )
				)
			)
			( gate "@baseboard_fab2_lib.baseboard_fab2(sch_1):page201_i149"
				( attribute "CDS_LIB" "mstr_discrete"
					( Origin gPackager )
				)
				( attribute "CDS_LOCATION" "R6P30"
					( Origin gPackager )
				)
				( attribute "CDS_SEC" "1"
					( Origin gPackager )
				)
				( attribute "LOCATION" "R6P30"
					( Origin gFrontEnd )
				)
				( attribute "MATERIAL" "CHIP"
					( Origin gFrontEnd )
				)
				( attribute "PACK_TYPE" "0402"
					( Origin gFrontEnd )
				)
				( attribute "PART_NUMBER" "G21497-005"
					( Origin gFrontEnd )
				)
				( attribute "PHYS_PAGE" "201"
					( Origin gFrontEnd )
				)
				( attribute "ROOM" "PVCCIN_CPU0_VR"
					( Origin gFrontEnd )
				)
				( attribute "ROT" "0"
					( Origin gFrontEnd )
				)
				( attribute "SEC" "1"
					( Origin gFrontEnd )
				)
				( attribute "SEC_TYPE" "0402"
					( Origin gFrontEnd )
				)
				( attribute "TOLERANCE" "5%"
					( Origin gFrontEnd )
				)
				( attribute "VALUE" "0.0"
					( Origin gFrontEnd )
				)
				( attribute "VER" "2"
					( Origin gFrontEnd )
				)
				( attribute "WATTAGE" "1/16W"
					( Origin gFrontEnd )
				)
				( attribute "XY" "(-5175,3625)"
					( Origin gFrontEnd )
				)
				( attribute "CHIPS_PART_NAME" "RES"
					( Origin gPackager )
				)
				( attribute "CDS_PART_NAME" "RES_0402-0.0,5%,1/16W,CHIP,G21A"
					( Origin gPackager )
				)
				( objectStatus "R6P30" )
				( pin "a"
					( attribute "PN" "1"
						( Origin gPackager )
					)
					( objectStatus "R6P30.1" )
				)
				( pin "b"
					( attribute "PN" "2"
						( Origin gPackager )
					)
					( objectStatus "R6P30.2" )
				)
			)
			( gate "@baseboard_fab2_lib.baseboard_fab2(sch_1):page201_i150"
				( attribute "CDS_LIB" "mstr_discrete"
					( Origin gPackager )
				)
				( attribute "CDS_LOCATION" "R6P43"
					( Origin gPackager )
				)
				( attribute "CDS_SEC" "1"
					( Origin gPackager )
				)
				( attribute "LOCATION" "R6P43"
					( Origin gFrontEnd )
				)
				( attribute "MATERIAL" "CHIP"
					( Origin gFrontEnd )
				)
				( attribute "PACK_TYPE" "0402"
					( Origin gFrontEnd )
				)
				( attribute "PART_NUMBER" "G21497-005"
					( Origin gFrontEnd )
				)
				( attribute "PHYS_PAGE" "201"
					( Origin gFrontEnd )
				)
				( attribute "ROOM" "PVCCIN_CPU0_VR"
					( Origin gFrontEnd )
				)
				( attribute "ROT" "0"
					( Origin gFrontEnd )
				)
				( attribute "SEC" "1"
					( Origin gFrontEnd )
				)
				( attribute "SEC_TYPE" "0402"
					( Origin gFrontEnd )
				)
				( attribute "TOLERANCE" "5%"
					( Origin gFrontEnd )
				)
				( attribute "VALUE" "0.0"
					( Origin gFrontEnd )
				)
				( attribute "VER" "2"
					( Origin gFrontEnd )
				)
				( attribute "WATTAGE" "1/16W"
					( Origin gFrontEnd )
				)
				( attribute "XY" "(-6850,3625)"
					( Origin gFrontEnd )
				)
				( attribute "CHIPS_PART_NAME" "RES"
					( Origin gPackager )
				)
				( attribute "CDS_PART_NAME" "RES_0402-0.0,5%,1/16W,CHIP,G21A"
					( Origin gPackager )
				)
				( objectStatus "R6P43" )
				( pin "a"
					( attribute "PN" "1"
						( Origin gPackager )
					)
					( objectStatus "R6P43.1" )
				)
				( pin "b"
					( attribute "PN" "2"
						( Origin gPackager )
					)
					( objectStatus "R6P43.2" )
				)
			)
			( gate "@baseboard_fab2_lib.baseboard_fab2(sch_1):page201_i154"
				( attribute "CDS_LIB" "mstr_discrete"
					( Origin gPackager )
				)
				( attribute "CDS_LOCATION" "R6P29"
					( Origin gPackager )
				)
				( attribute "CDS_SEC" "1"
					( Origin gPackager )
				)
				( attribute "LOCATION" "R6P29"
					( Origin gFrontEnd )
				)
				( attribute "MATERIAL" "CHIP"
					( Origin gFrontEnd )
				)
				( attribute "PACK_TYPE" "0402"
					( Origin gFrontEnd )
				)
				( attribute "PART_NUMBER" "G21497-005"
					( Origin gFrontEnd )
				)
				( attribute "PHYS_PAGE" "201"
					( Origin gFrontEnd )
				)
				( attribute "ROOM" "PVCCIN_CPU0_VR"
					( Origin gFrontEnd )
				)
				( attribute "ROT" "0"
					( Origin gFrontEnd )
				)
				( attribute "SEC" "1"
					( Origin gFrontEnd )
				)
				( attribute "SEC_TYPE" "0402"
					( Origin gFrontEnd )
				)
				( attribute "TOLERANCE" "5%"
					( Origin gFrontEnd )
				)
				( attribute "VALUE" "0.0"
					( Origin gFrontEnd )
				)
				( attribute "VER" "1"
					( Origin gFrontEnd )
				)
				( attribute "WATTAGE" "1/16W"
					( Origin gFrontEnd )
				)
				( attribute "XY" "(-6375,1350)"
					( Origin gFrontEnd )
				)
				( attribute "CHIPS_PART_NAME" "RES"
					( Origin gPackager )
				)
				( attribute "CDS_PART_NAME" "RES_0402-0.0,5%,1/16W,CHIP,G21A"
					( Origin gPackager )
				)
				( objectStatus "R6P29" )
				( pin "a"
					( attribute "PN" "1"
						( Origin gPackager )
					)
					( objectStatus "R6P29.1" )
				)
				( pin "b"
					( attribute "PN" "2"
						( Origin gPackager )
					)
					( objectStatus "R6P29.2" )
				)
			)
			( gate "@baseboard_fab2_lib.baseboard_fab2(sch_1):page201_i155"
				( attribute "CDS_LIB" "mstr_controller"
					( Origin gPackager )
				)
				( attribute "CDS_LMAN_SYM_OUTLINE" "-400,900,400,-900"
					( Origin gPackager )
				)
				( attribute "CDS_LOCATION" "EU4D4"
					( Origin gPackager )
				)
				( attribute "CDS_SEC" "1"
					( Origin gPackager )
				)
				( attribute "LOCATION" "EU4D4"
					( Origin gFrontEnd )
				)
				( attribute "MATERIAL" "IC"
					( Origin gFrontEnd )
				)
				( attribute "PACK_TYPE" "QFN"
					( Origin gFrontEnd )
				)
				( attribute "PART_NUMBER" "H79206-001"
					( Origin gFrontEnd )
				)
				( attribute "PHYS_PAGE" "201"
					( Origin gFrontEnd )
				)
				( attribute "ROT" "0"
					( Origin gFrontEnd )
				)
				( attribute "SEC" "1"
					( Origin gPackager )
				)
				( attribute "VER" "1"
					( Origin gFrontEnd )
				)
				( attribute "XY" "(-3800,2575)"
					( Origin gFrontEnd )
				)
				( attribute "CHIPS_PART_NAME" "PXE1610B"
					( Origin gPackager )
				)
				( attribute "CDS_PART_NAME" "PXE1610B_QFN-IC,H79206-001"
					( Origin gPackager )
				)
				( objectStatus "EU4D4" )
				( pin "airef1"
					( attribute "PN" "23"
						( Origin gPackager )
					)
					( objectStatus "EU4D4.23" )
				)
				( pin "airef2"
					( attribute "PN" "25"
						( Origin gPackager )
					)
					( objectStatus "EU4D4.25" )
				)
				( pin "airef3"
					( attribute "PN" "27"
						( Origin gPackager )
					)
					( objectStatus "EU4D4.27" )
				)
				( pin "airef4"
					( attribute "PN" "29"
						( Origin gPackager )
					)
					( objectStatus "EU4D4.29" )
				)
				( pin "airef5"
					( attribute "PN" "31"
						( Origin gPackager )
					)
					( objectStatus "EU4D4.31" )
				)
				( pin "airef6"
					( attribute "PN" "33"
						( Origin gPackager )
					)
					( objectStatus "EU4D4.33" )
				)
				( pin "aisen1"
					( attribute "PN" "24"
						( Origin gPackager )
					)
					( objectStatus "EU4D4.24" )
				)
				( pin "aisen2"
					( attribute "PN" "26"
						( Origin gPackager )
					)
					( objectStatus "EU4D4.26" )
				)
				( pin "aisen3"
					( attribute "PN" "28"
						( Origin gPackager )
					)
					( objectStatus "EU4D4.28" )
				)
				( pin "aisen4"
					( attribute "PN" "30"
						( Origin gPackager )
					)
					( objectStatus "EU4D4.30" )
				)
				( pin "aisen5"
					( attribute "PN" "32"
						( Origin gPackager )
					)
					( objectStatus "EU4D4.32" )
				)
				( pin "aisen6"
					( attribute "PN" "34"
						( Origin gPackager )
					)
					( objectStatus "EU4D4.34" )
				)
				( pin "apwm1"
					( attribute "PN" "7"
						( Origin gPackager )
					)
					( objectStatus "EU4D4.7" )
				)
				( pin "apwm2"
					( attribute "PN" "6"
						( Origin gPackager )
					)
					( objectStatus "EU4D4.6" )
				)
				( pin "apwm3"
					( attribute "PN" "5"
						( Origin gPackager )
					)
					( objectStatus "EU4D4.5" )
				)
				( pin "apwm4"
					( attribute "PN" "4"
						( Origin gPackager )
					)
					( objectStatus "EU4D4.4" )
				)
				( pin "apwm5"
					( attribute "PN" "3"
						( Origin gPackager )
					)
					( objectStatus "EU4D4.3" )
				)
				( pin "apwm6"
					( attribute "PN" "2"
						( Origin gPackager )
					)
					( objectStatus "EU4D4.2" )
				)
				( pin "atsen"
					( attribute "PN" "43"
						( Origin gPackager )
					)
					( objectStatus "EU4D4.43" )
				)
				( pin "avref"
					( attribute "PN" "22"
						( Origin gPackager )
					)
					( objectStatus "EU4D4.22" )
				)
				( pin "avren"
					( attribute "PN" "12"
						( Origin gPackager )
					)
					( objectStatus "EU4D4.12" )
				)
				( pin "avrrdy"
					( attribute "PN" "11"
						( Origin gPackager )
					)
					( objectStatus "EU4D4.11" )
				)
				( pin "avsen"
					( attribute "PN" "21"
						( Origin gPackager )
					)
					( objectStatus "EU4D4.21" )
				)
				( pin "biref1"
					( attribute "PN" "37"
						( Origin gPackager )
					)
					( objectStatus "EU4D4.37" )
				)
				( pin "bisen1"
					( attribute "PN" "38"
						( Origin gPackager )
					)
					( objectStatus "EU4D4.38" )
				)
				( pin "bpwm1"
					( attribute "PN" "1"
						( Origin gPackager )
					)
					( objectStatus "EU4D4.1" )
				)
				( pin "btsen"
					( attribute "PN" "42"
						( Origin gPackager )
					)
					( objectStatus "EU4D4.42" )
				)
				( pin "bvref"
					( attribute "PN" "36"
						( Origin gPackager )
					)
					( objectStatus "EU4D4.36" )
				)
				( pin "bvsen"
					( attribute "PN" "35"
						( Origin gPackager )
					)
					( objectStatus "EU4D4.35" )
				)
				( pin "iinsen"
					( attribute "PN" "46"
						( Origin gPackager )
					)
					( objectStatus "EU4D4.46" )
				)
				( pin "mp0"
					( attribute "PN" "15"
						( Origin gPackager )
					)
					( objectStatus "EU4D4.15" )
				)
				( pin "mp1"
					( attribute "PN" "16"
						( Origin gPackager )
					)
					( objectStatus "EU4D4.16" )
				)
				( pin "mp2"
					( attribute "PN" "20"
						( Origin gPackager )
					)
					( objectStatus "EU4D4.20" )
				)
				( pin "mp3"
					( attribute "PN" "39"
						( Origin gPackager )
					)
					( objectStatus "EU4D4.39" )
				)
				( pin "mp4"
					( attribute "PN" "40"
						( Origin gPackager )
					)
					( objectStatus "EU4D4.40" )
				)
				( pin "pinalrt_n"
					( attribute "PN" "14"
						( Origin gPackager )
					)
					( objectStatus "EU4D4.14" )
				)
				( pin "reset_n"
					( attribute "PN" "10"
						( Origin gPackager )
					)
					( objectStatus "EU4D4.10" )
				)
				( pin "scl"
					( attribute "PN" "9"
						( Origin gPackager )
					)
					( objectStatus "EU4D4.9" )
				)
				( pin "sda"
					( attribute "PN" "8"
						( Origin gPackager )
					)
					( objectStatus "EU4D4.8" )
				)
				( pin "thpad"
					( attribute "PN" "49"
						( Origin gPackager )
					)
					( objectStatus "EU4D4.49" )
				)
				( pin "valrt_n"
					( attribute "PN" "19"
						( Origin gPackager )
					)
					( objectStatus "EU4D4.19" )
				)
				( pin "vclk"
					( attribute "PN" "17"
						( Origin gPackager )
					)
					( objectStatus "EU4D4.17" )
				)
				( pin "vd12"
					( attribute "PN" "48"
						( Origin gPackager )
					)
					( objectStatus "EU4D4.48" )
				)
				( pin "vdd"
					( attribute "PN" "47"
						( Origin gPackager )
					)
					( objectStatus "EU4D4.47" )
				)
				( pin "vdio"
					( attribute "PN" "18"
						( Origin gPackager )
					)
					( objectStatus "EU4D4.18" )
				)
				( pin "vinsen"
					( attribute "PN" "45"
						( Origin gPackager )
					)
					( objectStatus "EU4D4.45" )
				)
				( pin "vrhot_n"
					( attribute "PN" "13"
						( Origin gPackager )
					)
					( objectStatus "EU4D4.13" )
				)
				( pin "xaddr1"
					( attribute "PN" "44"
						( Origin gPackager )
					)
					( objectStatus "EU4D4.44" )
				)
				( pin "xaddr2"
					( attribute "PN" "41"
						( Origin gPackager )
					)
					( objectStatus "EU4D4.41" )
				)
			)
			( gate "@baseboard_fab2_lib.baseboard_fab2(sch_1):page202_i5"
				( attribute "CDS_LIB" "mstr_discrete"
					( Origin gPackager )
				)
				( attribute "CDS_LOCATION" "L4E1"
					( Origin gPackager )
				)
				( attribute "CDS_SEC" "1"
					( Origin gPackager )
				)
				( attribute "LOCATION" "L4E1"
					( Origin gFrontEnd )
				)
				( attribute "MATERIAL" "IND"
					( Origin gFrontEnd )
				)
				( attribute "PACK_TYPE" "SM"
					( Origin gFrontEnd )
				)
				( attribute "PART_NUMBER" "D92183-034"
					( Origin gFrontEnd )
				)
				( attribute "PHYS_PAGE" "202"
					( Origin gFrontEnd )
				)
				( attribute "ROOM" "PVCCIN_CPU0_PWR_VR"
					( Origin gFrontEnd )
				)
				( attribute "ROT" "0"
					( Origin gFrontEnd )
				)
				( attribute "SEC" "1"
					( Origin gPackager )
				)
				( attribute "VALUE" "0.12UH"
					( Origin gFrontEnd )
				)
				( attribute "VER" "1"
					( Origin gFrontEnd )
				)
				( attribute "XY" "(-1775,3500)"
					( Origin gFrontEnd )
				)
				( attribute "CHIPS_PART_NAME" "INDUCTOR"
					( Origin gPackager )
				)
				( attribute "CDS_PART_NAME" "INDUCTOR_SM-0.12UH,IND,D92183-A"
					( Origin gPackager )
				)
				( objectStatus "L4E1" )
				( pin "ina"
					( attribute "PN" "1"
						( Origin gPackager )
					)
					( objectStatus "L4E1.1" )
				)
				( pin "inb"
					( attribute "PN" "2"
						( Origin gPackager )
					)
					( objectStatus "L4E1.2" )
				)
			)
			( gate "@baseboard_fab2_lib.baseboard_fab2(sch_1):page202_i9"
				( attribute "BOM_COST" "PROC_VRD_VCCIN_CPU0"
					( Origin gFrontEnd )
				)
				( attribute "CDS_LIB" "dev_discrete"
					( Origin gPackager )
				)
				( attribute "CDS_LOCATION" "C6R7"
					( Origin gPackager )
				)
				( attribute "CDS_SEC" "1"
					( Origin gPackager )
				)
				( attribute "LOCATION" "C6R7"
					( Origin gFrontEnd )
				)
				( attribute "MATERIAL" "X6S"
					( Origin gFrontEnd )
				)
				( attribute "PACK_TYPE" "0603V"
					( Origin gFrontEnd )
				)
				( attribute "PART_NUMBER" "E15431-004"
					( Origin gFrontEnd )
				)
				( attribute "PHYS_PAGE" "202"
					( Origin gFrontEnd )
				)
				( attribute "ROOM" "PVCCIN_CPU0_PWR_VR"
					( Origin gFrontEnd )
				)
				( attribute "ROT" "0"
					( Origin gFrontEnd )
				)
				( attribute "SEC" "1"
					( Origin gFrontEnd )
				)
				( attribute "SEC_TYPE" "0603V"
					( Origin gFrontEnd )
				)
				( attribute "TOLERANCE" "20%"
					( Origin gFrontEnd )
				)
				( attribute "VALUE" "22.0UF"
					( Origin gFrontEnd )
				)
				( attribute "VER" "1"
					( Origin gFrontEnd )
				)
				( attribute "VOLTAGE" "4V"
					( Units "uVoltage" "V" 1.000000)
					( Origin gFrontEnd )
				)
				( attribute "XY" "(-1250,3300)"
					( Origin gFrontEnd )
				)
				( attribute "CHIPS_PART_NAME" "CAP_A"
					( Origin gPackager )
				)
				( attribute "CDS_PART_NAME" "CAP_A_0603V-22.0UF,4V,20%,X6S,A"
					( Origin gPackager )
				)
				( objectStatus "C6R7" )
				( pin "a"
					( attribute "PN" "1"
						( Origin gPackager )
					)
					( objectStatus "C6R7.1" )
				)
				( pin "b"
					( attribute "PN" "2"
						( Origin gPackager )
					)
					( objectStatus "C6R7.2" )
				)
			)
			( gate "@baseboard_fab2_lib.baseboard_fab2(sch_1):page202_i18"
				( attribute "CDS_LIB" "mstr_discrete"
					( Origin gPackager )
				)
				( attribute "CDS_LOCATION" "C4E5"
					( Origin gPackager )
				)
				( attribute "CDS_SEC" "1"
					( Origin gPackager )
				)
				( attribute "LOCATION" "C4E5"
					( Origin gFrontEnd )
				)
				( attribute "MATERIAL" "X7R"
					( Origin gFrontEnd )
				)
				( attribute "PACK_TYPE" "0402"
					( Origin gFrontEnd )
				)
				( attribute "PART_NUMBER" "A36096-155"
					( Origin gFrontEnd )
				)
				( attribute "PHYS_PAGE" "202"
					( Origin gFrontEnd )
				)
				( attribute "ROOM" "PVCCIN_CPU0_PWR_VR"
					( Origin gFrontEnd )
				)
				( attribute "ROT" "0"
					( Origin gFrontEnd )
				)
				( attribute "SEC" "1"
					( Origin gFrontEnd )
				)
				( attribute "SEC_TYPE" "0402"
					( Origin gFrontEnd )
				)
				( attribute "TOLERANCE" "10%"
					( Origin gFrontEnd )
				)
				( attribute "VALUE" "0.22UF"
					( Origin gFrontEnd )
				)
				( attribute "VER" "1"
					( Origin gFrontEnd )
				)
				( attribute "VOLTAGE" "16V"
					( Units "uVoltage" "V" 1.000000)
					( Origin gFrontEnd )
				)
				( attribute "XY" "(-5025,4125)"
					( Origin gFrontEnd )
				)
				( attribute "CHIPS_PART_NAME" "CAP"
					( Origin gPackager )
				)
				( attribute "CDS_PART_NAME" "CAP_0402-0.22UF,16V,10%,X7R,A3A"
					( Origin gPackager )
				)
				( objectStatus "C4E5" )
				( pin "a"
					( attribute "PN" "1"
						( Origin gPackager )
					)
					( objectStatus "C4E5.1" )
				)
				( pin "b"
					( attribute "PN" "2"
						( Origin gPackager )
					)
					( objectStatus "C4E5.2" )
				)
			)
			( gate "@baseboard_fab2_lib.baseboard_fab2(sch_1):page202_i19"
				( attribute "CDS_LIB" "dev_discrete"
					( Origin gPackager )
				)
				( attribute "CDS_LOCATION" "C4E6"
					( Origin gPackager )
				)
				( attribute "CDS_SEC" "1"
					( Origin gPackager )
				)
				( attribute "LOCATION" "C4E6"
					( Origin gFrontEnd )
				)
				( attribute "MATERIAL" "X6S"
					( Origin gFrontEnd )
				)
				( attribute "PACK_TYPE" "0402V"
					( Origin gFrontEnd )
				)
				( attribute "PART_NUMBER" "D97712-004"
					( Origin gFrontEnd )
				)
				( attribute "PHYS_PAGE" "202"
					( Origin gFrontEnd )
				)
				( attribute "ROOM" "PVCCIN_CPU0_PWR_VR"
					( Origin gFrontEnd )
				)
				( attribute "ROT" "2"
					( Origin gFrontEnd )
				)
				( attribute "SEC" "1"
					( Origin gFrontEnd )
				)
				( attribute "SEC_TYPE" "0402V"
					( Origin gFrontEnd )
				)
				( attribute "TOLERANCE" "10%"
					( Origin gFrontEnd )
				)
				( attribute "VALUE" "1.0UF"
					( Origin gFrontEnd )
				)
				( attribute "VER" "1"
					( Origin gFrontEnd )
				)
				( attribute "VOLTAGE" "6.3V"
					( Units "uVoltage" "V" 1.000000)
					( Origin gFrontEnd )
				)
				( attribute "XY" "(-5125,4125)"
					( Origin gFrontEnd )
				)
				( attribute "CHIPS_PART_NAME" "CAP_A"
					( Origin gPackager )
				)
				( attribute "CDS_PART_NAME" "CAP_A_0402V-1.0UF,6.3V,10%,X6SA"
					( Origin gPackager )
				)
				( objectStatus "C4E6" )
				( pin "a"
					( attribute "PN" "1"
						( Origin gPackager )
					)
					( objectStatus "C4E6.1" )
				)
				( pin "b"
					( attribute "PN" "2"
						( Origin gPackager )
					)
					( objectStatus "C4E6.2" )
				)
			)
			( gate "@baseboard_fab2_lib.baseboard_fab2(sch_1):page202_i22"
				( attribute "CDS_LIB" "mstr_discrete"
					( Origin gPackager )
				)
				( attribute "CDS_LOCATION" "C4E17"
					( Origin gPackager )
				)
				( attribute "CDS_SEC" "1"
					( Origin gPackager )
				)
				( attribute "LOCATION" "C4E17"
					( Origin gFrontEnd )
				)
				( attribute "MATERIAL" "X7R"
					( Origin gFrontEnd )
				)
				( attribute "NO_XNET_CONNECTION" "1"
					( Origin gFrontEnd )
				)
				( attribute "PACK_TYPE" "0402"
					( Origin gFrontEnd )
				)
				( attribute "PART_NUMBER" "A36096-104"
					( Origin gFrontEnd )
				)
				( attribute "PHYS_PAGE" "202"
					( Origin gFrontEnd )
				)
				( attribute "ROOM" "PVCCIN_CPU0_PWR_VR"
					( Origin gFrontEnd )
				)
				( attribute "ROT" "2"
					( Origin gFrontEnd )
				)
				( attribute "SEC" "1"
					( Origin gFrontEnd )
				)
				( attribute "SEC_TYPE" "0402"
					( Origin gFrontEnd )
				)
				( attribute "SPOF" "TRUE"
					( Origin gFrontEnd )
				)
				( attribute "TOLERANCE" "10%"
					( Origin gFrontEnd )
				)
				( attribute "VALUE" "0.220UF"
					( Origin gFrontEnd )
				)
				( attribute "VER" "1"
					( Origin gFrontEnd )
				)
				( attribute "VOLTAGE" "16V"
					( Units "uVoltage" "V" 1.000000)
					( Origin gFrontEnd )
				)
				( attribute "XY" "(-5850,3450)"
					( Origin gFrontEnd )
				)
				( attribute "CHIPS_PART_NAME" "CAP"
					( Origin gPackager )
				)
				( attribute "CDS_PART_NAME" "CAP_0402-0.220UF,16V,10%,X7R,AA"
					( Origin gPackager )
				)
				( objectStatus "C4E17" )
				( pin "a"
					( attribute "PN" "1"
						( Origin gPackager )
					)
					( objectStatus "C4E17.1" )
				)
				( pin "b"
					( attribute "PN" "2"
						( Origin gPackager )
					)
					( objectStatus "C4E17.2" )
				)
			)
			( gate "@baseboard_fab2_lib.baseboard_fab2(sch_1):page202_i24"
				( attribute "CDS_LIB" "mstr_discrete"
					( Origin gPackager )
				)
				( attribute "CDS_LOCATION" "C4E27"
					( Origin gPackager )
				)
				( attribute "CDS_SEC" "1"
					( Origin gPackager )
				)
				( attribute "LOCATION" "C4E27"
					( Origin gFrontEnd )
				)
				( attribute "MATERIAL" "X7R"
					( Origin gFrontEnd )
				)
				( attribute "PACK_TYPE" "0402"
					( Origin gFrontEnd )
				)
				( attribute "PART_NUMBER" "A36096-155"
					( Origin gFrontEnd )
				)
				( attribute "PHYS_PAGE" "202"
					( Origin gFrontEnd )
				)
				( attribute "ROOM" "PVCCIN_CPU0_PWR_VR"
					( Origin gFrontEnd )
				)
				( attribute "ROT" "0"
					( Origin gFrontEnd )
				)
				( attribute "SEC" "1"
					( Origin gFrontEnd )
				)
				( attribute "SEC_TYPE" "0402"
					( Origin gFrontEnd )
				)
				( attribute "TOLERANCE" "10%"
					( Origin gFrontEnd )
				)
				( attribute "VALUE" "0.22UF"
					( Origin gFrontEnd )
				)
				( attribute "VER" "1"
					( Origin gFrontEnd )
				)
				( attribute "VOLTAGE" "16V"
					( Units "uVoltage" "V" 1.000000)
					( Origin gFrontEnd )
				)
				( attribute "XY" "(-5100,1425)"
					( Origin gFrontEnd )
				)
				( attribute "CHIPS_PART_NAME" "CAP"
					( Origin gPackager )
				)
				( attribute "CDS_PART_NAME" "CAP_0402-0.22UF,16V,10%,X7R,A3A"
					( Origin gPackager )
				)
				( objectStatus "C4E27" )
				( pin "a"
					( attribute "PN" "1"
						( Origin gPackager )
					)
					( objectStatus "C4E27.1" )
				)
				( pin "b"
					( attribute "PN" "2"
						( Origin gPackager )
					)
					( objectStatus "C4E27.2" )
				)
			)
			( gate "@baseboard_fab2_lib.baseboard_fab2(sch_1):page202_i25"
				( attribute "CDS_LIB" "dev_discrete"
					( Origin gPackager )
				)
				( attribute "CDS_LOCATION" "C4E25"
					( Origin gPackager )
				)
				( attribute "CDS_SEC" "1"
					( Origin gPackager )
				)
				( attribute "LOCATION" "C4E25"
					( Origin gFrontEnd )
				)
				( attribute "MATERIAL" "X6S"
					( Origin gFrontEnd )
				)
				( attribute "PACK_TYPE" "0402V"
					( Origin gFrontEnd )
				)
				( attribute "PART_NUMBER" "D97712-004"
					( Origin gFrontEnd )
				)
				( attribute "PHYS_PAGE" "202"
					( Origin gFrontEnd )
				)
				( attribute "ROOM" "PVCCIN_CPU0_PWR_VR"
					( Origin gFrontEnd )
				)
				( attribute "ROT" "2"
					( Origin gFrontEnd )
				)
				( attribute "SEC" "1"
					( Origin gFrontEnd )
				)
				( attribute "SEC_TYPE" "0402V"
					( Origin gFrontEnd )
				)
				( attribute "TOLERANCE" "10%"
					( Origin gFrontEnd )
				)
				( attribute "VALUE" "1.0UF"
					( Origin gFrontEnd )
				)
				( attribute "VER" "1"
					( Origin gFrontEnd )
				)
				( attribute "VOLTAGE" "6.3V"
					( Units "uVoltage" "V" 1.000000)
					( Origin gFrontEnd )
				)
				( attribute "XY" "(-5225,1450)"
					( Origin gFrontEnd )
				)
				( attribute "CHIPS_PART_NAME" "CAP_A"
					( Origin gPackager )
				)
				( attribute "CDS_PART_NAME" "CAP_A_0402V-1.0UF,6.3V,10%,X6SA"
					( Origin gPackager )
				)
				( objectStatus "C4E25" )
				( pin "a"
					( attribute "PN" "1"
						( Origin gPackager )
					)
					( objectStatus "C4E25.1" )
				)
				( pin "b"
					( attribute "PN" "2"
						( Origin gPackager )
					)
					( objectStatus "C4E25.2" )
				)
			)
			( gate "@baseboard_fab2_lib.baseboard_fab2(sch_1):page202_i27"
				( attribute "BOM_COST" "PROC_VRD_VCCIN_CPU0"
					( Origin gFrontEnd )
				)
				( attribute "CDS_LIB" "dev_discrete"
					( Origin gPackager )
				)
				( attribute "CDS_LOCATION" "C4E11"
					( Origin gPackager )
				)
				( attribute "CDS_SEC" "1"
					( Origin gPackager )
				)
				( attribute "LOCATION" "C4E11"
					( Origin gFrontEnd )
				)
				( attribute "MATERIAL" "X6S"
					( Origin gFrontEnd )
				)
				( attribute "PACK_TYPE" "0603V"
					( Origin gFrontEnd )
				)
				( attribute "PART_NUMBER" "E15431-004"
					( Origin gFrontEnd )
				)
				( attribute "PHYS_PAGE" "202"
					( Origin gFrontEnd )
				)
				( attribute "ROOM" "PVCCIN_CPU0_PWR_VR"
					( Origin gFrontEnd )
				)
				( attribute "ROT" "0"
					( Origin gFrontEnd )
				)
				( attribute "SEC" "1"
					( Origin gFrontEnd )
				)
				( attribute "SEC_TYPE" "0603V"
					( Origin gFrontEnd )
				)
				( attribute "TOLERANCE" "20%"
					( Origin gFrontEnd )
				)
				( attribute "VALUE" "22.0UF"
					( Origin gFrontEnd )
				)
				( attribute "VER" "1"
					( Origin gFrontEnd )
				)
				( attribute "VOLTAGE" "4V"
					( Units "uVoltage" "V" 1.000000)
					( Origin gFrontEnd )
				)
				( attribute "XY" "(-875,650)"
					( Origin gFrontEnd )
				)
				( attribute "CHIPS_PART_NAME" "CAP_A"
					( Origin gPackager )
				)
				( attribute "CDS_PART_NAME" "CAP_A_0603V-22.0UF,4V,20%,X6S,A"
					( Origin gPackager )
				)
				( objectStatus "C4E11" )
				( pin "a"
					( attribute "PN" "1"
						( Origin gPackager )
					)
					( objectStatus "C4E11.1" )
				)
				( pin "b"
					( attribute "PN" "2"
						( Origin gPackager )
					)
					( objectStatus "C4E11.2" )
				)
			)
			( gate "@baseboard_fab2_lib.baseboard_fab2(sch_1):page202_i29"
				( attribute "CDS_LIB" "mstr_discrete"
					( Origin gPackager )
				)
				( attribute "CDS_LOCATION" "L4D3"
					( Origin gPackager )
				)
				( attribute "CDS_SEC" "1"
					( Origin gPackager )
				)
				( attribute "LOCATION" "L4D3"
					( Origin gFrontEnd )
				)
				( attribute "MATERIAL" "IND"
					( Origin gFrontEnd )
				)
				( attribute "PACK_TYPE" "SM"
					( Origin gFrontEnd )
				)
				( attribute "PART_NUMBER" "D92183-034"
					( Origin gFrontEnd )
				)
				( attribute "PHYS_PAGE" "202"
					( Origin gFrontEnd )
				)
				( attribute "ROOM" "PVCCIN_CPU0_PWR_VR"
					( Origin gFrontEnd )
				)
				( attribute "ROT" "0"
					( Origin gFrontEnd )
				)
				( attribute "SEC" "1"
					( Origin gPackager )
				)
				( attribute "VALUE" "0.12UH"
					( Origin gFrontEnd )
				)
				( attribute "VER" "1"
					( Origin gFrontEnd )
				)
				( attribute "XY" "(-1700,925)"
					( Origin gFrontEnd )
				)
				( attribute "CHIPS_PART_NAME" "INDUCTOR"
					( Origin gPackager )
				)
				( attribute "CDS_PART_NAME" "INDUCTOR_SM-0.12UH,IND,D92183-A"
					( Origin gPackager )
				)
				( objectStatus "L4D3" )
				( pin "ina"
					( attribute "PN" "1"
						( Origin gPackager )
					)
					( objectStatus "L4D3.1" )
				)
				( pin "inb"
					( attribute "PN" "2"
						( Origin gPackager )
					)
					( objectStatus "L4D3.2" )
				)
			)
			( gate "@baseboard_fab2_lib.baseboard_fab2(sch_1):page202_i32"
				( attribute "CDS_LIB" "mstr_discrete"
					( Origin gPackager )
				)
				( attribute "CDS_LOCATION" "C4D50"
					( Origin gPackager )
				)
				( attribute "CDS_SEC" "1"
					( Origin gPackager )
				)
				( attribute "LOCATION" "C4D50"
					( Origin gFrontEnd )
				)
				( attribute "MATERIAL" "X7R"
					( Origin gFrontEnd )
				)
				( attribute "NO_XNET_CONNECTION" "1"
					( Origin gFrontEnd )
				)
				( attribute "PACK_TYPE" "0402"
					( Origin gFrontEnd )
				)
				( attribute "PART_NUMBER" "A36096-104"
					( Origin gFrontEnd )
				)
				( attribute "PHYS_PAGE" "202"
					( Origin gFrontEnd )
				)
				( attribute "ROOM" "PVCCIN_CPU0_PWR_VR"
					( Origin gFrontEnd )
				)
				( attribute "ROT" "2"
					( Origin gFrontEnd )
				)
				( attribute "SEC" "1"
					( Origin gFrontEnd )
				)
				( attribute "SEC_TYPE" "0402"
					( Origin gFrontEnd )
				)
				( attribute "SPOF" "TRUE"
					( Origin gFrontEnd )
				)
				( attribute "TOLERANCE" "10%"
					( Origin gFrontEnd )
				)
				( attribute "VALUE" "0.220UF"
					( Origin gFrontEnd )
				)
				( attribute "VER" "1"
					( Origin gFrontEnd )
				)
				( attribute "VOLTAGE" "16V"
					( Units "uVoltage" "V" 1.000000)
					( Origin gFrontEnd )
				)
				( attribute "XY" "(-5950,825)"
					( Origin gFrontEnd )
				)
				( attribute "CHIPS_PART_NAME" "CAP"
					( Origin gPackager )
				)
				( attribute "CDS_PART_NAME" "CAP_0402-0.220UF,16V,10%,X7R,AA"
					( Origin gPackager )
				)
				( objectStatus "C4D50" )
				( pin "a"
					( attribute "PN" "1"
						( Origin gPackager )
					)
					( objectStatus "C4D50.1" )
				)
				( pin "b"
					( attribute "PN" "2"
						( Origin gPackager )
					)
					( objectStatus "C4D50.2" )
				)
			)
			( gate "@baseboard_fab2_lib.baseboard_fab2(sch_1):page202_i33"
				( attribute "CDS_LIB" "mstr_discrete"
					( Origin gPackager )
				)
				( attribute "CDS_LOCATION" "R6R2"
					( Origin gPackager )
				)
				( attribute "CDS_SEC" "1"
					( Origin gPackager )
				)
				( attribute "LOCATION" "R6R2"
					( Origin gFrontEnd )
				)
				( attribute "MATERIAL" "CHIP"
					( Origin gFrontEnd )
				)
				( attribute "PACK_TYPE" "0402"
					( Origin gFrontEnd )
				)
				( attribute "PART_NUMBER" "G21796-090"
					( Origin gFrontEnd )
				)
				( attribute "PHYS_PAGE" "202"
					( Origin gFrontEnd )
				)
				( attribute "ROOM" "PVCCIN_CPU0_PWR_VR"
					( Origin gFrontEnd )
				)
				( attribute "ROT" "0"
					( Origin gFrontEnd )
				)
				( attribute "SEC" "1"
					( Origin gFrontEnd )
				)
				( attribute "SEC_TYPE" "0402"
					( Origin gFrontEnd )
				)
				( attribute "TOLERANCE" "1%"
					( Origin gFrontEnd )
				)
				( attribute "VALUE" "1.0"
					( Origin gFrontEnd )
				)
				( attribute "VER" "1"
					( Origin gFrontEnd )
				)
				( attribute "WATTAGE" "1/16W"
					( Origin gFrontEnd )
				)
				( attribute "XY" "(-5500,4625)"
					( Origin gFrontEnd )
				)
				( attribute "CHIPS_PART_NAME" "RES"
					( Origin gPackager )
				)
				( attribute "CDS_PART_NAME" "RES_0402-1.0,1%,1/16W,CHIP,G21A"
					( Origin gPackager )
				)
				( objectStatus "R6R2" )
				( pin "a"
					( attribute "PN" "1"
						( Origin gPackager )
					)
					( objectStatus "R6R2.1" )
				)
				( pin "b"
					( attribute "PN" "2"
						( Origin gPackager )
					)
					( objectStatus "R6R2.2" )
				)
			)
			( gate "@baseboard_fab2_lib.baseboard_fab2(sch_1):page202_i34"
				( attribute "CDS_LIB" "mstr_discrete"
					( Origin gPackager )
				)
				( attribute "CDS_LOCATION" "C4E10"
					( Origin gPackager )
				)
				( attribute "CDS_SEC" "1"
					( Origin gPackager )
				)
				( attribute "LOCATION" "C4E10"
					( Origin gFrontEnd )
				)
				( attribute "MATERIAL" "X6S"
					( Origin gFrontEnd )
				)
				( attribute "PACK_TYPE" "0402"
					( Origin gFrontEnd )
				)
				( attribute "PART_NUMBER" "D97712-011"
					( Origin gFrontEnd )
				)
				( attribute "PHYS_PAGE" "202"
					( Origin gFrontEnd )
				)
				( attribute "ROOM" "PVCCIN_CPU0_PWR_VR"
					( Origin gFrontEnd )
				)
				( attribute "ROT" "0"
					( Origin gFrontEnd )
				)
				( attribute "SEC" "1"
					( Origin gFrontEnd )
				)
				( attribute "SEC_TYPE" "0402"
					( Origin gFrontEnd )
				)
				( attribute "TOLERANCE" "10%"
					( Origin gFrontEnd )
				)
				( attribute "VALUE" "1.0UF"
					( Origin gFrontEnd )
				)
				( attribute "VER" "1"
					( Origin gFrontEnd )
				)
				( attribute "VOLTAGE" "16V"
					( Units "uVoltage" "V" 1.000000)
					( Origin gFrontEnd )
				)
				( attribute "XY" "(-5750,4025)"
					( Origin gFrontEnd )
				)
				( attribute "CHIPS_PART_NAME" "CAP"
					( Origin gPackager )
				)
				( attribute "CDS_PART_NAME" "CAP_0402-1.0UF,16V,10%,X6S,D97A"
					( Origin gPackager )
				)
				( objectStatus "C4E10" )
				( pin "a"
					( attribute "PN" "1"
						( Origin gPackager )
					)
					( objectStatus "C4E10.1" )
				)
				( pin "b"
					( attribute "PN" "2"
						( Origin gPackager )
					)
					( objectStatus "C4E10.2" )
				)
			)
			( gate "@baseboard_fab2_lib.baseboard_fab2(sch_1):page202_i35"
				( attribute "CDS_LIB" "dev_discrete"
					( Origin gPackager )
				)
				( attribute "CDS_LOCATION" "C4E20"
					( Origin gPackager )
				)
				( attribute "CDS_SEC" "1"
					( Origin gPackager )
				)
				( attribute "LOCATION" "C4E20"
					( Origin gFrontEnd )
				)
				( attribute "MATERIAL" "X7R"
					( Origin gFrontEnd )
				)
				( attribute "PACK_TYPE" "0402V"
					( Origin gFrontEnd )
				)
				( attribute "PART_NUMBER" "A36096-030"
					( Origin gFrontEnd )
				)
				( attribute "PHYS_PAGE" "202"
					( Origin gFrontEnd )
				)
				( attribute "ROOM" "PVCCIN_CPU0_PWR_VR"
					( Origin gFrontEnd )
				)
				( attribute "ROT" "0"
					( Origin gFrontEnd )
				)
				( attribute "SEC" "1"
					( Origin gFrontEnd )
				)
				( attribute "SEC_TYPE" "0402V"
					( Origin gFrontEnd )
				)
				( attribute "TOLERANCE" "10%"
					( Origin gFrontEnd )
				)
				( attribute "VALUE" "0.1UF"
					( Origin gFrontEnd )
				)
				( attribute "VER" "1"
					( Origin gFrontEnd )
				)
				( attribute "VOLTAGE" "16V"
					( Units "uVoltage" "V" 1.000000)
					( Origin gFrontEnd )
				)
				( attribute "XY" "(-6050,4025)"
					( Origin gFrontEnd )
				)
				( attribute "CHIPS_PART_NAME" "CAP_A"
					( Origin gPackager )
				)
				( attribute "CDS_PART_NAME" "CAP_A_0402V-0.1UF,16V,10%,X7R,A"
					( Origin gPackager )
				)
				( objectStatus "C4E20" )
				( pin "a"
					( attribute "PN" "1"
						( Origin gPackager )
					)
					( objectStatus "C4E20.1" )
				)
				( pin "b"
					( attribute "PN" "2"
						( Origin gPackager )
					)
					( objectStatus "C4E20.2" )
				)
			)
			( gate "@baseboard_fab2_lib.baseboard_fab2(sch_1):page202_i36"
				( attribute "CDS_LIB" "mstr_discrete"
					( Origin gPackager )
				)
				( attribute "CDS_LOCATION" "C4E19"
					( Origin gPackager )
				)
				( attribute "CDS_SEC" "1"
					( Origin gPackager )
				)
				( attribute "LOCATION" "C4E19"
					( Origin gFrontEnd )
				)
				( attribute "MATERIAL" "X6S"
					( Origin gFrontEnd )
				)
				( attribute "PACK_TYPE" "0402"
					( Origin gFrontEnd )
				)
				( attribute "PART_NUMBER" "D97712-011"
					( Origin gFrontEnd )
				)
				( attribute "PHYS_PAGE" "202"
					( Origin gFrontEnd )
				)
				( attribute "ROOM" "PVCCIN_CPU0_PWR_VR"
					( Origin gFrontEnd )
				)
				( attribute "ROT" "0"
					( Origin gFrontEnd )
				)
				( attribute "SEC" "1"
					( Origin gFrontEnd )
				)
				( attribute "SEC_TYPE" "0402"
					( Origin gFrontEnd )
				)
				( attribute "TOLERANCE" "10%"
					( Origin gFrontEnd )
				)
				( attribute "VALUE" "1.0UF"
					( Origin gFrontEnd )
				)
				( attribute "VER" "1"
					( Origin gFrontEnd )
				)
				( attribute "VOLTAGE" "16V"
					( Units "uVoltage" "V" 1.000000)
					( Origin gFrontEnd )
				)
				( attribute "XY" "(-6325,4050)"
					( Origin gFrontEnd )
				)
				( attribute "CHIPS_PART_NAME" "CAP"
					( Origin gPackager )
				)
				( attribute "CDS_PART_NAME" "CAP_0402-1.0UF,16V,10%,X6S,D97A"
					( Origin gPackager )
				)
				( objectStatus "C4E19" )
				( pin "a"
					( attribute "PN" "1"
						( Origin gPackager )
					)
					( objectStatus "C4E19.1" )
				)
				( pin "b"
					( attribute "PN" "2"
						( Origin gPackager )
					)
					( objectStatus "C4E19.2" )
				)
			)
			( gate "@baseboard_fab2_lib.baseboard_fab2(sch_1):page202_i37"
				( attribute "CDS_LIB" "mstr_discrete"
					( Origin gPackager )
				)
				( attribute "CDS_LOCATION" "C6R11"
					( Origin gPackager )
				)
				( attribute "CDS_SEC" "1"
					( Origin gPackager )
				)
				( attribute "LOCATION" "C6R11"
					( Origin gFrontEnd )
				)
				( attribute "MATERIAL" "X6S"
					( Origin gFrontEnd )
				)
				( attribute "PACK_TYPE" "0805"
					( Origin gFrontEnd )
				)
				( attribute "PART_NUMBER" "C95333-007"
					( Origin gFrontEnd )
				)
				( attribute "PHYS_PAGE" "202"
					( Origin gFrontEnd )
				)
				( attribute "ROOM" "PVCCIN_CPU0_PWR_VR"
					( Origin gFrontEnd )
				)
				( attribute "ROT" "0"
					( Origin gFrontEnd )
				)
				( attribute "SEC" "1"
					( Origin gFrontEnd )
				)
				( attribute "SEC_TYPE" "0805"
					( Origin gFrontEnd )
				)
				( attribute "TOLERANCE" "10%"
					( Origin gFrontEnd )
				)
				( attribute "VALUE" "10UF"
					( Origin gFrontEnd )
				)
				( attribute "VER" "1"
					( Origin gFrontEnd )
				)
				( attribute "VOLTAGE" "16V"
					( Units "uVoltage" "V" 1.000000)
					( Origin gFrontEnd )
				)
				( attribute "XY" "(-6600,4050)"
					( Origin gFrontEnd )
				)
				( attribute "CHIPS_PART_NAME" "CAP"
					( Origin gPackager )
				)
				( attribute "CDS_PART_NAME" "CAP_0805-10UF,16V,10%,X6S,C953A"
					( Origin gPackager )
				)
				( objectStatus "C6R11" )
				( pin "a"
					( attribute "PN" "1"
						( Origin gPackager )
					)
					( objectStatus "C6R11.1" )
				)
				( pin "b"
					( attribute "PN" "2"
						( Origin gPackager )
					)
					( objectStatus "C6R11.2" )
				)
			)
			( gate "@baseboard_fab2_lib.baseboard_fab2(sch_1):page202_i38"
				( attribute "CDS_LIB" "mstr_discrete"
					( Origin gPackager )
				)
				( attribute "CDS_LOCATION" "C6P13"
					( Origin gPackager )
				)
				( attribute "CDS_SEC" "1"
					( Origin gPackager )
				)
				( attribute "LOCATION" "C6P13"
					( Origin gFrontEnd )
				)
				( attribute "MATERIAL" "X6S"
					( Origin gFrontEnd )
				)
				( attribute "PACK_TYPE" "0805"
					( Origin gFrontEnd )
				)
				( attribute "PART_NUMBER" "C95333-007"
					( Origin gFrontEnd )
				)
				( attribute "PHYS_PAGE" "202"
					( Origin gFrontEnd )
				)
				( attribute "ROOM" "PVCCIN_CPU0_PWR_VR"
					( Origin gFrontEnd )
				)
				( attribute "ROT" "0"
					( Origin gFrontEnd )
				)
				( attribute "SEC" "1"
					( Origin gFrontEnd )
				)
				( attribute "SEC_TYPE" "0805"
					( Origin gFrontEnd )
				)
				( attribute "TOLERANCE" "10%"
					( Origin gFrontEnd )
				)
				( attribute "VALUE" "10UF"
					( Origin gFrontEnd )
				)
				( attribute "VER" "1"
					( Origin gFrontEnd )
				)
				( attribute "VOLTAGE" "16V"
					( Units "uVoltage" "V" 1.000000)
					( Origin gFrontEnd )
				)
				( attribute "XY" "(-6900,4075)"
					( Origin gFrontEnd )
				)
				( attribute "CHIPS_PART_NAME" "CAP"
					( Origin gPackager )
				)
				( attribute "CDS_PART_NAME" "CAP_0805-10UF,16V,10%,X6S,C953A"
					( Origin gPackager )
				)
				( objectStatus "C6P13" )
				( pin "a"
					( attribute "PN" "1"
						( Origin gPackager )
					)
					( objectStatus "C6P13.1" )
				)
				( pin "b"
					( attribute "PN" "2"
						( Origin gPackager )
					)
					( objectStatus "C6P13.2" )
				)
			)
			( gate "@baseboard_fab2_lib.baseboard_fab2(sch_1):page202_i39"
				( attribute "CDS_LIB" "mstr_discrete"
					( Origin gPackager )
				)
				( attribute "CDS_LOCATION" "R6R6"
					( Origin gPackager )
				)
				( attribute "CDS_SEC" "1"
					( Origin gPackager )
				)
				( attribute "LOCATION" "R6R6"
					( Origin gFrontEnd )
				)
				( attribute "MATERIAL" "CHIP"
					( Origin gFrontEnd )
				)
				( attribute "PACK_TYPE" "0402"
					( Origin gFrontEnd )
				)
				( attribute "PART_NUMBER" "G21796-090"
					( Origin gFrontEnd )
				)
				( attribute "PHYS_PAGE" "202"
					( Origin gFrontEnd )
				)
				( attribute "ROOM" "PVCCIN_CPU0_PWR_VR"
					( Origin gFrontEnd )
				)
				( attribute "ROT" "0"
					( Origin gFrontEnd )
				)
				( attribute "SEC" "1"
					( Origin gFrontEnd )
				)
				( attribute "SEC_TYPE" "0402"
					( Origin gFrontEnd )
				)
				( attribute "TOLERANCE" "1%"
					( Origin gFrontEnd )
				)
				( attribute "VALUE" "1.0"
					( Origin gFrontEnd )
				)
				( attribute "VER" "1"
					( Origin gFrontEnd )
				)
				( attribute "WATTAGE" "1/16W"
					( Origin gFrontEnd )
				)
				( attribute "XY" "(-5625,1975)"
					( Origin gFrontEnd )
				)
				( attribute "CHIPS_PART_NAME" "RES"
					( Origin gPackager )
				)
				( attribute "CDS_PART_NAME" "RES_0402-1.0,1%,1/16W,CHIP,G21A"
					( Origin gPackager )
				)
				( objectStatus "R6R6" )
				( pin "a"
					( attribute "PN" "1"
						( Origin gPackager )
					)
					( objectStatus "R6R6.1" )
				)
				( pin "b"
					( attribute "PN" "2"
						( Origin gPackager )
					)
					( objectStatus "R6R6.2" )
				)
			)
			( gate "@baseboard_fab2_lib.baseboard_fab2(sch_1):page202_i42"
				( attribute "CDS_LIB" "mstr_discrete"
					( Origin gPackager )
				)
				( attribute "CDS_LOCATION" "C6R13"
					( Origin gPackager )
				)
				( attribute "CDS_SEC" "1"
					( Origin gPackager )
				)
				( attribute "LOCATION" "C6R13"
					( Origin gFrontEnd )
				)
				( attribute "MATERIAL" "X6S"
					( Origin gFrontEnd )
				)
				( attribute "PACK_TYPE" "0805"
					( Origin gFrontEnd )
				)
				( attribute "PART_NUMBER" "C95333-007"
					( Origin gFrontEnd )
				)
				( attribute "PHYS_PAGE" "202"
					( Origin gFrontEnd )
				)
				( attribute "ROOM" "PVCCIN_CPU0_PWR_VR"
					( Origin gFrontEnd )
				)
				( attribute "ROT" "0"
					( Origin gFrontEnd )
				)
				( attribute "SEC" "1"
					( Origin gFrontEnd )
				)
				( attribute "SEC_TYPE" "0805"
					( Origin gFrontEnd )
				)
				( attribute "TOLERANCE" "10%"
					( Origin gFrontEnd )
				)
				( attribute "VALUE" "10UF"
					( Origin gFrontEnd )
				)
				( attribute "VER" "1"
					( Origin gFrontEnd )
				)
				( attribute "VOLTAGE" "16V"
					( Units "uVoltage" "V" 1.000000)
					( Origin gFrontEnd )
				)
				( attribute "XY" "(-7200,4075)"
					( Origin gFrontEnd )
				)
				( attribute "CHIPS_PART_NAME" "CAP"
					( Origin gPackager )
				)
				( attribute "CDS_PART_NAME" "CAP_0805-10UF,16V,10%,X6S,C953A"
					( Origin gPackager )
				)
				( objectStatus "C6R13" )
				( pin "a"
					( attribute "PN" "1"
						( Origin gPackager )
					)
					( objectStatus "C6R13.1" )
				)
				( pin "b"
					( attribute "PN" "2"
						( Origin gPackager )
					)
					( objectStatus "C6R13.2" )
				)
			)
			( gate "@baseboard_fab2_lib.baseboard_fab2(sch_1):page202_i45"
				( attribute "CDS_LIB" "mstr_discrete"
					( Origin gPackager )
				)
				( attribute "CDS_LOCATION" "C4E26"
					( Origin gPackager )
				)
				( attribute "CDS_SEC" "1"
					( Origin gPackager )
				)
				( attribute "LOCATION" "C4E26"
					( Origin gFrontEnd )
				)
				( attribute "MATERIAL" "X6S"
					( Origin gFrontEnd )
				)
				( attribute "PACK_TYPE" "0402"
					( Origin gFrontEnd )
				)
				( attribute "PART_NUMBER" "D97712-011"
					( Origin gFrontEnd )
				)
				( attribute "PHYS_PAGE" "202"
					( Origin gFrontEnd )
				)
				( attribute "ROOM" "PVCCIN_CPU0_PWR_VR"
					( Origin gFrontEnd )
				)
				( attribute "ROT" "0"
					( Origin gFrontEnd )
				)
				( attribute "SEC" "1"
					( Origin gFrontEnd )
				)
				( attribute "SEC_TYPE" "0402"
					( Origin gFrontEnd )
				)
				( attribute "TOLERANCE" "10%"
					( Origin gFrontEnd )
				)
				( attribute "VALUE" "1.0UF"
					( Origin gFrontEnd )
				)
				( attribute "VER" "1"
					( Origin gFrontEnd )
				)
				( attribute "VOLTAGE" "16V"
					( Units "uVoltage" "V" 1.000000)
					( Origin gFrontEnd )
				)
				( attribute "XY" "(-5950,1425)"
					( Origin gFrontEnd )
				)
				( attribute "CHIPS_PART_NAME" "CAP"
					( Origin gPackager )
				)
				( attribute "CDS_PART_NAME" "CAP_0402-1.0UF,16V,10%,X6S,D97A"
					( Origin gPackager )
				)
				( objectStatus "C4E26" )
				( pin "a"
					( attribute "PN" "1"
						( Origin gPackager )
					)
					( objectStatus "C4E26.1" )
				)
				( pin "b"
					( attribute "PN" "2"
						( Origin gPackager )
					)
					( objectStatus "C4E26.2" )
				)
			)
			( gate "@baseboard_fab2_lib.baseboard_fab2(sch_1):page202_i46"
				( attribute "CDS_LIB" "dev_discrete"
					( Origin gPackager )
				)
				( attribute "CDS_LOCATION" "C4D49"
					( Origin gPackager )
				)
				( attribute "CDS_SEC" "1"
					( Origin gPackager )
				)
				( attribute "LOCATION" "C4D49"
					( Origin gFrontEnd )
				)
				( attribute "MATERIAL" "X7R"
					( Origin gFrontEnd )
				)
				( attribute "PACK_TYPE" "0402V"
					( Origin gFrontEnd )
				)
				( attribute "PART_NUMBER" "A36096-030"
					( Origin gFrontEnd )
				)
				( attribute "PHYS_PAGE" "202"
					( Origin gFrontEnd )
				)
				( attribute "ROOM" "PVCCIN_CPU0_PWR_VR"
					( Origin gFrontEnd )
				)
				( attribute "ROT" "0"
					( Origin gFrontEnd )
				)
				( attribute "SEC" "1"
					( Origin gFrontEnd )
				)
				( attribute "SEC_TYPE" "0402V"
					( Origin gFrontEnd )
				)
				( attribute "TOLERANCE" "10%"
					( Origin gFrontEnd )
				)
				( attribute "VALUE" "0.1UF"
					( Origin gFrontEnd )
				)
				( attribute "VER" "1"
					( Origin gFrontEnd )
				)
				( attribute "VOLTAGE" "16V"
					( Units "uVoltage" "V" 1.000000)
					( Origin gFrontEnd )
				)
				( attribute "XY" "(-6225,1475)"
					( Origin gFrontEnd )
				)
				( attribute "CHIPS_PART_NAME" "CAP_A"
					( Origin gPackager )
				)
				( attribute "CDS_PART_NAME" "CAP_A_0402V-0.1UF,16V,10%,X7R,A"
					( Origin gPackager )
				)
				( objectStatus "C4D49" )
				( pin "a"
					( attribute "PN" "1"
						( Origin gPackager )
					)
					( objectStatus "C4D49.1" )
				)
				( pin "b"
					( attribute "PN" "2"
						( Origin gPackager )
					)
					( objectStatus "C4D49.2" )
				)
			)
			( gate "@baseboard_fab2_lib.baseboard_fab2(sch_1):page202_i47"
				( attribute "CDS_LIB" "mstr_discrete"
					( Origin gPackager )
				)
				( attribute "CDS_LOCATION" "C4D48"
					( Origin gPackager )
				)
				( attribute "CDS_SEC" "1"
					( Origin gPackager )
				)
				( attribute "LOCATION" "C4D48"
					( Origin gFrontEnd )
				)
				( attribute "MATERIAL" "X6S"
					( Origin gFrontEnd )
				)
				( attribute "PACK_TYPE" "0402"
					( Origin gFrontEnd )
				)
				( attribute "PART_NUMBER" "D97712-011"
					( Origin gFrontEnd )
				)
				( attribute "PHYS_PAGE" "202"
					( Origin gFrontEnd )
				)
				( attribute "ROOM" "PVCCIN_CPU0_PWR_VR"
					( Origin gFrontEnd )
				)
				( attribute "ROT" "0"
					( Origin gFrontEnd )
				)
				( attribute "SEC" "1"
					( Origin gFrontEnd )
				)
				( attribute "SEC_TYPE" "0402"
					( Origin gFrontEnd )
				)
				( attribute "TOLERANCE" "10%"
					( Origin gFrontEnd )
				)
				( attribute "VALUE" "1.0UF"
					( Origin gFrontEnd )
				)
				( attribute "VER" "1"
					( Origin gFrontEnd )
				)
				( attribute "VOLTAGE" "16V"
					( Units "uVoltage" "V" 1.000000)
					( Origin gFrontEnd )
				)
				( attribute "XY" "(-6450,1425)"
					( Origin gFrontEnd )
				)
				( attribute "CHIPS_PART_NAME" "CAP"
					( Origin gPackager )
				)
				( attribute "CDS_PART_NAME" "CAP_0402-1.0UF,16V,10%,X6S,D97A"
					( Origin gPackager )
				)
				( objectStatus "C4D48" )
				( pin "a"
					( attribute "PN" "1"
						( Origin gPackager )
					)
					( objectStatus "C4D48.1" )
				)
				( pin "b"
					( attribute "PN" "2"
						( Origin gPackager )
					)
					( objectStatus "C4D48.2" )
				)
			)
			( gate "@baseboard_fab2_lib.baseboard_fab2(sch_1):page202_i48"
				( attribute "CDS_LIB" "mstr_discrete"
					( Origin gPackager )
				)
				( attribute "CDS_LOCATION" "C6R4"
					( Origin gPackager )
				)
				( attribute "CDS_SEC" "1"
					( Origin gPackager )
				)
				( attribute "LOCATION" "C6R4"
					( Origin gFrontEnd )
				)
				( attribute "MATERIAL" "X6S"
					( Origin gFrontEnd )
				)
				( attribute "PACK_TYPE" "0805"
					( Origin gFrontEnd )
				)
				( attribute "PART_NUMBER" "C95333-007"
					( Origin gFrontEnd )
				)
				( attribute "PHYS_PAGE" "202"
					( Origin gFrontEnd )
				)
				( attribute "ROOM" "PVCCIN_CPU0_PWR_VR"
					( Origin gFrontEnd )
				)
				( attribute "ROT" "0"
					( Origin gFrontEnd )
				)
				( attribute "SEC" "1"
					( Origin gFrontEnd )
				)
				( attribute "SEC_TYPE" "0805"
					( Origin gFrontEnd )
				)
				( attribute "TOLERANCE" "10%"
					( Origin gFrontEnd )
				)
				( attribute "VALUE" "10UF"
					( Origin gFrontEnd )
				)
				( attribute "VER" "1"
					( Origin gFrontEnd )
				)
				( attribute "VOLTAGE" "16V"
					( Units "uVoltage" "V" 1.000000)
					( Origin gFrontEnd )
				)
				( attribute "XY" "(-6725,1425)"
					( Origin gFrontEnd )
				)
				( attribute "CHIPS_PART_NAME" "CAP"
					( Origin gPackager )
				)
				( attribute "CDS_PART_NAME" "CAP_0805-10UF,16V,10%,X6S,C953A"
					( Origin gPackager )
				)
				( objectStatus "C6R4" )
				( pin "a"
					( attribute "PN" "1"
						( Origin gPackager )
					)
					( objectStatus "C6R4.1" )
				)
				( pin "b"
					( attribute "PN" "2"
						( Origin gPackager )
					)
					( objectStatus "C6R4.2" )
				)
			)
			( gate "@baseboard_fab2_lib.baseboard_fab2(sch_1):page202_i49"
				( attribute "CDS_LIB" "mstr_discrete"
					( Origin gPackager )
				)
				( attribute "CDS_LOCATION" "C6P22"
					( Origin gPackager )
				)
				( attribute "CDS_SEC" "1"
					( Origin gPackager )
				)
				( attribute "LOCATION" "C6P22"
					( Origin gFrontEnd )
				)
				( attribute "MATERIAL" "X6S"
					( Origin gFrontEnd )
				)
				( attribute "PACK_TYPE" "0805"
					( Origin gFrontEnd )
				)
				( attribute "PART_NUMBER" "C95333-007"
					( Origin gFrontEnd )
				)
				( attribute "PHYS_PAGE" "202"
					( Origin gFrontEnd )
				)
				( attribute "ROOM" "PVCCIN_CPU0_PWR_VR"
					( Origin gFrontEnd )
				)
				( attribute "ROT" "0"
					( Origin gFrontEnd )
				)
				( attribute "SEC" "1"
					( Origin gFrontEnd )
				)
				( attribute "SEC_TYPE" "0805"
					( Origin gFrontEnd )
				)
				( attribute "TOLERANCE" "10%"
					( Origin gFrontEnd )
				)
				( attribute "VALUE" "10UF"
					( Origin gFrontEnd )
				)
				( attribute "VER" "1"
					( Origin gFrontEnd )
				)
				( attribute "VOLTAGE" "16V"
					( Units "uVoltage" "V" 1.000000)
					( Origin gFrontEnd )
				)
				( attribute "XY" "(-6975,1450)"
					( Origin gFrontEnd )
				)
				( attribute "CHIPS_PART_NAME" "CAP"
					( Origin gPackager )
				)
				( attribute "CDS_PART_NAME" "CAP_0805-10UF,16V,10%,X6S,C953A"
					( Origin gPackager )
				)
				( objectStatus "C6P22" )
				( pin "a"
					( attribute "PN" "1"
						( Origin gPackager )
					)
					( objectStatus "C6P22.1" )
				)
				( pin "b"
					( attribute "PN" "2"
						( Origin gPackager )
					)
					( objectStatus "C6P22.2" )
				)
			)
			( gate "@baseboard_fab2_lib.baseboard_fab2(sch_1):page202_i51"
				( attribute "CDS_LIB" "mstr_discrete"
					( Origin gPackager )
				)
				( attribute "CDS_LOCATION" "C6N8"
					( Origin gPackager )
				)
				( attribute "CDS_SEC" "1"
					( Origin gPackager )
				)
				( attribute "LOCATION" "C6N8"
					( Origin gFrontEnd )
				)
				( attribute "MATERIAL" "X6S"
					( Origin gFrontEnd )
				)
				( attribute "PACK_TYPE" "0805"
					( Origin gFrontEnd )
				)
				( attribute "PART_NUMBER" "C95333-007"
					( Origin gFrontEnd )
				)
				( attribute "PHYS_PAGE" "202"
					( Origin gFrontEnd )
				)
				( attribute "ROOM" "PVCCIN_CPU0_PWR_VR"
					( Origin gFrontEnd )
				)
				( attribute "ROT" "0"
					( Origin gFrontEnd )
				)
				( attribute "SEC" "1"
					( Origin gFrontEnd )
				)
				( attribute "SEC_TYPE" "0805"
					( Origin gFrontEnd )
				)
				( attribute "TOLERANCE" "10%"
					( Origin gFrontEnd )
				)
				( attribute "VALUE" "10UF"
					( Origin gFrontEnd )
				)
				( attribute "VER" "1"
					( Origin gFrontEnd )
				)
				( attribute "VOLTAGE" "16V"
					( Units "uVoltage" "V" 1.000000)
					( Origin gFrontEnd )
				)
				( attribute "XY" "(-7225,1475)"
					( Origin gFrontEnd )
				)
				( attribute "CHIPS_PART_NAME" "CAP"
					( Origin gPackager )
				)
				( attribute "CDS_PART_NAME" "CAP_0805-10UF,16V,10%,X6S,C953A"
					( Origin gPackager )
				)
				( objectStatus "C6N8" )
				( pin "a"
					( attribute "PN" "1"
						( Origin gPackager )
					)
					( objectStatus "C6N8.1" )
				)
				( pin "b"
					( attribute "PN" "2"
						( Origin gPackager )
					)
					( objectStatus "C6N8.2" )
				)
			)
			( gate "@baseboard_fab2_lib.baseboard_fab2(sch_1):page202_i61"
				( attribute "CDS_LIB" "dev_discrete"
					( Origin gPackager )
				)
				( attribute "CDS_LOCATION" "C4E3"
					( Origin gPackager )
				)
				( attribute "CDS_SEC" "1"
					( Origin gPackager )
				)
				( attribute "LOCATION" "C4E3"
					( Origin gFrontEnd )
				)
				( attribute "MATERIAL" "X6S"
					( Origin gFrontEnd )
				)
				( attribute "PACK_TYPE" "0603V"
					( Origin gFrontEnd )
				)
				( attribute "PART_NUMBER" "E15431-004"
					( Origin gFrontEnd )
				)
				( attribute "PHYS_PAGE" "202"
					( Origin gFrontEnd )
				)
				( attribute "ROT" "0"
					( Origin gFrontEnd )
				)
				( attribute "SEC" "1"
					( Origin gFrontEnd )
				)
				( attribute "SEC_TYPE" "0603V"
					( Origin gFrontEnd )
				)
				( attribute "TOLERANCE" "20%"
					( Origin gFrontEnd )
				)
				( attribute "VALUE" "22.0UF"
					( Origin gFrontEnd )
				)
				( attribute "VER" "1"
					( Origin gFrontEnd )
				)
				( attribute "VOLTAGE" "4V"
					( Units "uVoltage" "V" 1.000000)
					( Origin gFrontEnd )
				)
				( attribute "XY" "(-875,3300)"
					( Origin gFrontEnd )
				)
				( attribute "CHIPS_PART_NAME" "CAP_A"
					( Origin gPackager )
				)
				( attribute "CDS_PART_NAME" "CAP_A_0603V-22.0UF,4V,20%,X6S,A"
					( Origin gPackager )
				)
				( objectStatus "C4E3" )
				( pin "a"
					( attribute "PN" "1"
						( Origin gPackager )
					)
					( objectStatus "C4E3.1" )
				)
				( pin "b"
					( attribute "PN" "2"
						( Origin gPackager )
					)
					( objectStatus "C4E3.2" )
				)
			)
			( gate "@baseboard_fab2_lib.baseboard_fab2(sch_1):page202_i62"
				( attribute "CDS_LIB" "dev_discrete"
					( Origin gPackager )
				)
				( attribute "CDS_LOCATION" "C6P16"
					( Origin gPackager )
				)
				( attribute "CDS_SEC" "1"
					( Origin gPackager )
				)
				( attribute "LOCATION" "C6P16"
					( Origin gFrontEnd )
				)
				( attribute "MATERIAL" "X6S"
					( Origin gFrontEnd )
				)
				( attribute "PACK_TYPE" "0603V"
					( Origin gFrontEnd )
				)
				( attribute "PART_NUMBER" "E15431-004"
					( Origin gFrontEnd )
				)
				( attribute "PHYS_PAGE" "202"
					( Origin gFrontEnd )
				)
				( attribute "ROT" "0"
					( Origin gFrontEnd )
				)
				( attribute "SEC" "1"
					( Origin gFrontEnd )
				)
				( attribute "SEC_TYPE" "0603V"
					( Origin gFrontEnd )
				)
				( attribute "TOLERANCE" "20%"
					( Origin gFrontEnd )
				)
				( attribute "VALUE" "22.0UF"
					( Origin gFrontEnd )
				)
				( attribute "VER" "1"
					( Origin gFrontEnd )
				)
				( attribute "VOLTAGE" "4V"
					( Units "uVoltage" "V" 1.000000)
					( Origin gFrontEnd )
				)
				( attribute "XY" "(-575,650)"
					( Origin gFrontEnd )
				)
				( attribute "CHIPS_PART_NAME" "CAP_A"
					( Origin gPackager )
				)
				( attribute "CDS_PART_NAME" "CAP_A_0603V-22.0UF,4V,20%,X6S,A"
					( Origin gPackager )
				)
				( objectStatus "C6P16" )
				( pin "a"
					( attribute "PN" "1"
						( Origin gPackager )
					)
					( objectStatus "C6P16.1" )
				)
				( pin "b"
					( attribute "PN" "2"
						( Origin gPackager )
					)
					( objectStatus "C6P16.2" )
				)
			)
			( gate "@baseboard_fab2_lib.baseboard_fab2(sch_1):page202_i63"
				( attribute "CDS_LIB" "mstr_discrete"
					( Origin gPackager )
				)
				( attribute "CDS_LOCATION" "EU4E1"
					( Origin gPackager )
				)
				( attribute "CDS_SEC" "1"
					( Origin gPackager )
				)
				( attribute "LOCATION" "EU4E1"
					( Origin gFrontEnd )
				)
				( attribute "MATERIAL" "IC"
					( Origin gFrontEnd )
				)
				( attribute "PACK_TYPE" "SM"
					( Origin gFrontEnd )
				)
				( attribute "PART_NUMBER" "H73688-001"
					( Origin gFrontEnd )
				)
				( attribute "PHYS_PAGE" "202"
					( Origin gFrontEnd )
				)
				( attribute "ROT" "0"
					( Origin gFrontEnd )
				)
				( attribute "SEC" "1"
					( Origin gPackager )
				)
				( attribute "VALUE" "IR35411"
					( Origin gFrontEnd )
				)
				( attribute "VER" "1"
					( Origin gFrontEnd )
				)
				( attribute "XY" "(-3425,3800)"
					( Origin gFrontEnd )
				)
				( attribute "CHIPS_PART_NAME" "IR354XX"
					( Origin gPackager )
				)
				( attribute "CDS_PART_NAME" "IR354XX_SM-IR35411,IC,H73688-0A"
					( Origin gPackager )
				)
				( objectStatus "EU4E1" )
				( pin "boost"
					( attribute "PN" "33"
						( Origin gPackager )
					)
					( objectStatus "EU4E1.33" )
				)
				( pin "en"
					( attribute "PN" "35"
						( Origin gPackager )
					)
					( objectStatus "EU4E1.35" )
				)
				( pin "gl(0)"
					( attribute "PN" "6"
						( Origin gPackager )
					)
					( objectStatus "EU4E1.6" )
				)
				( pin "gl(1)"
					( attribute "PN" "41"
						( Origin gPackager )
					)
					( objectStatus "EU4E1.41" )
				)
				( pin "iout"
					( attribute "PN" "38"
						( Origin gPackager )
					)
					( objectStatus "EU4E1.38" )
				)
				( pin "lgnd"
					( attribute "PN" "2"
						( Origin gPackager )
					)
					( objectStatus "EU4E1.2" )
				)
				( pin "nc"
					( attribute "PN" "31"
						( Origin gPackager )
					)
					( objectStatus "EU4E1.31" )
				)
				( pin "ocset"
					( attribute "PN" "37"
						( Origin gPackager )
					)
					( objectStatus "EU4E1.37" )
				)
				( pin "pgnd(0)"
					( attribute "PN" "5"
						( Origin gPackager )
					)
					( objectStatus "EU4E1.5" )
				)
				( pin "pgnd(1)"
					( attribute "PN" "7"
						( Origin gPackager )
					)
					( objectStatus "EU4E1.7" )
				)
				( pin "pgnd(2)"
					( attribute "PN" "40"
						( Origin gPackager )
					)
					( objectStatus "EU4E1.40" )
				)
				( pin "phase"
					( attribute "PN" "32"
						( Origin gPackager )
					)
					( objectStatus "EU4E1.32" )
				)
				( pin "pwm"
					( attribute "PN" "34"
						( Origin gPackager )
					)
					( objectStatus "EU4E1.34" )
				)
				( pin "refin"
					( attribute "PN" "39"
						( Origin gPackager )
					)
					( objectStatus "EU4E1.39" )
				)
				( pin "sw"
					( attribute "PN" "10"
						( Origin gPackager )
					)
					( objectStatus "EU4E1.10" )
				)
				( pin "tout_flt"
					( attribute "PN" "36"
						( Origin gPackager )
					)
					( objectStatus "EU4E1.36" )
				)
				( pin "vcc"
					( attribute "PN" "3"
						( Origin gPackager )
					)
					( objectStatus "EU4E1.3" )
				)
				( pin "vdrv"
					( attribute "PN" "4"
						( Origin gPackager )
					)
					( objectStatus "EU4E1.4" )
				)
				( pin "vin(0)"
					( attribute "PN" "25"
						( Origin gPackager )
					)
					( objectStatus "EU4E1.25" )
				)
				( pin "vin(1)"
					( attribute "PN" "30"
						( Origin gPackager )
					)
					( objectStatus "EU4E1.30" )
				)
				( pin "vos"
					( attribute "PN" "1"
						( Origin gPackager )
					)
					( objectStatus "EU4E1.1" )
				)
			)
			( gate "@baseboard_fab2_lib.baseboard_fab2(sch_1):page202_i64"
				( attribute "CDS_LIB" "mstr_discrete"
					( Origin gPackager )
				)
				( attribute "CDS_LOCATION" "EU4D6"
					( Origin gPackager )
				)
				( attribute "CDS_SEC" "1"
					( Origin gPackager )
				)
				( attribute "LOCATION" "EU4D6"
					( Origin gFrontEnd )
				)
				( attribute "MATERIAL" "IC"
					( Origin gFrontEnd )
				)
				( attribute "PACK_TYPE" "SM"
					( Origin gFrontEnd )
				)
				( attribute "PART_NUMBER" "H73688-001"
					( Origin gFrontEnd )
				)
				( attribute "PHYS_PAGE" "202"
					( Origin gFrontEnd )
				)
				( attribute "ROT" "0"
					( Origin gFrontEnd )
				)
				( attribute "SEC" "1"
					( Origin gPackager )
				)
				( attribute "VALUE" "IR35411"
					( Origin gFrontEnd )
				)
				( attribute "VER" "1"
					( Origin gFrontEnd )
				)
				( attribute "XY" "(-3475,1175)"
					( Origin gFrontEnd )
				)
				( attribute "CHIPS_PART_NAME" "IR354XX"
					( Origin gPackager )
				)
				( attribute "CDS_PART_NAME" "IR354XX_SM-IR35411,IC,H73688-0A"
					( Origin gPackager )
				)
				( objectStatus "EU4D6" )
				( pin "boost"
					( attribute "PN" "33"
						( Origin gPackager )
					)
					( objectStatus "EU4D6.33" )
				)
				( pin "en"
					( attribute "PN" "35"
						( Origin gPackager )
					)
					( objectStatus "EU4D6.35" )
				)
				( pin "gl(0)"
					( attribute "PN" "6"
						( Origin gPackager )
					)
					( objectStatus "EU4D6.6" )
				)
				( pin "gl(1)"
					( attribute "PN" "41"
						( Origin gPackager )
					)
					( objectStatus "EU4D6.41" )
				)
				( pin "iout"
					( attribute "PN" "38"
						( Origin gPackager )
					)
					( objectStatus "EU4D6.38" )
				)
				( pin "lgnd"
					( attribute "PN" "2"
						( Origin gPackager )
					)
					( objectStatus "EU4D6.2" )
				)
				( pin "nc"
					( attribute "PN" "31"
						( Origin gPackager )
					)
					( objectStatus "EU4D6.31" )
				)
				( pin "ocset"
					( attribute "PN" "37"
						( Origin gPackager )
					)
					( objectStatus "EU4D6.37" )
				)
				( pin "pgnd(0)"
					( attribute "PN" "5"
						( Origin gPackager )
					)
					( objectStatus "EU4D6.5" )
				)
				( pin "pgnd(1)"
					( attribute "PN" "7"
						( Origin gPackager )
					)
					( objectStatus "EU4D6.7" )
				)
				( pin "pgnd(2)"
					( attribute "PN" "40"
						( Origin gPackager )
					)
					( objectStatus "EU4D6.40" )
				)
				( pin "phase"
					( attribute "PN" "32"
						( Origin gPackager )
					)
					( objectStatus "EU4D6.32" )
				)
				( pin "pwm"
					( attribute "PN" "34"
						( Origin gPackager )
					)
					( objectStatus "EU4D6.34" )
				)
				( pin "refin"
					( attribute "PN" "39"
						( Origin gPackager )
					)
					( objectStatus "EU4D6.39" )
				)
				( pin "sw"
					( attribute "PN" "10"
						( Origin gPackager )
					)
					( objectStatus "EU4D6.10" )
				)
				( pin "tout_flt"
					( attribute "PN" "36"
						( Origin gPackager )
					)
					( objectStatus "EU4D6.36" )
				)
				( pin "vcc"
					( attribute "PN" "3"
						( Origin gPackager )
					)
					( objectStatus "EU4D6.3" )
				)
				( pin "vdrv"
					( attribute "PN" "4"
						( Origin gPackager )
					)
					( objectStatus "EU4D6.4" )
				)
				( pin "vin(0)"
					( attribute "PN" "25"
						( Origin gPackager )
					)
					( objectStatus "EU4D6.25" )
				)
				( pin "vin(1)"
					( attribute "PN" "30"
						( Origin gPackager )
					)
					( objectStatus "EU4D6.30" )
				)
				( pin "vos"
					( attribute "PN" "1"
						( Origin gPackager )
					)
					( objectStatus "EU4D6.1" )
				)
			)
			( gate "@baseboard_fab2_lib.baseboard_fab2(sch_1):page202_i65"
				( attribute "CDS_LIB" "mstr_discrete"
					( Origin gPackager )
				)
				( attribute "CDS_LOCATION" "R4E22"
					( Origin gPackager )
				)
				( attribute "CDS_SEC" "1"
					( Origin gPackager )
				)
				( attribute "LOCATION" "R4E22"
					( Origin gFrontEnd )
				)
				( attribute "MATERIAL" "EMPTY"
					( Origin gFrontEnd )
				)
				( attribute "PACK_TYPE" "0402"
					( Origin gFrontEnd )
				)
				( attribute "PART_NUMBER" "G21796-187"
					( Origin gFrontEnd )
				)
				( attribute "PHYS_PAGE" "202"
					( Origin gFrontEnd )
				)
				( attribute "ROT" "0"
					( Origin gFrontEnd )
				)
				( attribute "SEC" "1"
					( Origin gPackager )
				)
				( attribute "TOLERANCE" "1%"
					( Origin gFrontEnd )
				)
				( attribute "VALUE" "68.1K"
					( Origin gFrontEnd )
				)
				( attribute "VER" "2"
					( Origin gFrontEnd )
				)
				( attribute "WATTAGE" "1/16W"
					( Origin gFrontEnd )
				)
				( attribute "XY" "(-750,3900)"
					( Origin gFrontEnd )
				)
				( attribute "CHIPS_PART_NAME" "RES"
					( Origin gPackager )
				)
				( attribute "CDS_PART_NAME" "RES_0402-68.1K,1%,1/16W,EMPTY,A"
					( Origin gPackager )
				)
				( objectStatus "R4E22" )
				( pin "a"
					( attribute "PN" "1"
						( Origin gPackager )
					)
					( objectStatus "R4E22.1" )
				)
				( pin "b"
					( attribute "PN" "2"
						( Origin gPackager )
					)
					( objectStatus "R4E22.2" )
				)
			)
			( gate "@baseboard_fab2_lib.baseboard_fab2(sch_1):page202_i67"
				( attribute "CDS_LIB" "mstr_discrete"
					( Origin gPackager )
				)
				( attribute "CDS_LOCATION" "R4E19"
					( Origin gPackager )
				)
				( attribute "CDS_SEC" "1"
					( Origin gPackager )
				)
				( attribute "LOCATION" "R4E19"
					( Origin gFrontEnd )
				)
				( attribute "MATERIAL" "EMPTY"
					( Origin gFrontEnd )
				)
				( attribute "PACK_TYPE" "0402"
					( Origin gFrontEnd )
				)
				( attribute "PART_NUMBER" "G21796-187"
					( Origin gFrontEnd )
				)
				( attribute "PHYS_PAGE" "202"
					( Origin gFrontEnd )
				)
				( attribute "ROT" "0"
					( Origin gFrontEnd )
				)
				( attribute "SEC" "1"
					( Origin gPackager )
				)
				( attribute "TOLERANCE" "1%"
					( Origin gFrontEnd )
				)
				( attribute "VALUE" "68.1K"
					( Origin gFrontEnd )
				)
				( attribute "VER" "2"
					( Origin gFrontEnd )
				)
				( attribute "WATTAGE" "1/16W"
					( Origin gFrontEnd )
				)
				( attribute "XY" "(-825,1350)"
					( Origin gFrontEnd )
				)
				( attribute "CHIPS_PART_NAME" "RES"
					( Origin gPackager )
				)
				( attribute "CDS_PART_NAME" "RES_0402-68.1K,1%,1/16W,EMPTY,A"
					( Origin gPackager )
				)
				( objectStatus "R4E19" )
				( pin "a"
					( attribute "PN" "1"
						( Origin gPackager )
					)
					( objectStatus "R4E19.1" )
				)
				( pin "b"
					( attribute "PN" "2"
						( Origin gPackager )
					)
					( objectStatus "R4E19.2" )
				)
			)
			( gate "@baseboard_fab2_lib.baseboard_fab2(sch_1):page203_i1"
				( attribute "CDS_LIB" "mstr_discrete"
					( Origin gPackager )
				)
				( attribute "CDS_LOCATION" "C6P24"
					( Origin gPackager )
				)
				( attribute "CDS_SEC" "1"
					( Origin gPackager )
				)
				( attribute "LOCATION" "C6P24"
					( Origin gFrontEnd )
				)
				( attribute "MATERIAL" "X6S"
					( Origin gFrontEnd )
				)
				( attribute "PACK_TYPE" "0805"
					( Origin gFrontEnd )
				)
				( attribute "PART_NUMBER" "C95333-007"
					( Origin gFrontEnd )
				)
				( attribute "PHYS_PAGE" "203"
					( Origin gFrontEnd )
				)
				( attribute "ROOM" "PVCCIN_CPU0_PWR_VR"
					( Origin gFrontEnd )
				)
				( attribute "ROT" "0"
					( Origin gFrontEnd )
				)
				( attribute "SEC" "1"
					( Origin gFrontEnd )
				)
				( attribute "SEC_TYPE" "0805"
					( Origin gFrontEnd )
				)
				( attribute "TOLERANCE" "10%"
					( Origin gFrontEnd )
				)
				( attribute "VALUE" "10UF"
					( Origin gFrontEnd )
				)
				( attribute "VER" "1"
					( Origin gFrontEnd )
				)
				( attribute "VOLTAGE" "16V"
					( Units "uVoltage" "V" 1.000000)
					( Origin gFrontEnd )
				)
				( attribute "XY" "(-6850,4175)"
					( Origin gFrontEnd )
				)
				( attribute "CHIPS_PART_NAME" "CAP"
					( Origin gPackager )
				)
				( attribute "CDS_PART_NAME" "CAP_0805-10UF,16V,10%,X6S,C953A"
					( Origin gPackager )
				)
				( objectStatus "C6P24" )
				( pin "a"
					( attribute "PN" "1"
						( Origin gPackager )
					)
					( objectStatus "C6P24.1" )
				)
				( pin "b"
					( attribute "PN" "2"
						( Origin gPackager )
					)
					( objectStatus "C6P24.2" )
				)
			)
			( gate "@baseboard_fab2_lib.baseboard_fab2(sch_1):page203_i2"
				( attribute "CDS_LIB" "mstr_discrete"
					( Origin gPackager )
				)
				( attribute "CDS_LOCATION" "C6R6"
					( Origin gPackager )
				)
				( attribute "CDS_SEC" "1"
					( Origin gPackager )
				)
				( attribute "LOCATION" "C6R6"
					( Origin gFrontEnd )
				)
				( attribute "MATERIAL" "X6S"
					( Origin gFrontEnd )
				)
				( attribute "PACK_TYPE" "0805"
					( Origin gFrontEnd )
				)
				( attribute "PART_NUMBER" "C95333-007"
					( Origin gFrontEnd )
				)
				( attribute "PHYS_PAGE" "203"
					( Origin gFrontEnd )
				)
				( attribute "ROOM" "PVCCIN_CPU0_PWR_VR"
					( Origin gFrontEnd )
				)
				( attribute "ROT" "0"
					( Origin gFrontEnd )
				)
				( attribute "SEC" "1"
					( Origin gFrontEnd )
				)
				( attribute "SEC_TYPE" "0805"
					( Origin gFrontEnd )
				)
				( attribute "TOLERANCE" "10%"
					( Origin gFrontEnd )
				)
				( attribute "VALUE" "10UF"
					( Origin gFrontEnd )
				)
				( attribute "VER" "1"
					( Origin gFrontEnd )
				)
				( attribute "VOLTAGE" "16V"
					( Units "uVoltage" "V" 1.000000)
					( Origin gFrontEnd )
				)
				( attribute "XY" "(-7125,4150)"
					( Origin gFrontEnd )
				)
				( attribute "CHIPS_PART_NAME" "CAP"
					( Origin gPackager )
				)
				( attribute "CDS_PART_NAME" "CAP_0805-10UF,16V,10%,X6S,C953A"
					( Origin gPackager )
				)
				( objectStatus "C6R6" )
				( pin "a"
					( attribute "PN" "1"
						( Origin gPackager )
					)
					( objectStatus "C6R6.1" )
				)
				( pin "b"
					( attribute "PN" "2"
						( Origin gPackager )
					)
					( objectStatus "C6R6.2" )
				)
			)
			( gate "@baseboard_fab2_lib.baseboard_fab2(sch_1):page203_i3"
				( attribute "CDS_LIB" "mstr_discrete"
					( Origin gPackager )
				)
				( attribute "CDS_LOCATION" "C4D9"
					( Origin gPackager )
				)
				( attribute "CDS_SEC" "1"
					( Origin gPackager )
				)
				( attribute "LOCATION" "C4D9"
					( Origin gFrontEnd )
				)
				( attribute "MATERIAL" "X7R"
					( Origin gFrontEnd )
				)
				( attribute "NO_XNET_CONNECTION" "1"
					( Origin gFrontEnd )
				)
				( attribute "PACK_TYPE" "0402"
					( Origin gFrontEnd )
				)
				( attribute "PART_NUMBER" "A36096-104"
					( Origin gFrontEnd )
				)
				( attribute "PHYS_PAGE" "203"
					( Origin gFrontEnd )
				)
				( attribute "ROOM" "PVCCIN_CPU0_PWR_VR"
					( Origin gFrontEnd )
				)
				( attribute "ROT" "2"
					( Origin gFrontEnd )
				)
				( attribute "SEC" "1"
					( Origin gFrontEnd )
				)
				( attribute "SEC_TYPE" "0402"
					( Origin gFrontEnd )
				)
				( attribute "SPOF" "TRUE"
					( Origin gFrontEnd )
				)
				( attribute "TOLERANCE" "10%"
					( Origin gFrontEnd )
				)
				( attribute "VALUE" "0.220UF"
					( Origin gFrontEnd )
				)
				( attribute "VER" "1"
					( Origin gFrontEnd )
				)
				( attribute "VOLTAGE" "16V"
					( Units "uVoltage" "V" 1.000000)
					( Origin gFrontEnd )
				)
				( attribute "XY" "(-6100,800)"
					( Origin gFrontEnd )
				)
				( attribute "CHIPS_PART_NAME" "CAP"
					( Origin gPackager )
				)
				( attribute "CDS_PART_NAME" "CAP_0402-0.220UF,16V,10%,X7R,AA"
					( Origin gPackager )
				)
				( objectStatus "C4D9" )
				( pin "a"
					( attribute "PN" "1"
						( Origin gPackager )
					)
					( objectStatus "C4D9.1" )
				)
				( pin "b"
					( attribute "PN" "2"
						( Origin gPackager )
					)
					( objectStatus "C4D9.2" )
				)
			)
			( gate "@baseboard_fab2_lib.baseboard_fab2(sch_1):page203_i15"
				( attribute "CDS_LIB" "mstr_discrete"
					( Origin gPackager )
				)
				( attribute "CDS_LOCATION" "L4D2"
					( Origin gPackager )
				)
				( attribute "CDS_SEC" "1"
					( Origin gPackager )
				)
				( attribute "LOCATION" "L4D2"
					( Origin gFrontEnd )
				)
				( attribute "MATERIAL" "IND"
					( Origin gFrontEnd )
				)
				( attribute "PACK_TYPE" "SM"
					( Origin gFrontEnd )
				)
				( attribute "PART_NUMBER" "D92183-034"
					( Origin gFrontEnd )
				)
				( attribute "PHYS_PAGE" "203"
					( Origin gFrontEnd )
				)
				( attribute "ROOM" "PVCCIN_CPU0_PWR_VR"
					( Origin gFrontEnd )
				)
				( attribute "ROT" "0"
					( Origin gFrontEnd )
				)
				( attribute "SEC" "1"
					( Origin gPackager )
				)
				( attribute "VALUE" "0.12UH"
					( Origin gFrontEnd )
				)
				( attribute "VER" "1"
					( Origin gFrontEnd )
				)
				( attribute "XY" "(-1550,3625)"
					( Origin gFrontEnd )
				)
				( attribute "CHIPS_PART_NAME" "INDUCTOR"
					( Origin gPackager )
				)
				( attribute "CDS_PART_NAME" "INDUCTOR_SM-0.12UH,IND,D92183-A"
					( Origin gPackager )
				)
				( objectStatus "L4D2" )
				( pin "ina"
					( attribute "PN" "1"
						( Origin gPackager )
					)
					( objectStatus "L4D2.1" )
				)
				( pin "inb"
					( attribute "PN" "2"
						( Origin gPackager )
					)
					( objectStatus "L4D2.2" )
				)
			)
			( gate "@baseboard_fab2_lib.baseboard_fab2(sch_1):page203_i16"
				( attribute "BOM_COST" "PROC_VRD_VCCIN_CPU0"
					( Origin gFrontEnd )
				)
				( attribute "CDS_LIB" "mstr_discrete"
					( Origin gPackager )
				)
				( attribute "CDS_LOCATION" "C6R3"
					( Origin gPackager )
				)
				( attribute "CDS_SEC" "1"
					( Origin gPackager )
				)
				( attribute "LOCATION" "C6R3"
					( Origin gFrontEnd )
				)
				( attribute "MATERIAL" "ALUM"
					( Origin gFrontEnd )
				)
				( attribute "PACK_TYPE" "3018"
					( Origin gFrontEnd )
				)
				( attribute "PART_NUMBER" "699013-049"
					( Origin gFrontEnd )
				)
				( attribute "PHYS_PAGE" "203"
					( Origin gFrontEnd )
				)
				( attribute "ROOM" "PVCCIN_CPU0_DECAP_VR"
					( Origin gFrontEnd )
				)
				( attribute "ROT" "0"
					( Origin gFrontEnd )
				)
				( attribute "SEC" "1"
					( Origin gFrontEnd )
				)
				( attribute "SEC_TYPE" "3018"
					( Origin gFrontEnd )
				)
				( attribute "TOLERANCE" "20%"
					( Origin gFrontEnd )
				)
				( attribute "VALUE" "470UF"
					( Origin gFrontEnd )
				)
				( attribute "VER" "1"
					( Origin gFrontEnd )
				)
				( attribute "VOLTAGE" "2.5V"
					( Units "uVoltage" "V" 1.000000)
					( Origin gFrontEnd )
				)
				( attribute "XY" "(-1150,2575)"
					( Origin gFrontEnd )
				)
				( attribute "CHIPS_PART_NAME" "CAPP"
					( Origin gPackager )
				)
				( attribute "CDS_PART_NAME" "CAPP_3018-470UF,2.5V,20%,ALUM,A"
					( Origin gPackager )
				)
				( objectStatus "C6R3" )
				( pin "a"
					( attribute "PN" "1"
						( Origin gPackager )
					)
					( objectStatus "C6R3.1" )
				)
				( pin "b"
					( attribute "PN" "2"
						( Origin gPackager )
					)
					( objectStatus "C6R3.2" )
				)
			)
			( gate "@baseboard_fab2_lib.baseboard_fab2(sch_1):page203_i18"
				( attribute "BOM_COST" "PROC_VRD_VCCIN_CPU0"
					( Origin gFrontEnd )
				)
				( attribute "CDS_LIB" "mstr_discrete"
					( Origin gPackager )
				)
				( attribute "CDS_LOCATION" "C6R9"
					( Origin gPackager )
				)
				( attribute "CDS_SEC" "1"
					( Origin gPackager )
				)
				( attribute "LOCATION" "C6R9"
					( Origin gFrontEnd )
				)
				( attribute "MATERIAL" "ALUM"
					( Origin gFrontEnd )
				)
				( attribute "PACK_TYPE" "3018"
					( Origin gFrontEnd )
				)
				( attribute "PART_NUMBER" "699013-049"
					( Origin gFrontEnd )
				)
				( attribute "PHYS_PAGE" "203"
					( Origin gFrontEnd )
				)
				( attribute "ROOM" "PVCCIN_CPU0_DECAP_VR"
					( Origin gFrontEnd )
				)
				( attribute "ROT" "0"
					( Origin gFrontEnd )
				)
				( attribute "SEC" "1"
					( Origin gFrontEnd )
				)
				( attribute "SEC_TYPE" "3018"
					( Origin gFrontEnd )
				)
				( attribute "TOLERANCE" "20%"
					( Origin gFrontEnd )
				)
				( attribute "VALUE" "470UF"
					( Origin gFrontEnd )
				)
				( attribute "VER" "1"
					( Origin gFrontEnd )
				)
				( attribute "VOLTAGE" "2.5V"
					( Units "uVoltage" "V" 1.000000)
					( Origin gFrontEnd )
				)
				( attribute "XY" "(-1625,2575)"
					( Origin gFrontEnd )
				)
				( attribute "CHIPS_PART_NAME" "CAPP"
					( Origin gPackager )
				)
				( attribute "CDS_PART_NAME" "CAPP_3018-470UF,2.5V,20%,ALUM,A"
					( Origin gPackager )
				)
				( objectStatus "C6R9" )
				( pin "a"
					( attribute "PN" "1"
						( Origin gPackager )
					)
					( objectStatus "C6R9.1" )
				)
				( pin "b"
					( attribute "PN" "2"
						( Origin gPackager )
					)
					( objectStatus "C6R9.2" )
				)
			)
			( gate "@baseboard_fab2_lib.baseboard_fab2(sch_1):page203_i24"
				( attribute "CDS_LIB" "mstr_discrete"
					( Origin gPackager )
				)
				( attribute "CDS_LOCATION" "L4D1"
					( Origin gPackager )
				)
				( attribute "CDS_SEC" "1"
					( Origin gPackager )
				)
				( attribute "LOCATION" "L4D1"
					( Origin gFrontEnd )
				)
				( attribute "MATERIAL" "IND"
					( Origin gFrontEnd )
				)
				( attribute "PACK_TYPE" "SM"
					( Origin gFrontEnd )
				)
				( attribute "PART_NUMBER" "D92183-034"
					( Origin gFrontEnd )
				)
				( attribute "PHYS_PAGE" "203"
					( Origin gFrontEnd )
				)
				( attribute "ROOM" "PVCCIN_CPU0_PWR_VR"
					( Origin gFrontEnd )
				)
				( attribute "ROT" "0"
					( Origin gFrontEnd )
				)
				( attribute "SEC" "1"
					( Origin gPackager )
				)
				( attribute "VALUE" "0.12UH"
					( Origin gFrontEnd )
				)
				( attribute "VER" "1"
					( Origin gFrontEnd )
				)
				( attribute "XY" "(-1650,900)"
					( Origin gFrontEnd )
				)
				( attribute "CHIPS_PART_NAME" "INDUCTOR"
					( Origin gPackager )
				)
				( attribute "CDS_PART_NAME" "INDUCTOR_SM-0.12UH,IND,D92183-A"
					( Origin gPackager )
				)
				( objectStatus "L4D1" )
				( pin "ina"
					( attribute "PN" "1"
						( Origin gPackager )
					)
					( objectStatus "L4D1.1" )
				)
				( pin "inb"
					( attribute "PN" "2"
						( Origin gPackager )
					)
					( objectStatus "L4D1.2" )
				)
			)
			( gate "@baseboard_fab2_lib.baseboard_fab2(sch_1):page203_i25"
				( attribute "BOM_COST" "PROC_VRD_VCCIN_CPU0"
					( Origin gFrontEnd )
				)
				( attribute "CDS_LIB" "dev_discrete"
					( Origin gPackager )
				)
				( attribute "CDS_LOCATION" "C6P3"
					( Origin gPackager )
				)
				( attribute "CDS_SEC" "1"
					( Origin gPackager )
				)
				( attribute "LOCATION" "C6P3"
					( Origin gFrontEnd )
				)
				( attribute "MATERIAL" "X6S"
					( Origin gFrontEnd )
				)
				( attribute "PACK_TYPE" "0603V"
					( Origin gFrontEnd )
				)
				( attribute "PART_NUMBER" "E15431-004"
					( Origin gFrontEnd )
				)
				( attribute "PHYS_PAGE" "203"
					( Origin gFrontEnd )
				)
				( attribute "ROOM" "PVCCIN_CPU0_PWR_VR"
					( Origin gFrontEnd )
				)
				( attribute "ROT" "0"
					( Origin gFrontEnd )
				)
				( attribute "SEC" "1"
					( Origin gFrontEnd )
				)
				( attribute "SEC_TYPE" "0603V"
					( Origin gFrontEnd )
				)
				( attribute "TOLERANCE" "20%"
					( Origin gFrontEnd )
				)
				( attribute "VALUE" "22.0UF"
					( Origin gFrontEnd )
				)
				( attribute "VER" "1"
					( Origin gFrontEnd )
				)
				( attribute "VOLTAGE" "4V"
					( Units "uVoltage" "V" 1.000000)
					( Origin gFrontEnd )
				)
				( attribute "XY" "(-1025,600)"
					( Origin gFrontEnd )
				)
				( attribute "CHIPS_PART_NAME" "CAP_A"
					( Origin gPackager )
				)
				( attribute "CDS_PART_NAME" "CAP_A_0603V-22.0UF,4V,20%,X6S,A"
					( Origin gPackager )
				)
				( objectStatus "C6P3" )
				( pin "a"
					( attribute "PN" "1"
						( Origin gPackager )
					)
					( objectStatus "C6P3.1" )
				)
				( pin "b"
					( attribute "PN" "2"
						( Origin gPackager )
					)
					( objectStatus "C6P3.2" )
				)
			)
			( gate "@baseboard_fab2_lib.baseboard_fab2(sch_1):page203_i28"
				( attribute "BOM_COST" "PROC_VRD_VCCIN_CPU0"
					( Origin gFrontEnd )
				)
				( attribute "CDS_LIB" "mstr_discrete"
					( Origin gPackager )
				)
				( attribute "CDS_LOCATION" "C6P23"
					( Origin gPackager )
				)
				( attribute "CDS_SEC" "1"
					( Origin gPackager )
				)
				( attribute "LOCATION" "C6P23"
					( Origin gFrontEnd )
				)
				( attribute "MATERIAL" "ALUM"
					( Origin gFrontEnd )
				)
				( attribute "PACK_TYPE" "3018"
					( Origin gFrontEnd )
				)
				( attribute "PART_NUMBER" "699013-049"
					( Origin gFrontEnd )
				)
				( attribute "PHYS_PAGE" "203"
					( Origin gFrontEnd )
				)
				( attribute "ROOM" "PVCCIN_CPU0_DECAP_VR"
					( Origin gFrontEnd )
				)
				( attribute "ROT" "0"
					( Origin gFrontEnd )
				)
				( attribute "SEC" "1"
					( Origin gFrontEnd )
				)
				( attribute "SEC_TYPE" "3018"
					( Origin gFrontEnd )
				)
				( attribute "TOLERANCE" "20%"
					( Origin gFrontEnd )
				)
				( attribute "VALUE" "470UF"
					( Origin gFrontEnd )
				)
				( attribute "VER" "1"
					( Origin gFrontEnd )
				)
				( attribute "VOLTAGE" "2.5V"
					( Units "uVoltage" "V" 1.000000)
					( Origin gFrontEnd )
				)
				( attribute "XY" "(-2075,2550)"
					( Origin gFrontEnd )
				)
				( attribute "CHIPS_PART_NAME" "CAPP"
					( Origin gPackager )
				)
				( attribute "CDS_PART_NAME" "CAPP_3018-470UF,2.5V,20%,ALUM,A"
					( Origin gPackager )
				)
				( objectStatus "C6P23" )
				( pin "a"
					( attribute "PN" "1"
						( Origin gPackager )
					)
					( objectStatus "C6P23.1" )
				)
				( pin "b"
					( attribute "PN" "2"
						( Origin gPackager )
					)
					( objectStatus "C6P23.2" )
				)
			)
			( gate "@baseboard_fab2_lib.baseboard_fab2(sch_1):page203_i29"
				( attribute "BOM_COST" "PROC_VRD_VCCIN_CPU0"
					( Origin gFrontEnd )
				)
				( attribute "CDS_LIB" "mstr_discrete"
					( Origin gPackager )
				)
				( attribute "CDS_LOCATION" "C6P14"
					( Origin gPackager )
				)
				( attribute "CDS_SEC" "1"
					( Origin gPackager )
				)
				( attribute "LOCATION" "C6P14"
					( Origin gFrontEnd )
				)
				( attribute "MATERIAL" "ALUM"
					( Origin gFrontEnd )
				)
				( attribute "PACK_TYPE" "3018"
					( Origin gFrontEnd )
				)
				( attribute "PART_NUMBER" "699013-049"
					( Origin gFrontEnd )
				)
				( attribute "PHYS_PAGE" "203"
					( Origin gFrontEnd )
				)
				( attribute "ROOM" "PVCCIN_CPU0_DECAP_VR"
					( Origin gFrontEnd )
				)
				( attribute "ROT" "0"
					( Origin gFrontEnd )
				)
				( attribute "SEC" "1"
					( Origin gFrontEnd )
				)
				( attribute "SEC_TYPE" "3018"
					( Origin gFrontEnd )
				)
				( attribute "TOLERANCE" "20%"
					( Origin gFrontEnd )
				)
				( attribute "VALUE" "470UF"
					( Origin gFrontEnd )
				)
				( attribute "VER" "1"
					( Origin gFrontEnd )
				)
				( attribute "VOLTAGE" "2.5V"
					( Units "uVoltage" "V" 1.000000)
					( Origin gFrontEnd )
				)
				( attribute "XY" "(-2525,2575)"
					( Origin gFrontEnd )
				)
				( attribute "CHIPS_PART_NAME" "CAPP"
					( Origin gPackager )
				)
				( attribute "CDS_PART_NAME" "CAPP_3018-470UF,2.5V,20%,ALUM,A"
					( Origin gPackager )
				)
				( objectStatus "C6P14" )
				( pin "a"
					( attribute "PN" "1"
						( Origin gPackager )
					)
					( objectStatus "C6P14.1" )
				)
				( pin "b"
					( attribute "PN" "2"
						( Origin gPackager )
					)
					( objectStatus "C6P14.2" )
				)
			)
			( gate "@baseboard_fab2_lib.baseboard_fab2(sch_1):page203_i30"
				( attribute "BOM_COST" "PROC_VRD_VCCIN_CPU0"
					( Origin gFrontEnd )
				)
				( attribute "CDS_LIB" "mstr_discrete"
					( Origin gPackager )
				)
				( attribute "CDS_LOCATION" "C6P18"
					( Origin gPackager )
				)
				( attribute "CDS_SEC" "1"
					( Origin gPackager )
				)
				( attribute "LOCATION" "C6P18"
					( Origin gFrontEnd )
				)
				( attribute "MATERIAL" "ALUM"
					( Origin gFrontEnd )
				)
				( attribute "PACK_TYPE" "3018"
					( Origin gFrontEnd )
				)
				( attribute "PART_NUMBER" "699013-049"
					( Origin gFrontEnd )
				)
				( attribute "PHYS_PAGE" "203"
					( Origin gFrontEnd )
				)
				( attribute "ROOM" "PVCCIN_CPU0_DECAP_VR"
					( Origin gFrontEnd )
				)
				( attribute "ROT" "0"
					( Origin gFrontEnd )
				)
				( attribute "SEC" "1"
					( Origin gFrontEnd )
				)
				( attribute "SEC_TYPE" "3018"
					( Origin gFrontEnd )
				)
				( attribute "TOLERANCE" "20%"
					( Origin gFrontEnd )
				)
				( attribute "VALUE" "470UF"
					( Origin gFrontEnd )
				)
				( attribute "VER" "1"
					( Origin gFrontEnd )
				)
				( attribute "VOLTAGE" "2.5V"
					( Units "uVoltage" "V" 1.000000)
					( Origin gFrontEnd )
				)
				( attribute "XY" "(-2975,2575)"
					( Origin gFrontEnd )
				)
				( attribute "CHIPS_PART_NAME" "CAPP"
					( Origin gPackager )
				)
				( attribute "CDS_PART_NAME" "CAPP_3018-470UF,2.5V,20%,ALUM,A"
					( Origin gPackager )
				)
				( objectStatus "C6P18" )
				( pin "a"
					( attribute "PN" "1"
						( Origin gPackager )
					)
					( objectStatus "C6P18.1" )
				)
				( pin "b"
					( attribute "PN" "2"
						( Origin gPackager )
					)
					( objectStatus "C6P18.2" )
				)
			)
			( gate "@baseboard_fab2_lib.baseboard_fab2(sch_1):page203_i32"
				( attribute "BOM_COST" "PROC_VRD_VCCIN_CPU0"
					( Origin gFrontEnd )
				)
				( attribute "CDS_LIB" "mstr_discrete"
					( Origin gPackager )
				)
				( attribute "CDS_LOCATION" "C6P8"
					( Origin gPackager )
				)
				( attribute "CDS_SEC" "1"
					( Origin gPackager )
				)
				( attribute "LOCATION" "C6P8"
					( Origin gFrontEnd )
				)
				( attribute "MATERIAL" "ALUM"
					( Origin gFrontEnd )
				)
				( attribute "PACK_TYPE" "3018"
					( Origin gFrontEnd )
				)
				( attribute "PART_NUMBER" "699013-049"
					( Origin gFrontEnd )
				)
				( attribute "PHYS_PAGE" "203"
					( Origin gFrontEnd )
				)
				( attribute "ROOM" "PVCCIN_CPU0_DECAP_VR"
					( Origin gFrontEnd )
				)
				( attribute "ROT" "0"
					( Origin gFrontEnd )
				)
				( attribute "SEC" "1"
					( Origin gFrontEnd )
				)
				( attribute "SEC_TYPE" "3018"
					( Origin gFrontEnd )
				)
				( attribute "TOLERANCE" "20%"
					( Origin gFrontEnd )
				)
				( attribute "VALUE" "470UF"
					( Origin gFrontEnd )
				)
				( attribute "VER" "1"
					( Origin gFrontEnd )
				)
				( attribute "VOLTAGE" "2.5V"
					( Units "uVoltage" "V" 1.000000)
					( Origin gFrontEnd )
				)
				( attribute "XY" "(-3425,2575)"
					( Origin gFrontEnd )
				)
				( attribute "CHIPS_PART_NAME" "CAPP"
					( Origin gPackager )
				)
				( attribute "CDS_PART_NAME" "CAPP_3018-470UF,2.5V,20%,ALUM,A"
					( Origin gPackager )
				)
				( objectStatus "C6P8" )
				( pin "a"
					( attribute "PN" "1"
						( Origin gPackager )
					)
					( objectStatus "C6P8.1" )
				)
				( pin "b"
					( attribute "PN" "2"
						( Origin gPackager )
					)
					( objectStatus "C6P8.2" )
				)
			)
			( gate "@baseboard_fab2_lib.baseboard_fab2(sch_1):page203_i34"
				( attribute "BOM_COST" "PROC_VRD_VCCIN_CPU0"
					( Origin gFrontEnd )
				)
				( attribute "CDS_LIB" "mstr_discrete"
					( Origin gPackager )
				)
				( attribute "CDS_LOCATION" "C6N9"
					( Origin gPackager )
				)
				( attribute "CDS_SEC" "1"
					( Origin gPackager )
				)
				( attribute "LOCATION" "C6N9"
					( Origin gFrontEnd )
				)
				( attribute "MATERIAL" "ALUM"
					( Origin gFrontEnd )
				)
				( attribute "PACK_TYPE" "3018"
					( Origin gFrontEnd )
				)
				( attribute "PART_NUMBER" "699013-049"
					( Origin gFrontEnd )
				)
				( attribute "PHYS_PAGE" "203"
					( Origin gFrontEnd )
				)
				( attribute "ROOM" "PVCCIN_CPU0_DECAP_VR"
					( Origin gFrontEnd )
				)
				( attribute "ROT" "0"
					( Origin gFrontEnd )
				)
				( attribute "SEC" "1"
					( Origin gFrontEnd )
				)
				( attribute "SEC_TYPE" "3018"
					( Origin gFrontEnd )
				)
				( attribute "TOLERANCE" "20%"
					( Origin gFrontEnd )
				)
				( attribute "VALUE" "470UF"
					( Origin gFrontEnd )
				)
				( attribute "VER" "1"
					( Origin gFrontEnd )
				)
				( attribute "VOLTAGE" "2.5V"
					( Units "uVoltage" "V" 1.000000)
					( Origin gFrontEnd )
				)
				( attribute "XY" "(-3850,2575)"
					( Origin gFrontEnd )
				)
				( attribute "CHIPS_PART_NAME" "CAPP"
					( Origin gPackager )
				)
				( attribute "CDS_PART_NAME" "CAPP_3018-470UF,2.5V,20%,ALUM,A"
					( Origin gPackager )
				)
				( objectStatus "C6N9" )
				( pin "a"
					( attribute "PN" "1"
						( Origin gPackager )
					)
					( objectStatus "C6N9.1" )
				)
				( pin "b"
					( attribute "PN" "2"
						( Origin gPackager )
					)
					( objectStatus "C6N9.2" )
				)
			)
			( gate "@baseboard_fab2_lib.baseboard_fab2(sch_1):page203_i38"
				( attribute "CDS_LIB" "mstr_discrete"
					( Origin gPackager )
				)
				( attribute "CDS_LOCATION" "R6P19"
					( Origin gPackager )
				)
				( attribute "CDS_SEC" "1"
					( Origin gPackager )
				)
				( attribute "LOCATION" "R6P19"
					( Origin gFrontEnd )
				)
				( attribute "MATERIAL" "CHIP"
					( Origin gFrontEnd )
				)
				( attribute "PACK_TYPE" "0402"
					( Origin gFrontEnd )
				)
				( attribute "PART_NUMBER" "G21796-090"
					( Origin gFrontEnd )
				)
				( attribute "PHYS_PAGE" "203"
					( Origin gFrontEnd )
				)
				( attribute "ROOM" "PVCCIN_CPU0_PWR_VR"
					( Origin gFrontEnd )
				)
				( attribute "ROT" "0"
					( Origin gFrontEnd )
				)
				( attribute "SEC" "1"
					( Origin gFrontEnd )
				)
				( attribute "SEC_TYPE" "0402"
					( Origin gFrontEnd )
				)
				( attribute "TOLERANCE" "1%"
					( Origin gFrontEnd )
				)
				( attribute "VALUE" "1.0"
					( Origin gFrontEnd )
				)
				( attribute "VER" "1"
					( Origin gFrontEnd )
				)
				( attribute "WATTAGE" "1/16W"
					( Origin gFrontEnd )
				)
				( attribute "XY" "(-5850,4725)"
					( Origin gFrontEnd )
				)
				( attribute "CHIPS_PART_NAME" "RES"
					( Origin gPackager )
				)
				( attribute "CDS_PART_NAME" "RES_0402-1.0,1%,1/16W,CHIP,G21A"
					( Origin gPackager )
				)
				( objectStatus "R6P19" )
				( pin "a"
					( attribute "PN" "1"
						( Origin gPackager )
					)
					( objectStatus "R6P19.1" )
				)
				( pin "b"
					( attribute "PN" "2"
						( Origin gPackager )
					)
					( objectStatus "R6P19.2" )
				)
			)
			( gate "@baseboard_fab2_lib.baseboard_fab2(sch_1):page203_i40"
				( attribute "CDS_LIB" "mstr_discrete"
					( Origin gPackager )
				)
				( attribute "CDS_LOCATION" "C4D13"
					( Origin gPackager )
				)
				( attribute "CDS_SEC" "1"
					( Origin gPackager )
				)
				( attribute "LOCATION" "C4D13"
					( Origin gFrontEnd )
				)
				( attribute "MATERIAL" "X7R"
					( Origin gFrontEnd )
				)
				( attribute "PACK_TYPE" "0402"
					( Origin gFrontEnd )
				)
				( attribute "PART_NUMBER" "A36096-155"
					( Origin gFrontEnd )
				)
				( attribute "PHYS_PAGE" "203"
					( Origin gFrontEnd )
				)
				( attribute "ROOM" "PVCCIN_CPU0_PWR_VR"
					( Origin gFrontEnd )
				)
				( attribute "ROT" "0"
					( Origin gFrontEnd )
				)
				( attribute "SEC" "1"
					( Origin gFrontEnd )
				)
				( attribute "SEC_TYPE" "0402"
					( Origin gFrontEnd )
				)
				( attribute "TOLERANCE" "10%"
					( Origin gFrontEnd )
				)
				( attribute "VALUE" "0.22UF"
					( Origin gFrontEnd )
				)
				( attribute "VER" "1"
					( Origin gFrontEnd )
				)
				( attribute "VOLTAGE" "16V"
					( Units "uVoltage" "V" 1.000000)
					( Origin gFrontEnd )
				)
				( attribute "XY" "(-5300,4125)"
					( Origin gFrontEnd )
				)
				( attribute "CHIPS_PART_NAME" "CAP"
					( Origin gPackager )
				)
				( attribute "CDS_PART_NAME" "CAP_0402-0.22UF,16V,10%,X7R,A3A"
					( Origin gPackager )
				)
				( objectStatus "C4D13" )
				( pin "a"
					( attribute "PN" "1"
						( Origin gPackager )
					)
					( objectStatus "C4D13.1" )
				)
				( pin "b"
					( attribute "PN" "2"
						( Origin gPackager )
					)
					( objectStatus "C4D13.2" )
				)
			)
			( gate "@baseboard_fab2_lib.baseboard_fab2(sch_1):page203_i41"
				( attribute "CDS_LIB" "dev_discrete"
					( Origin gPackager )
				)
				( attribute "CDS_LOCATION" "C4D14"
					( Origin gPackager )
				)
				( attribute "CDS_SEC" "1"
					( Origin gPackager )
				)
				( attribute "LOCATION" "C4D14"
					( Origin gFrontEnd )
				)
				( attribute "MATERIAL" "X6S"
					( Origin gFrontEnd )
				)
				( attribute "PACK_TYPE" "0402V"
					( Origin gFrontEnd )
				)
				( attribute "PART_NUMBER" "D97712-004"
					( Origin gFrontEnd )
				)
				( attribute "PHYS_PAGE" "203"
					( Origin gFrontEnd )
				)
				( attribute "ROOM" "PVCCIN_CPU0_PWR_VR"
					( Origin gFrontEnd )
				)
				( attribute "ROT" "2"
					( Origin gFrontEnd )
				)
				( attribute "SEC" "1"
					( Origin gFrontEnd )
				)
				( attribute "SEC_TYPE" "0402V"
					( Origin gFrontEnd )
				)
				( attribute "TOLERANCE" "10%"
					( Origin gFrontEnd )
				)
				( attribute "VALUE" "1.0UF"
					( Origin gFrontEnd )
				)
				( attribute "VER" "1"
					( Origin gFrontEnd )
				)
				( attribute "VOLTAGE" "6.3V"
					( Units "uVoltage" "V" 1.000000)
					( Origin gFrontEnd )
				)
				( attribute "XY" "(-5450,4150)"
					( Origin gFrontEnd )
				)
				( attribute "CHIPS_PART_NAME" "CAP_A"
					( Origin gPackager )
				)
				( attribute "CDS_PART_NAME" "CAP_A_0402V-1.0UF,6.3V,10%,X6SA"
					( Origin gPackager )
				)
				( objectStatus "C4D14" )
				( pin "a"
					( attribute "PN" "1"
						( Origin gPackager )
					)
					( objectStatus "C4D14.1" )
				)
				( pin "b"
					( attribute "PN" "2"
						( Origin gPackager )
					)
					( objectStatus "C4D14.2" )
				)
			)
			( gate "@baseboard_fab2_lib.baseboard_fab2(sch_1):page203_i42"
				( attribute "CDS_LIB" "mstr_discrete"
					( Origin gPackager )
				)
				( attribute "CDS_LOCATION" "C4D28"
					( Origin gPackager )
				)
				( attribute "LOCATION" "C4D28"
					( Origin gFrontEnd )
				)
				( attribute "MATERIAL" "X7R"
					( Origin gFrontEnd )
				)
				( attribute "NO_XNET_CONNECTION" "1"
					( Origin gFrontEnd )
				)
				( attribute "PACK_TYPE" "0402"
					( Origin gFrontEnd )
				)
				( attribute "PART_NUMBER" "A36096-104"
					( Origin gFrontEnd )
				)
				( attribute "PHYS_PAGE" "203"
					( Origin gFrontEnd )
				)
				( attribute "ROOM" "PVCCIN_CPU0_PWR_VR"
					( Origin gFrontEnd )
				)
				( attribute "ROT" "2"
					( Origin gFrontEnd )
				)
				( attribute "SEC" "1"
					( Origin gFrontEnd )
				)
				( attribute "SEC_TYPE" "0402"
					( Origin gFrontEnd )
				)
				( attribute "SPOF" "TRUE"
					( Origin gFrontEnd )
				)
				( attribute "TOLERANCE" "10%"
					( Origin gFrontEnd )
				)
				( attribute "VALUE" "0.220UF"
					( Origin gFrontEnd )
				)
				( attribute "VER" "1"
					( Origin gFrontEnd )
				)
				( attribute "VOLTAGE" "16V"
					( Units "uVoltage" "V" 1.000000)
					( Origin gFrontEnd )
				)
				( attribute "XY" "(-6025,3525)"
					( Origin gFrontEnd )
				)
				( attribute "CHIPS_PART_NAME" "CAP"
					( Origin gPackager )
				)
				( attribute "CDS_PART_NAME" "CAP_0402-0.220UF,16V,10%,X7R,AA"
					( Origin gPackager )
				)
				( attribute "CDS_SEC" "1"
					( Origin gPackager )
				)
				( objectStatus "C4D28" )
				( pin "a"
					( attribute "PN" "1"
						( Origin gPackager )
					)
					( objectStatus "C4D28.1" )
				)
				( pin "b"
					( attribute "PN" "2"
						( Origin gPackager )
					)
					( objectStatus "C4D28.2" )
				)
			)
			( gate "@baseboard_fab2_lib.baseboard_fab2(sch_1):page203_i45"
				( attribute "CDS_LIB" "mstr_discrete"
					( Origin gPackager )
				)
				( attribute "CDS_LOCATION" "C4D16"
					( Origin gPackager )
				)
				( attribute "CDS_SEC" "1"
					( Origin gPackager )
				)
				( attribute "LOCATION" "C4D16"
					( Origin gFrontEnd )
				)
				( attribute "MATERIAL" "X6S"
					( Origin gFrontEnd )
				)
				( attribute "PACK_TYPE" "0402"
					( Origin gFrontEnd )
				)
				( attribute "PART_NUMBER" "D97712-011"
					( Origin gFrontEnd )
				)
				( attribute "PHYS_PAGE" "203"
					( Origin gFrontEnd )
				)
				( attribute "ROOM" "PVCCIN_CPU0_PWR_VR"
					( Origin gFrontEnd )
				)
				( attribute "ROT" "0"
					( Origin gFrontEnd )
				)
				( attribute "SEC" "1"
					( Origin gFrontEnd )
				)
				( attribute "SEC_TYPE" "0402"
					( Origin gFrontEnd )
				)
				( attribute "TOLERANCE" "10%"
					( Origin gFrontEnd )
				)
				( attribute "VALUE" "1.0UF"
					( Origin gFrontEnd )
				)
				( attribute "VER" "1"
					( Origin gFrontEnd )
				)
				( attribute "VOLTAGE" "16V"
					( Units "uVoltage" "V" 1.000000)
					( Origin gFrontEnd )
				)
				( attribute "XY" "(-6075,4125)"
					( Origin gFrontEnd )
				)
				( attribute "CHIPS_PART_NAME" "CAP"
					( Origin gPackager )
				)
				( attribute "CDS_PART_NAME" "CAP_0402-1.0UF,16V,10%,X6S,D97A"
					( Origin gPackager )
				)
				( objectStatus "C4D16" )
				( pin "a"
					( attribute "PN" "1"
						( Origin gPackager )
					)
					( objectStatus "C4D16.1" )
				)
				( pin "b"
					( attribute "PN" "2"
						( Origin gPackager )
					)
					( objectStatus "C4D16.2" )
				)
			)
			( gate "@baseboard_fab2_lib.baseboard_fab2(sch_1):page203_i46"
				( attribute "CDS_LIB" "dev_discrete"
					( Origin gPackager )
				)
				( attribute "CDS_LOCATION" "C4D35"
					( Origin gPackager )
				)
				( attribute "CDS_SEC" "1"
					( Origin gPackager )
				)
				( attribute "LOCATION" "C4D35"
					( Origin gFrontEnd )
				)
				( attribute "MATERIAL" "X7R"
					( Origin gFrontEnd )
				)
				( attribute "PACK_TYPE" "0402V"
					( Origin gFrontEnd )
				)
				( attribute "PART_NUMBER" "A36096-030"
					( Origin gFrontEnd )
				)
				( attribute "PHYS_PAGE" "203"
					( Origin gFrontEnd )
				)
				( attribute "ROOM" "PVCCIN_CPU0_PWR_VR"
					( Origin gFrontEnd )
				)
				( attribute "ROT" "0"
					( Origin gFrontEnd )
				)
				( attribute "SEC" "1"
					( Origin gFrontEnd )
				)
				( attribute "SEC_TYPE" "0402V"
					( Origin gFrontEnd )
				)
				( attribute "TOLERANCE" "10%"
					( Origin gFrontEnd )
				)
				( attribute "VALUE" "0.1UF"
					( Origin gFrontEnd )
				)
				( attribute "VER" "1"
					( Origin gFrontEnd )
				)
				( attribute "VOLTAGE" "16V"
					( Units "uVoltage" "V" 1.000000)
					( Origin gFrontEnd )
				)
				( attribute "XY" "(-6350,4150)"
					( Origin gFrontEnd )
				)
				( attribute "CHIPS_PART_NAME" "CAP_A"
					( Origin gPackager )
				)
				( attribute "CDS_PART_NAME" "CAP_A_0402V-0.1UF,16V,10%,X7R,A"
					( Origin gPackager )
				)
				( objectStatus "C4D35" )
				( pin "a"
					( attribute "PN" "1"
						( Origin gPackager )
					)
					( objectStatus "C4D35.1" )
				)
				( pin "b"
					( attribute "PN" "2"
						( Origin gPackager )
					)
					( objectStatus "C4D35.2" )
				)
			)
			( gate "@baseboard_fab2_lib.baseboard_fab2(sch_1):page203_i47"
				( attribute "CDS_LIB" "mstr_discrete"
					( Origin gPackager )
				)
				( attribute "CDS_LOCATION" "C4D30"
					( Origin gPackager )
				)
				( attribute "CDS_SEC" "1"
					( Origin gPackager )
				)
				( attribute "LOCATION" "C4D30"
					( Origin gFrontEnd )
				)
				( attribute "MATERIAL" "X6S"
					( Origin gFrontEnd )
				)
				( attribute "PACK_TYPE" "0402"
					( Origin gFrontEnd )
				)
				( attribute "PART_NUMBER" "D97712-011"
					( Origin gFrontEnd )
				)
				( attribute "PHYS_PAGE" "203"
					( Origin gFrontEnd )
				)
				( attribute "ROOM" "PVCCIN_CPU0_PWR_VR"
					( Origin gFrontEnd )
				)
				( attribute "ROT" "0"
					( Origin gFrontEnd )
				)
				( attribute "SEC" "1"
					( Origin gFrontEnd )
				)
				( attribute "SEC_TYPE" "0402"
					( Origin gFrontEnd )
				)
				( attribute "TOLERANCE" "10%"
					( Origin gFrontEnd )
				)
				( attribute "VALUE" "1.0UF"
					( Origin gFrontEnd )
				)
				( attribute "VER" "1"
					( Origin gFrontEnd )
				)
				( attribute "VOLTAGE" "16V"
					( Units "uVoltage" "V" 1.000000)
					( Origin gFrontEnd )
				)
				( attribute "XY" "(-6600,4150)"
					( Origin gFrontEnd )
				)
				( attribute "CHIPS_PART_NAME" "CAP"
					( Origin gPackager )
				)
				( attribute "CDS_PART_NAME" "CAP_0402-1.0UF,16V,10%,X6S,D97A"
					( Origin gPackager )
				)
				( objectStatus "C4D30" )
				( pin "a"
					( attribute "PN" "1"
						( Origin gPackager )
					)
					( objectStatus "C4D30.1" )
				)
				( pin "b"
					( attribute "PN" "2"
						( Origin gPackager )
					)
					( objectStatus "C4D30.2" )
				)
			)
			( gate "@baseboard_fab2_lib.baseboard_fab2(sch_1):page203_i48"
				( attribute "CDS_LIB" "mstr_discrete"
					( Origin gPackager )
				)
				( attribute "CDS_LOCATION" "C4D5"
					( Origin gPackager )
				)
				( attribute "CDS_SEC" "1"
					( Origin gPackager )
				)
				( attribute "LOCATION" "C4D5"
					( Origin gFrontEnd )
				)
				( attribute "MATERIAL" "X7R"
					( Origin gFrontEnd )
				)
				( attribute "PACK_TYPE" "0402"
					( Origin gFrontEnd )
				)
				( attribute "PART_NUMBER" "A36096-155"
					( Origin gFrontEnd )
				)
				( attribute "PHYS_PAGE" "203"
					( Origin gFrontEnd )
				)
				( attribute "ROOM" "PVCCIN_CPU0_PWR_VR"
					( Origin gFrontEnd )
				)
				( attribute "ROT" "0"
					( Origin gFrontEnd )
				)
				( attribute "SEC" "1"
					( Origin gFrontEnd )
				)
				( attribute "SEC_TYPE" "0402"
					( Origin gFrontEnd )
				)
				( attribute "TOLERANCE" "10%"
					( Origin gFrontEnd )
				)
				( attribute "VALUE" "0.22UF"
					( Origin gFrontEnd )
				)
				( attribute "VER" "1"
					( Origin gFrontEnd )
				)
				( attribute "VOLTAGE" "16V"
					( Units "uVoltage" "V" 1.000000)
					( Origin gFrontEnd )
				)
				( attribute "XY" "(-5525,1475)"
					( Origin gFrontEnd )
				)
				( attribute "CHIPS_PART_NAME" "CAP"
					( Origin gPackager )
				)
				( attribute "CDS_PART_NAME" "CAP_0402-0.22UF,16V,10%,X7R,A3A"
					( Origin gPackager )
				)
				( objectStatus "C4D5" )
				( pin "a"
					( attribute "PN" "1"
						( Origin gPackager )
					)
					( objectStatus "C4D5.1" )
				)
				( pin "b"
					( attribute "PN" "2"
						( Origin gPackager )
					)
					( objectStatus "C4D5.2" )
				)
			)
			( gate "@baseboard_fab2_lib.baseboard_fab2(sch_1):page203_i49"
				( attribute "CDS_LIB" "dev_discrete"
					( Origin gPackager )
				)
				( attribute "CDS_LOCATION" "C4D6"
					( Origin gPackager )
				)
				( attribute "CDS_SEC" "1"
					( Origin gPackager )
				)
				( attribute "LOCATION" "C4D6"
					( Origin gFrontEnd )
				)
				( attribute "MATERIAL" "X6S"
					( Origin gFrontEnd )
				)
				( attribute "PACK_TYPE" "0402V"
					( Origin gFrontEnd )
				)
				( attribute "PART_NUMBER" "D97712-004"
					( Origin gFrontEnd )
				)
				( attribute "PHYS_PAGE" "203"
					( Origin gFrontEnd )
				)
				( attribute "ROOM" "PVCCIN_CPU0_PWR_VR"
					( Origin gFrontEnd )
				)
				( attribute "ROT" "2"
					( Origin gFrontEnd )
				)
				( attribute "SEC" "1"
					( Origin gFrontEnd )
				)
				( attribute "SEC_TYPE" "0402V"
					( Origin gFrontEnd )
				)
				( attribute "TOLERANCE" "10%"
					( Origin gFrontEnd )
				)
				( attribute "VALUE" "1.0UF"
					( Origin gFrontEnd )
				)
				( attribute "VER" "1"
					( Origin gFrontEnd )
				)
				( attribute "VOLTAGE" "6.3V"
					( Units "uVoltage" "V" 1.000000)
					( Origin gFrontEnd )
				)
				( attribute "XY" "(-5650,1475)"
					( Origin gFrontEnd )
				)
				( attribute "CHIPS_PART_NAME" "CAP_A"
					( Origin gPackager )
				)
				( attribute "CDS_PART_NAME" "CAP_A_0402V-1.0UF,6.3V,10%,X6SA"
					( Origin gPackager )
				)
				( objectStatus "C4D6" )
				( pin "a"
					( attribute "PN" "1"
						( Origin gPackager )
					)
					( objectStatus "C4D6.1" )
				)
				( pin "b"
					( attribute "PN" "2"
						( Origin gPackager )
					)
					( objectStatus "C4D6.2" )
				)
			)
			( gate "@baseboard_fab2_lib.baseboard_fab2(sch_1):page203_i50"
				( attribute "CDS_LIB" "mstr_discrete"
					( Origin gPackager )
				)
				( attribute "CDS_LOCATION" "R6P10"
					( Origin gPackager )
				)
				( attribute "CDS_SEC" "1"
					( Origin gPackager )
				)
				( attribute "LOCATION" "R6P10"
					( Origin gFrontEnd )
				)
				( attribute "MATERIAL" "CHIP"
					( Origin gFrontEnd )
				)
				( attribute "PACK_TYPE" "0402"
					( Origin gFrontEnd )
				)
				( attribute "PART_NUMBER" "G21796-090"
					( Origin gFrontEnd )
				)
				( attribute "PHYS_PAGE" "203"
					( Origin gFrontEnd )
				)
				( attribute "ROOM" "PVCCIN_CPU0_PWR_VR"
					( Origin gFrontEnd )
				)
				( attribute "ROT" "0"
					( Origin gFrontEnd )
				)
				( attribute "SEC" "1"
					( Origin gFrontEnd )
				)
				( attribute "SEC_TYPE" "0402"
					( Origin gFrontEnd )
				)
				( attribute "TOLERANCE" "1%"
					( Origin gFrontEnd )
				)
				( attribute "VALUE" "1.0"
					( Origin gFrontEnd )
				)
				( attribute "VER" "1"
					( Origin gFrontEnd )
				)
				( attribute "WATTAGE" "1/16W"
					( Origin gFrontEnd )
				)
				( attribute "XY" "(-5900,1975)"
					( Origin gFrontEnd )
				)
				( attribute "CHIPS_PART_NAME" "RES"
					( Origin gPackager )
				)
				( attribute "CDS_PART_NAME" "RES_0402-1.0,1%,1/16W,CHIP,G21A"
					( Origin gPackager )
				)
				( objectStatus "R6P10" )
				( pin "a"
					( attribute "PN" "1"
						( Origin gPackager )
					)
					( objectStatus "R6P10.1" )
				)
				( pin "b"
					( attribute "PN" "2"
						( Origin gPackager )
					)
					( objectStatus "R6P10.2" )
				)
			)
			( gate "@baseboard_fab2_lib.baseboard_fab2(sch_1):page203_i51"
				( attribute "CDS_LIB" "mstr_discrete"
					( Origin gPackager )
				)
				( attribute "CDS_LOCATION" "C4D7"
					( Origin gPackager )
				)
				( attribute "CDS_SEC" "1"
					( Origin gPackager )
				)
				( attribute "LOCATION" "C4D7"
					( Origin gFrontEnd )
				)
				( attribute "MATERIAL" "X6S"
					( Origin gFrontEnd )
				)
				( attribute "PACK_TYPE" "0402"
					( Origin gFrontEnd )
				)
				( attribute "PART_NUMBER" "D97712-011"
					( Origin gFrontEnd )
				)
				( attribute "PHYS_PAGE" "203"
					( Origin gFrontEnd )
				)
				( attribute "ROOM" "PVCCIN_CPU0_PWR_VR"
					( Origin gFrontEnd )
				)
				( attribute "ROT" "0"
					( Origin gFrontEnd )
				)
				( attribute "SEC" "1"
					( Origin gFrontEnd )
				)
				( attribute "SEC_TYPE" "0402"
					( Origin gFrontEnd )
				)
				( attribute "TOLERANCE" "10%"
					( Origin gFrontEnd )
				)
				( attribute "VALUE" "1.0UF"
					( Origin gFrontEnd )
				)
				( attribute "VER" "1"
					( Origin gFrontEnd )
				)
				( attribute "VOLTAGE" "16V"
					( Units "uVoltage" "V" 1.000000)
					( Origin gFrontEnd )
				)
				( attribute "XY" "(-6225,1450)"
					( Origin gFrontEnd )
				)
				( attribute "CHIPS_PART_NAME" "CAP"
					( Origin gPackager )
				)
				( attribute "CDS_PART_NAME" "CAP_0402-1.0UF,16V,10%,X6S,D97A"
					( Origin gPackager )
				)
				( objectStatus "C4D7" )
				( pin "a"
					( attribute "PN" "1"
						( Origin gPackager )
					)
					( objectStatus "C4D7.1" )
				)
				( pin "b"
					( attribute "PN" "2"
						( Origin gPackager )
					)
					( objectStatus "C4D7.2" )
				)
			)
			( gate "@baseboard_fab2_lib.baseboard_fab2(sch_1):page203_i52"
				( attribute "CDS_LIB" "dev_discrete"
					( Origin gPackager )
				)
				( attribute "CDS_LOCATION" "C4D11"
					( Origin gPackager )
				)
				( attribute "CDS_SEC" "1"
					( Origin gPackager )
				)
				( attribute "LOCATION" "C4D11"
					( Origin gFrontEnd )
				)
				( attribute "MATERIAL" "X7R"
					( Origin gFrontEnd )
				)
				( attribute "PACK_TYPE" "0402V"
					( Origin gFrontEnd )
				)
				( attribute "PART_NUMBER" "A36096-030"
					( Origin gFrontEnd )
				)
				( attribute "PHYS_PAGE" "203"
					( Origin gFrontEnd )
				)
				( attribute "ROOM" "PVCCIN_CPU0_PWR_VR"
					( Origin gFrontEnd )
				)
				( attribute "ROT" "0"
					( Origin gFrontEnd )
				)
				( attribute "SEC" "1"
					( Origin gFrontEnd )
				)
				( attribute "SEC_TYPE" "0402V"
					( Origin gFrontEnd )
				)
				( attribute "TOLERANCE" "10%"
					( Origin gFrontEnd )
				)
				( attribute "VALUE" "0.1UF"
					( Origin gFrontEnd )
				)
				( attribute "VER" "1"
					( Origin gFrontEnd )
				)
				( attribute "VOLTAGE" "16V"
					( Units "uVoltage" "V" 1.000000)
					( Origin gFrontEnd )
				)
				( attribute "XY" "(-6475,1450)"
					( Origin gFrontEnd )
				)
				( attribute "CHIPS_PART_NAME" "CAP_A"
					( Origin gPackager )
				)
				( attribute "CDS_PART_NAME" "CAP_A_0402V-0.1UF,16V,10%,X7R,A"
					( Origin gPackager )
				)
				( objectStatus "C4D11" )
				( pin "a"
					( attribute "PN" "1"
						( Origin gPackager )
					)
					( objectStatus "C4D11.1" )
				)
				( pin "b"
					( attribute "PN" "2"
						( Origin gPackager )
					)
					( objectStatus "C4D11.2" )
				)
			)
			( gate "@baseboard_fab2_lib.baseboard_fab2(sch_1):page203_i53"
				( attribute "CDS_LIB" "mstr_discrete"
					( Origin gPackager )
				)
				( attribute "CDS_LOCATION" "C4D10"
					( Origin gPackager )
				)
				( attribute "CDS_SEC" "1"
					( Origin gPackager )
				)
				( attribute "LOCATION" "C4D10"
					( Origin gFrontEnd )
				)
				( attribute "MATERIAL" "X6S"
					( Origin gFrontEnd )
				)
				( attribute "PACK_TYPE" "0402"
					( Origin gFrontEnd )
				)
				( attribute "PART_NUMBER" "D97712-011"
					( Origin gFrontEnd )
				)
				( attribute "PHYS_PAGE" "203"
					( Origin gFrontEnd )
				)
				( attribute "ROOM" "PVCCIN_CPU0_PWR_VR"
					( Origin gFrontEnd )
				)
				( attribute "ROT" "0"
					( Origin gFrontEnd )
				)
				( attribute "SEC" "1"
					( Origin gFrontEnd )
				)
				( attribute "SEC_TYPE" "0402"
					( Origin gFrontEnd )
				)
				( attribute "TOLERANCE" "10%"
					( Origin gFrontEnd )
				)
				( attribute "VALUE" "1.0UF"
					( Origin gFrontEnd )
				)
				( attribute "VER" "1"
					( Origin gFrontEnd )
				)
				( attribute "VOLTAGE" "16V"
					( Units "uVoltage" "V" 1.000000)
					( Origin gFrontEnd )
				)
				( attribute "XY" "(-6700,1400)"
					( Origin gFrontEnd )
				)
				( attribute "CHIPS_PART_NAME" "CAP"
					( Origin gPackager )
				)
				( attribute "CDS_PART_NAME" "CAP_0402-1.0UF,16V,10%,X6S,D97A"
					( Origin gPackager )
				)
				( objectStatus "C4D10" )
				( pin "a"
					( attribute "PN" "1"
						( Origin gPackager )
					)
					( objectStatus "C4D10.1" )
				)
				( pin "b"
					( attribute "PN" "2"
						( Origin gPackager )
					)
					( objectStatus "C4D10.2" )
				)
			)
			( gate "@baseboard_fab2_lib.baseboard_fab2(sch_1):page203_i54"
				( attribute "CDS_LIB" "mstr_discrete"
					( Origin gPackager )
				)
				( attribute "CDS_LOCATION" "C6P19"
					( Origin gPackager )
				)
				( attribute "CDS_SEC" "1"
					( Origin gPackager )
				)
				( attribute "LOCATION" "C6P19"
					( Origin gFrontEnd )
				)
				( attribute "MATERIAL" "X6S"
					( Origin gFrontEnd )
				)
				( attribute "PACK_TYPE" "0805"
					( Origin gFrontEnd )
				)
				( attribute "PART_NUMBER" "C95333-007"
					( Origin gFrontEnd )
				)
				( attribute "PHYS_PAGE" "203"
					( Origin gFrontEnd )
				)
				( attribute "ROOM" "PVCCIN_CPU0_PWR_VR"
					( Origin gFrontEnd )
				)
				( attribute "ROT" "0"
					( Origin gFrontEnd )
				)
				( attribute "SEC" "1"
					( Origin gFrontEnd )
				)
				( attribute "SEC_TYPE" "0805"
					( Origin gFrontEnd )
				)
				( attribute "TOLERANCE" "10%"
					( Origin gFrontEnd )
				)
				( attribute "VALUE" "10UF"
					( Origin gFrontEnd )
				)
				( attribute "VER" "1"
					( Origin gFrontEnd )
				)
				( attribute "VOLTAGE" "16V"
					( Units "uVoltage" "V" 1.000000)
					( Origin gFrontEnd )
				)
				( attribute "XY" "(-7425,4150)"
					( Origin gFrontEnd )
				)
				( attribute "CHIPS_PART_NAME" "CAP"
					( Origin gPackager )
				)
				( attribute "CDS_PART_NAME" "CAP_0805-10UF,16V,10%,X6S,C953A"
					( Origin gPackager )
				)
				( objectStatus "C6P19" )
				( pin "a"
					( attribute "PN" "1"
						( Origin gPackager )
					)
					( objectStatus "C6P19.1" )
				)
				( pin "b"
					( attribute "PN" "2"
						( Origin gPackager )
					)
					( objectStatus "C6P19.2" )
				)
			)
			( gate "@baseboard_fab2_lib.baseboard_fab2(sch_1):page203_i57"
				( attribute "CDS_LIB" "mstr_discrete"
					( Origin gPackager )
				)
				( attribute "CDS_LOCATION" "C6P20"
					( Origin gPackager )
				)
				( attribute "CDS_SEC" "1"
					( Origin gPackager )
				)
				( attribute "LOCATION" "C6P20"
					( Origin gFrontEnd )
				)
				( attribute "MATERIAL" "X6S"
					( Origin gFrontEnd )
				)
				( attribute "PACK_TYPE" "0805"
					( Origin gFrontEnd )
				)
				( attribute "PART_NUMBER" "C95333-007"
					( Origin gFrontEnd )
				)
				( attribute "PHYS_PAGE" "203"
					( Origin gFrontEnd )
				)
				( attribute "ROOM" "PVCCIN_CPU0_PWR_VR"
					( Origin gFrontEnd )
				)
				( attribute "ROT" "0"
					( Origin gFrontEnd )
				)
				( attribute "SEC" "1"
					( Origin gFrontEnd )
				)
				( attribute "SEC_TYPE" "0805"
					( Origin gFrontEnd )
				)
				( attribute "TOLERANCE" "10%"
					( Origin gFrontEnd )
				)
				( attribute "VALUE" "10UF"
					( Origin gFrontEnd )
				)
				( attribute "VER" "1"
					( Origin gFrontEnd )
				)
				( attribute "VOLTAGE" "16V"
					( Units "uVoltage" "V" 1.000000)
					( Origin gFrontEnd )
				)
				( attribute "XY" "(-6950,1400)"
					( Origin gFrontEnd )
				)
				( attribute "CHIPS_PART_NAME" "CAP"
					( Origin gPackager )
				)
				( attribute "CDS_PART_NAME" "CAP_0805-10UF,16V,10%,X6S,C953A"
					( Origin gPackager )
				)
				( objectStatus "C6P20" )
				( pin "a"
					( attribute "PN" "1"
						( Origin gPackager )
					)
					( objectStatus "C6P20.1" )
				)
				( pin "b"
					( attribute "PN" "2"
						( Origin gPackager )
					)
					( objectStatus "C6P20.2" )
				)
			)
			( gate "@baseboard_fab2_lib.baseboard_fab2(sch_1):page203_i58"
				( attribute "CDS_LIB" "mstr_discrete"
					( Origin gPackager )
				)
				( attribute "CDS_LOCATION" "C6P15"
					( Origin gPackager )
				)
				( attribute "CDS_SEC" "1"
					( Origin gPackager )
				)
				( attribute "LOCATION" "C6P15"
					( Origin gFrontEnd )
				)
				( attribute "MATERIAL" "X6S"
					( Origin gFrontEnd )
				)
				( attribute "PACK_TYPE" "0805"
					( Origin gFrontEnd )
				)
				( attribute "PART_NUMBER" "C95333-007"
					( Origin gFrontEnd )
				)
				( attribute "PHYS_PAGE" "203"
					( Origin gFrontEnd )
				)
				( attribute "ROOM" "PVCCIN_CPU0_PWR_VR"
					( Origin gFrontEnd )
				)
				( attribute "ROT" "0"
					( Origin gFrontEnd )
				)
				( attribute "SEC" "1"
					( Origin gFrontEnd )
				)
				( attribute "SEC_TYPE" "0805"
					( Origin gFrontEnd )
				)
				( attribute "TOLERANCE" "10%"
					( Origin gFrontEnd )
				)
				( attribute "VALUE" "10UF"
					( Origin gFrontEnd )
				)
				( attribute "VER" "1"
					( Origin gFrontEnd )
				)
				( attribute "VOLTAGE" "16V"
					( Units "uVoltage" "V" 1.000000)
					( Origin gFrontEnd )
				)
				( attribute "XY" "(-7200,1450)"
					( Origin gFrontEnd )
				)
				( attribute "CHIPS_PART_NAME" "CAP"
					( Origin gPackager )
				)
				( attribute "CDS_PART_NAME" "CAP_0805-10UF,16V,10%,X6S,C953A"
					( Origin gPackager )
				)
				( objectStatus "C6P15" )
				( pin "a"
					( attribute "PN" "1"
						( Origin gPackager )
					)
					( objectStatus "C6P15.1" )
				)
				( pin "b"
					( attribute "PN" "2"
						( Origin gPackager )
					)
					( objectStatus "C6P15.2" )
				)
			)
			( gate "@baseboard_fab2_lib.baseboard_fab2(sch_1):page203_i59"
				( attribute "CDS_LIB" "mstr_discrete"
					( Origin gPackager )
				)
				( attribute "CDS_LOCATION" "C6P7"
					( Origin gPackager )
				)
				( attribute "CDS_SEC" "1"
					( Origin gPackager )
				)
				( attribute "LOCATION" "C6P7"
					( Origin gFrontEnd )
				)
				( attribute "MATERIAL" "X6S"
					( Origin gFrontEnd )
				)
				( attribute "PACK_TYPE" "0805"
					( Origin gFrontEnd )
				)
				( attribute "PART_NUMBER" "C95333-007"
					( Origin gFrontEnd )
				)
				( attribute "PHYS_PAGE" "203"
					( Origin gFrontEnd )
				)
				( attribute "ROOM" "PVCCIN_CPU0_PWR_VR"
					( Origin gFrontEnd )
				)
				( attribute "ROT" "0"
					( Origin gFrontEnd )
				)
				( attribute "SEC" "1"
					( Origin gFrontEnd )
				)
				( attribute "SEC_TYPE" "0805"
					( Origin gFrontEnd )
				)
				( attribute "TOLERANCE" "10%"
					( Origin gFrontEnd )
				)
				( attribute "VALUE" "10UF"
					( Origin gFrontEnd )
				)
				( attribute "VER" "1"
					( Origin gFrontEnd )
				)
				( attribute "VOLTAGE" "16V"
					( Units "uVoltage" "V" 1.000000)
					( Origin gFrontEnd )
				)
				( attribute "XY" "(-7475,1450)"
					( Origin gFrontEnd )
				)
				( attribute "CHIPS_PART_NAME" "CAP"
					( Origin gPackager )
				)
				( attribute "CDS_PART_NAME" "CAP_0805-10UF,16V,10%,X6S,C953A"
					( Origin gPackager )
				)
				( objectStatus "C6P7" )
				( pin "a"
					( attribute "PN" "1"
						( Origin gPackager )
					)
					( objectStatus "C6P7.1" )
				)
				( pin "b"
					( attribute "PN" "2"
						( Origin gPackager )
					)
					( objectStatus "C6P7.2" )
				)
			)
			( gate "@baseboard_fab2_lib.baseboard_fab2(sch_1):page203_i66"
				( attribute "BOM_COST" "PROC_VRD_VCCIN_CPU0"
					( Origin gFrontEnd )
				)
				( attribute "CDS_LIB" "dev_discrete"
					( Origin gPackager )
				)
				( attribute "CDS_LOCATION" "C6P21"
					( Origin gPackager )
				)
				( attribute "CDS_SEC" "1"
					( Origin gPackager )
				)
				( attribute "LOCATION" "C6P21"
					( Origin gFrontEnd )
				)
				( attribute "MATERIAL" "X6S"
					( Origin gFrontEnd )
				)
				( attribute "PACK_TYPE" "0603V"
					( Origin gFrontEnd )
				)
				( attribute "PART_NUMBER" "E15431-004"
					( Origin gFrontEnd )
				)
				( attribute "PHYS_PAGE" "203"
					( Origin gFrontEnd )
				)
				( attribute "ROOM" "PVCCIN_CPU0_PWR_VR"
					( Origin gFrontEnd )
				)
				( attribute "ROT" "0"
					( Origin gFrontEnd )
				)
				( attribute "SEC" "1"
					( Origin gFrontEnd )
				)
				( attribute "SEC_TYPE" "0603V"
					( Origin gFrontEnd )
				)
				( attribute "TOLERANCE" "20%"
					( Origin gFrontEnd )
				)
				( attribute "VALUE" "22.0UF"
					( Origin gFrontEnd )
				)
				( attribute "VER" "1"
					( Origin gFrontEnd )
				)
				( attribute "VOLTAGE" "4V"
					( Units "uVoltage" "V" 1.000000)
					( Origin gFrontEnd )
				)
				( attribute "XY" "(-1025,3375)"
					( Origin gFrontEnd )
				)
				( attribute "CHIPS_PART_NAME" "CAP_A"
					( Origin gPackager )
				)
				( attribute "CDS_PART_NAME" "CAP_A_0603V-22.0UF,4V,20%,X6S,A"
					( Origin gPackager )
				)
				( objectStatus "C6P21" )
				( pin "a"
					( attribute "PN" "1"
						( Origin gPackager )
					)
					( objectStatus "C6P21.1" )
				)
				( pin "b"
					( attribute "PN" "2"
						( Origin gPackager )
					)
					( objectStatus "C6P21.2" )
				)
			)
			( gate "@baseboard_fab2_lib.baseboard_fab2(sch_1):page203_i67"
				( attribute "BOM_COST" "PROC_VRD_VCCIN_CPU0"
					( Origin gFrontEnd )
				)
				( attribute "CDS_LIB" "mstr_discrete"
					( Origin gPackager )
				)
				( attribute "CDS_LOCATION" "R4E13"
					( Origin gPackager )
				)
				( attribute "CDS_SEC" "1"
					( Origin gPackager )
				)
				( attribute "LOCATION" "R4E13"
					( Origin gFrontEnd )
				)
				( attribute "MATERIAL" "CHIP"
					( Origin gFrontEnd )
				)
				( attribute "PACK_TYPE" "0603"
					( Origin gFrontEnd )
				)
				( attribute "PART_NUMBER" "G22026-038"
					( Origin gFrontEnd )
				)
				( attribute "PHYS_PAGE" "203"
					( Origin gFrontEnd )
				)
				( attribute "ROOM" "PVCCIN_CPU0_DECAP_VR"
					( Origin gFrontEnd )
				)
				( attribute "ROT" "0"
					( Origin gFrontEnd )
				)
				( attribute "SEC" "1"
					( Origin gFrontEnd )
				)
				( attribute "SEC_TYPE" "0603"
					( Origin gFrontEnd )
				)
				( attribute "TOLERANCE" "1%"
					( Origin gFrontEnd )
				)
				( attribute "VALUE" "100.0"
					( Origin gFrontEnd )
				)
				( attribute "VER" "2"
					( Origin gFrontEnd )
				)
				( attribute "WATTAGE" "1/10W"
					( Origin gFrontEnd )
				)
				( attribute "XY" "(-700,2525)"
					( Origin gFrontEnd )
				)
				( attribute "CHIPS_PART_NAME" "RES"
					( Origin gPackager )
				)
				( attribute "CDS_PART_NAME" "RES_0603-100.0,1%,1/10W,CHIP,GA"
					( Origin gPackager )
				)
				( objectStatus "R4E13" )
				( pin "a"
					( attribute "PN" "1"
						( Origin gPackager )
					)
					( objectStatus "R4E13.1" )
				)
				( pin "b"
					( attribute "PN" "2"
						( Origin gPackager )
					)
					( objectStatus "R4E13.2" )
				)
			)
			( gate "@baseboard_fab2_lib.baseboard_fab2(sch_1):page203_i68"
				( attribute "CDS_LIB" "dev_discrete"
					( Origin gPackager )
				)
				( attribute "CDS_LOCATION" "C4D34"
					( Origin gPackager )
				)
				( attribute "CDS_SEC" "1"
					( Origin gPackager )
				)
				( attribute "LOCATION" "C4D34"
					( Origin gFrontEnd )
				)
				( attribute "MATERIAL" "X6S"
					( Origin gFrontEnd )
				)
				( attribute "PACK_TYPE" "0603V"
					( Origin gFrontEnd )
				)
				( attribute "PART_NUMBER" "E15431-004"
					( Origin gFrontEnd )
				)
				( attribute "PHYS_PAGE" "203"
					( Origin gFrontEnd )
				)
				( attribute "ROT" "0"
					( Origin gFrontEnd )
				)
				( attribute "SEC" "1"
					( Origin gFrontEnd )
				)
				( attribute "SEC_TYPE" "0603V"
					( Origin gFrontEnd )
				)
				( attribute "TOLERANCE" "20%"
					( Origin gFrontEnd )
				)
				( attribute "VALUE" "22.0UF"
					( Origin gFrontEnd )
				)
				( attribute "VER" "1"
					( Origin gFrontEnd )
				)
				( attribute "VOLTAGE" "4V"
					( Units "uVoltage" "V" 1.000000)
					( Origin gFrontEnd )
				)
				( attribute "XY" "(-750,3375)"
					( Origin gFrontEnd )
				)
				( attribute "CHIPS_PART_NAME" "CAP_A"
					( Origin gPackager )
				)
				( attribute "CDS_PART_NAME" "CAP_A_0603V-22.0UF,4V,20%,X6S,A"
					( Origin gPackager )
				)
				( objectStatus "C4D34" )
				( pin "a"
					( attribute "PN" "1"
						( Origin gPackager )
					)
					( objectStatus "C4D34.1" )
				)
				( pin "b"
					( attribute "PN" "2"
						( Origin gPackager )
					)
					( objectStatus "C4D34.2" )
				)
			)
			( gate "@baseboard_fab2_lib.baseboard_fab2(sch_1):page203_i69"
				( attribute "CDS_LIB" "dev_discrete"
					( Origin gPackager )
				)
				( attribute "CDS_LOCATION" "C4D4"
					( Origin gPackager )
				)
				( attribute "CDS_SEC" "1"
					( Origin gPackager )
				)
				( attribute "LOCATION" "C4D4"
					( Origin gFrontEnd )
				)
				( attribute "MATERIAL" "X6S"
					( Origin gFrontEnd )
				)
				( attribute "PACK_TYPE" "0603V"
					( Origin gFrontEnd )
				)
				( attribute "PART_NUMBER" "E15431-004"
					( Origin gFrontEnd )
				)
				( attribute "PHYS_PAGE" "203"
					( Origin gFrontEnd )
				)
				( attribute "ROT" "0"
					( Origin gFrontEnd )
				)
				( attribute "SEC" "1"
					( Origin gFrontEnd )
				)
				( attribute "SEC_TYPE" "0603V"
					( Origin gFrontEnd )
				)
				( attribute "TOLERANCE" "20%"
					( Origin gFrontEnd )
				)
				( attribute "VALUE" "22.0UF"
					( Origin gFrontEnd )
				)
				( attribute "VER" "1"
					( Origin gFrontEnd )
				)
				( attribute "VOLTAGE" "4V"
					( Units "uVoltage" "V" 1.000000)
					( Origin gFrontEnd )
				)
				( attribute "XY" "(-750,575)"
					( Origin gFrontEnd )
				)
				( attribute "CHIPS_PART_NAME" "CAP_A"
					( Origin gPackager )
				)
				( attribute "CDS_PART_NAME" "CAP_A_0603V-22.0UF,4V,20%,X6S,A"
					( Origin gPackager )
				)
				( objectStatus "C4D4" )
				( pin "a"
					( attribute "PN" "1"
						( Origin gPackager )
					)
					( objectStatus "C4D4.1" )
				)
				( pin "b"
					( attribute "PN" "2"
						( Origin gPackager )
					)
					( objectStatus "C4D4.2" )
				)
			)
			( gate "@baseboard_fab2_lib.baseboard_fab2(sch_1):page203_i70"
				( attribute "CDS_LIB" "mstr_discrete"
					( Origin gPackager )
				)
				( attribute "CDS_LOCATION" "EU4D3"
					( Origin gPackager )
				)
				( attribute "CDS_SEC" "1"
					( Origin gPackager )
				)
				( attribute "LOCATION" "EU4D3"
					( Origin gFrontEnd )
				)
				( attribute "MATERIAL" "IC"
					( Origin gFrontEnd )
				)
				( attribute "PACK_TYPE" "SM"
					( Origin gFrontEnd )
				)
				( attribute "PART_NUMBER" "H73688-001"
					( Origin gFrontEnd )
				)
				( attribute "PHYS_PAGE" "203"
					( Origin gFrontEnd )
				)
				( attribute "ROT" "0"
					( Origin gFrontEnd )
				)
				( attribute "SEC" "1"
					( Origin gFrontEnd )
				)
				( attribute "SEC_TYPE" "SM"
					( Origin gFrontEnd )
				)
				( attribute "VALUE" "IR35411"
					( Origin gFrontEnd )
				)
				( attribute "VER" "1"
					( Origin gFrontEnd )
				)
				( attribute "XY" "(-3325,3900)"
					( Origin gFrontEnd )
				)
				( attribute "CHIPS_PART_NAME" "IR354XX"
					( Origin gPackager )
				)
				( attribute "CDS_PART_NAME" "IR354XX_SM-IR35411,IC,H73688-0A"
					( Origin gPackager )
				)
				( objectStatus "EU4D3" )
				( pin "boost"
					( attribute "PN" "33"
						( Origin gPackager )
					)
					( objectStatus "EU4D3.33" )
				)
				( pin "en"
					( attribute "PN" "35"
						( Origin gPackager )
					)
					( objectStatus "EU4D3.35" )
				)
				( pin "gl(0)"
					( attribute "PN" "6"
						( Origin gPackager )
					)
					( objectStatus "EU4D3.6" )
				)
				( pin "gl(1)"
					( attribute "PN" "41"
						( Origin gPackager )
					)
					( objectStatus "EU4D3.41" )
				)
				( pin "iout"
					( attribute "PN" "38"
						( Origin gPackager )
					)
					( objectStatus "EU4D3.38" )
				)
				( pin "lgnd"
					( attribute "PN" "2"
						( Origin gPackager )
					)
					( objectStatus "EU4D3.2" )
				)
				( pin "nc"
					( attribute "PN" "31"
						( Origin gPackager )
					)
					( objectStatus "EU4D3.31" )
				)
				( pin "ocset"
					( attribute "PN" "37"
						( Origin gPackager )
					)
					( objectStatus "EU4D3.37" )
				)
				( pin "pgnd(0)"
					( attribute "PN" "5"
						( Origin gPackager )
					)
					( objectStatus "EU4D3.5" )
				)
				( pin "pgnd(1)"
					( attribute "PN" "7"
						( Origin gPackager )
					)
					( objectStatus "EU4D3.7" )
				)
				( pin "pgnd(2)"
					( attribute "PN" "40"
						( Origin gPackager )
					)
					( objectStatus "EU4D3.40" )
				)
				( pin "phase"
					( attribute "PN" "32"
						( Origin gPackager )
					)
					( objectStatus "EU4D3.32" )
				)
				( pin "pwm"
					( attribute "PN" "34"
						( Origin gPackager )
					)
					( objectStatus "EU4D3.34" )
				)
				( pin "refin"
					( attribute "PN" "39"
						( Origin gPackager )
					)
					( objectStatus "EU4D3.39" )
				)
				( pin "sw"
					( attribute "PN" "10"
						( Origin gPackager )
					)
					( objectStatus "EU4D3.10" )
				)
				( pin "tout_flt"
					( attribute "PN" "36"
						( Origin gPackager )
					)
					( objectStatus "EU4D3.36" )
				)
				( pin "vcc"
					( attribute "PN" "3"
						( Origin gPackager )
					)
					( objectStatus "EU4D3.3" )
				)
				( pin "vdrv"
					( attribute "PN" "4"
						( Origin gPackager )
					)
					( objectStatus "EU4D3.4" )
				)
				( pin "vin(0)"
					( attribute "PN" "25"
						( Origin gPackager )
					)
					( objectStatus "EU4D3.25" )
				)
				( pin "vin(1)"
					( attribute "PN" "30"
						( Origin gPackager )
					)
					( objectStatus "EU4D3.30" )
				)
				( pin "vos"
					( attribute "PN" "1"
						( Origin gPackager )
					)
					( objectStatus "EU4D3.1" )
				)
			)
			( gate "@baseboard_fab2_lib.baseboard_fab2(sch_1):page203_i71"
				( attribute "CDS_LIB" "mstr_discrete"
					( Origin gPackager )
				)
				( attribute "CDS_LOCATION" "EU4D1"
					( Origin gPackager )
				)
				( attribute "CDS_SEC" "1"
					( Origin gPackager )
				)
				( attribute "LOCATION" "EU4D1"
					( Origin gFrontEnd )
				)
				( attribute "MATERIAL" "IC"
					( Origin gFrontEnd )
				)
				( attribute "PACK_TYPE" "SM"
					( Origin gFrontEnd )
				)
				( attribute "PART_NUMBER" "H73688-001"
					( Origin gFrontEnd )
				)
				( attribute "PHYS_PAGE" "203"
					( Origin gFrontEnd )
				)
				( attribute "ROT" "0"
					( Origin gFrontEnd )
				)
				( attribute "SEC" "1"
					( Origin gPackager )
				)
				( attribute "VALUE" "IR35411"
					( Origin gFrontEnd )
				)
				( attribute "VER" "1"
					( Origin gFrontEnd )
				)
				( attribute "XY" "(-3350,1175)"
					( Origin gFrontEnd )
				)
				( attribute "CHIPS_PART_NAME" "IR354XX"
					( Origin gPackager )
				)
				( attribute "CDS_PART_NAME" "IR354XX_SM-IR35411,IC,H73688-0A"
					( Origin gPackager )
				)
				( objectStatus "EU4D1" )
				( pin "boost"
					( attribute "PN" "33"
						( Origin gPackager )
					)
					( objectStatus "EU4D1.33" )
				)
				( pin "en"
					( attribute "PN" "35"
						( Origin gPackager )
					)
					( objectStatus "EU4D1.35" )
				)
				( pin "gl(0)"
					( attribute "PN" "6"
						( Origin gPackager )
					)
					( objectStatus "EU4D1.6" )
				)
				( pin "gl(1)"
					( attribute "PN" "41"
						( Origin gPackager )
					)
					( objectStatus "EU4D1.41" )
				)
				( pin "iout"
					( attribute "PN" "38"
						( Origin gPackager )
					)
					( objectStatus "EU4D1.38" )
				)
				( pin "lgnd"
					( attribute "PN" "2"
						( Origin gPackager )
					)
					( objectStatus "EU4D1.2" )
				)
				( pin "nc"
					( attribute "PN" "31"
						( Origin gPackager )
					)
					( objectStatus "EU4D1.31" )
				)
				( pin "ocset"
					( attribute "PN" "37"
						( Origin gPackager )
					)
					( objectStatus "EU4D1.37" )
				)
				( pin "pgnd(0)"
					( attribute "PN" "5"
						( Origin gPackager )
					)
					( objectStatus "EU4D1.5" )
				)
				( pin "pgnd(1)"
					( attribute "PN" "7"
						( Origin gPackager )
					)
					( objectStatus "EU4D1.7" )
				)
				( pin "pgnd(2)"
					( attribute "PN" "40"
						( Origin gPackager )
					)
					( objectStatus "EU4D1.40" )
				)
				( pin "phase"
					( attribute "PN" "32"
						( Origin gPackager )
					)
					( objectStatus "EU4D1.32" )
				)
				( pin "pwm"
					( attribute "PN" "34"
						( Origin gPackager )
					)
					( objectStatus "EU4D1.34" )
				)
				( pin "refin"
					( attribute "PN" "39"
						( Origin gPackager )
					)
					( objectStatus "EU4D1.39" )
				)
				( pin "sw"
					( attribute "PN" "10"
						( Origin gPackager )
					)
					( objectStatus "EU4D1.10" )
				)
				( pin "tout_flt"
					( attribute "PN" "36"
						( Origin gPackager )
					)
					( objectStatus "EU4D1.36" )
				)
				( pin "vcc"
					( attribute "PN" "3"
						( Origin gPackager )
					)
					( objectStatus "EU4D1.3" )
				)
				( pin "vdrv"
					( attribute "PN" "4"
						( Origin gPackager )
					)
					( objectStatus "EU4D1.4" )
				)
				( pin "vin(0)"
					( attribute "PN" "25"
						( Origin gPackager )
					)
					( objectStatus "EU4D1.25" )
				)
				( pin "vin(1)"
					( attribute "PN" "30"
						( Origin gPackager )
					)
					( objectStatus "EU4D1.30" )
				)
				( pin "vos"
					( attribute "PN" "1"
						( Origin gPackager )
					)
					( objectStatus "EU4D1.1" )
				)
			)
			( gate "@baseboard_fab2_lib.baseboard_fab2(sch_1):page203_i89"
				( attribute "CDS_LIB" "mstr_discrete"
					( Origin gPackager )
				)
				( attribute "CDS_LOCATION" "R4D72"
					( Origin gPackager )
				)
				( attribute "CDS_SEC" "1"
					( Origin gPackager )
				)
				( attribute "LOCATION" "R4D72"
					( Origin gFrontEnd )
				)
				( attribute "MATERIAL" "EMPTY"
					( Origin gFrontEnd )
				)
				( attribute "PACK_TYPE" "0402"
					( Origin gFrontEnd )
				)
				( attribute "PART_NUMBER" "G21796-187"
					( Origin gFrontEnd )
				)
				( attribute "PHYS_PAGE" "203"
					( Origin gFrontEnd )
				)
				( attribute "ROT" "0"
					( Origin gFrontEnd )
				)
				( attribute "SEC" "1"
					( Origin gPackager )
				)
				( attribute "TOLERANCE" "1%"
					( Origin gFrontEnd )
				)
				( attribute "VALUE" "68.1K"
					( Origin gFrontEnd )
				)
				( attribute "VER" "2"
					( Origin gFrontEnd )
				)
				( attribute "WATTAGE" "1/16W"
					( Origin gFrontEnd )
				)
				( attribute "XY" "(-625,4075)"
					( Origin gFrontEnd )
				)
				( attribute "CHIPS_PART_NAME" "RES"
					( Origin gPackager )
				)
				( attribute "CDS_PART_NAME" "RES_0402-68.1K,1%,1/16W,EMPTY,A"
					( Origin gPackager )
				)
				( objectStatus "R4D72" )
				( pin "a"
					( attribute "PN" "1"
						( Origin gPackager )
					)
					( objectStatus "R4D72.1" )
				)
				( pin "b"
					( attribute "PN" "2"
						( Origin gPackager )
					)
					( objectStatus "R4D72.2" )
				)
			)
			( gate "@baseboard_fab2_lib.baseboard_fab2(sch_1):page203_i91"
				( attribute "CDS_LIB" "mstr_discrete"
					( Origin gPackager )
				)
				( attribute "CDS_LOCATION" "R4D71"
					( Origin gPackager )
				)
				( attribute "CDS_SEC" "1"
					( Origin gPackager )
				)
				( attribute "LOCATION" "R4D71"
					( Origin gFrontEnd )
				)
				( attribute "MATERIAL" "EMPTY"
					( Origin gFrontEnd )
				)
				( attribute "PACK_TYPE" "0402"
					( Origin gFrontEnd )
				)
				( attribute "PART_NUMBER" "G21796-187"
					( Origin gFrontEnd )
				)
				( attribute "PHYS_PAGE" "203"
					( Origin gFrontEnd )
				)
				( attribute "ROT" "0"
					( Origin gFrontEnd )
				)
				( attribute "SEC" "1"
					( Origin gPackager )
				)
				( attribute "TOLERANCE" "1%"
					( Origin gFrontEnd )
				)
				( attribute "VALUE" "68.1K"
					( Origin gFrontEnd )
				)
				( attribute "VER" "2"
					( Origin gFrontEnd )
				)
				( attribute "WATTAGE" "1/16W"
					( Origin gFrontEnd )
				)
				( attribute "XY" "(-450,1375)"
					( Origin gFrontEnd )
				)
				( attribute "CHIPS_PART_NAME" "RES"
					( Origin gPackager )
				)
				( attribute "CDS_PART_NAME" "RES_0402-68.1K,1%,1/16W,EMPTY,A"
					( Origin gPackager )
				)
				( objectStatus "R4D71" )
				( pin "a"
					( attribute "PN" "1"
						( Origin gPackager )
					)
					( objectStatus "R4D71.1" )
				)
				( pin "b"
					( attribute "PN" "2"
						( Origin gPackager )
					)
					( objectStatus "R4D71.2" )
				)
			)
			( gate "@baseboard_fab2_lib.baseboard_fab2(sch_1):page204_i5"
				( attribute "CDS_LIB" "mstr_discrete"
					( Origin gPackager )
				)
				( attribute "CDS_LOCATION" "L4C3"
					( Origin gPackager )
				)
				( attribute "CDS_SEC" "1"
					( Origin gPackager )
				)
				( attribute "LOCATION" "L4C3"
					( Origin gFrontEnd )
				)
				( attribute "MATERIAL" "IND"
					( Origin gFrontEnd )
				)
				( attribute "PACK_TYPE" "SM"
					( Origin gFrontEnd )
				)
				( attribute "PART_NUMBER" "D92183-034"
					( Origin gFrontEnd )
				)
				( attribute "PHYS_PAGE" "204"
					( Origin gFrontEnd )
				)
				( attribute "ROOM" "PVCCIN_CPU0_PWR_VR"
					( Origin gFrontEnd )
				)
				( attribute "ROT" "0"
					( Origin gFrontEnd )
				)
				( attribute "SEC" "1"
					( Origin gPackager )
				)
				( attribute "VALUE" "0.12UH"
					( Origin gFrontEnd )
				)
				( attribute "VER" "1"
					( Origin gFrontEnd )
				)
				( attribute "XY" "(-1925,3400)"
					( Origin gFrontEnd )
				)
				( attribute "CHIPS_PART_NAME" "INDUCTOR"
					( Origin gPackager )
				)
				( attribute "CDS_PART_NAME" "INDUCTOR_SM-0.12UH,IND,D92183-A"
					( Origin gPackager )
				)
				( objectStatus "L4C3" )
				( pin "ina"
					( attribute "PN" "1"
						( Origin gPackager )
					)
					( objectStatus "L4C3.1" )
				)
				( pin "inb"
					( attribute "PN" "2"
						( Origin gPackager )
					)
					( objectStatus "L4C3.2" )
				)
			)
			( gate "@baseboard_fab2_lib.baseboard_fab2(sch_1):page204_i9"
				( attribute "BOM_COST" "PROC_VRD_VCCIN_CPU0"
					( Origin gFrontEnd )
				)
				( attribute "CDS_LIB" "dev_discrete"
					( Origin gPackager )
				)
				( attribute "CDS_LOCATION" "C4D12"
					( Origin gPackager )
				)
				( attribute "CDS_SEC" "1"
					( Origin gPackager )
				)
				( attribute "LOCATION" "C4D12"
					( Origin gFrontEnd )
				)
				( attribute "MATERIAL" "X6S"
					( Origin gFrontEnd )
				)
				( attribute "PACK_TYPE" "0603V"
					( Origin gFrontEnd )
				)
				( attribute "PART_NUMBER" "E15431-004"
					( Origin gFrontEnd )
				)
				( attribute "PHYS_PAGE" "204"
					( Origin gFrontEnd )
				)
				( attribute "ROOM" "PVCCIN_CPU0_PWR_VR"
					( Origin gFrontEnd )
				)
				( attribute "ROT" "0"
					( Origin gFrontEnd )
				)
				( attribute "SEC" "1"
					( Origin gFrontEnd )
				)
				( attribute "SEC_TYPE" "0603V"
					( Origin gFrontEnd )
				)
				( attribute "TOLERANCE" "20%"
					( Origin gFrontEnd )
				)
				( attribute "VALUE" "22.0UF"
					( Origin gFrontEnd )
				)
				( attribute "VER" "1"
					( Origin gFrontEnd )
				)
				( attribute "VOLTAGE" "4V"
					( Units "uVoltage" "V" 1.000000)
					( Origin gFrontEnd )
				)
				( attribute "XY" "(-1100,3100)"
					( Origin gFrontEnd )
				)
				( attribute "CHIPS_PART_NAME" "CAP_A"
					( Origin gPackager )
				)
				( attribute "CDS_PART_NAME" "CAP_A_0603V-22.0UF,4V,20%,X6S,A"
					( Origin gPackager )
				)
				( objectStatus "C4D12" )
				( pin "a"
					( attribute "PN" "1"
						( Origin gPackager )
					)
					( objectStatus "C4D12.1" )
				)
				( pin "b"
					( attribute "PN" "2"
						( Origin gPackager )
					)
					( objectStatus "C4D12.2" )
				)
			)
			( gate "@baseboard_fab2_lib.baseboard_fab2(sch_1):page204_i18"
				( attribute "CDS_LIB" "mstr_discrete"
					( Origin gPackager )
				)
				( attribute "CDS_LOCATION" "C4D47"
					( Origin gPackager )
				)
				( attribute "CDS_SEC" "1"
					( Origin gPackager )
				)
				( attribute "LOCATION" "C4D47"
					( Origin gFrontEnd )
				)
				( attribute "MATERIAL" "X7R"
					( Origin gFrontEnd )
				)
				( attribute "PACK_TYPE" "0402"
					( Origin gFrontEnd )
				)
				( attribute "PART_NUMBER" "A36096-155"
					( Origin gFrontEnd )
				)
				( attribute "PHYS_PAGE" "204"
					( Origin gFrontEnd )
				)
				( attribute "ROOM" "PVCCIN_CPU0_PWR_VR"
					( Origin gFrontEnd )
				)
				( attribute "ROT" "0"
					( Origin gFrontEnd )
				)
				( attribute "SEC" "1"
					( Origin gFrontEnd )
				)
				( attribute "SEC_TYPE" "0402"
					( Origin gFrontEnd )
				)
				( attribute "TOLERANCE" "10%"
					( Origin gFrontEnd )
				)
				( attribute "VALUE" "0.22UF"
					( Origin gFrontEnd )
				)
				( attribute "VER" "1"
					( Origin gFrontEnd )
				)
				( attribute "VOLTAGE" "16V"
					( Units "uVoltage" "V" 1.000000)
					( Origin gFrontEnd )
				)
				( attribute "XY" "(-5675,3975)"
					( Origin gFrontEnd )
				)
				( attribute "CHIPS_PART_NAME" "CAP"
					( Origin gPackager )
				)
				( attribute "CDS_PART_NAME" "CAP_0402-0.22UF,16V,10%,X7R,A3A"
					( Origin gPackager )
				)
				( objectStatus "C4D47" )
				( pin "a"
					( attribute "PN" "1"
						( Origin gPackager )
					)
					( objectStatus "C4D47.1" )
				)
				( pin "b"
					( attribute "PN" "2"
						( Origin gPackager )
					)
					( objectStatus "C4D47.2" )
				)
			)
			( gate "@baseboard_fab2_lib.baseboard_fab2(sch_1):page204_i19"
				( attribute "CDS_LIB" "dev_discrete"
					( Origin gPackager )
				)
				( attribute "CDS_LOCATION" "C4C14"
					( Origin gPackager )
				)
				( attribute "CDS_SEC" "1"
					( Origin gPackager )
				)
				( attribute "LOCATION" "C4C14"
					( Origin gFrontEnd )
				)
				( attribute "MATERIAL" "X6S"
					( Origin gFrontEnd )
				)
				( attribute "PACK_TYPE" "0402V"
					( Origin gFrontEnd )
				)
				( attribute "PART_NUMBER" "D97712-004"
					( Origin gFrontEnd )
				)
				( attribute "PHYS_PAGE" "204"
					( Origin gFrontEnd )
				)
				( attribute "ROOM" "PVCCIN_CPU0_PWR_VR"
					( Origin gFrontEnd )
				)
				( attribute "ROT" "2"
					( Origin gFrontEnd )
				)
				( attribute "SEC" "1"
					( Origin gFrontEnd )
				)
				( attribute "SEC_TYPE" "0402V"
					( Origin gFrontEnd )
				)
				( attribute "TOLERANCE" "10%"
					( Origin gFrontEnd )
				)
				( attribute "VALUE" "1.0UF"
					( Origin gFrontEnd )
				)
				( attribute "VER" "1"
					( Origin gFrontEnd )
				)
				( attribute "VOLTAGE" "6.3V"
					( Units "uVoltage" "V" 1.000000)
					( Origin gFrontEnd )
				)
				( attribute "XY" "(-5825,3975)"
					( Origin gFrontEnd )
				)
				( attribute "CHIPS_PART_NAME" "CAP_A"
					( Origin gPackager )
				)
				( attribute "CDS_PART_NAME" "CAP_A_0402V-1.0UF,6.3V,10%,X6SA"
					( Origin gPackager )
				)
				( objectStatus "C4C14" )
				( pin "a"
					( attribute "PN" "1"
						( Origin gPackager )
					)
					( objectStatus "C4C14.1" )
				)
				( pin "b"
					( attribute "PN" "2"
						( Origin gPackager )
					)
					( objectStatus "C4C14.2" )
				)
			)
			( gate "@baseboard_fab2_lib.baseboard_fab2(sch_1):page204_i22"
				( attribute "CDS_LIB" "mstr_discrete"
					( Origin gPackager )
				)
				( attribute "CDS_LOCATION" "C4C17"
					( Origin gPackager )
				)
				( attribute "CDS_SEC" "1"
					( Origin gPackager )
				)
				( attribute "LOCATION" "C4C17"
					( Origin gFrontEnd )
				)
				( attribute "MATERIAL" "X7R"
					( Origin gFrontEnd )
				)
				( attribute "NO_XNET_CONNECTION" "1"
					( Origin gFrontEnd )
				)
				( attribute "PACK_TYPE" "0402"
					( Origin gFrontEnd )
				)
				( attribute "PART_NUMBER" "A36096-104"
					( Origin gFrontEnd )
				)
				( attribute "PHYS_PAGE" "204"
					( Origin gFrontEnd )
				)
				( attribute "ROOM" "PVCCIN_CPU0_PWR_VR"
					( Origin gFrontEnd )
				)
				( attribute "ROT" "2"
					( Origin gFrontEnd )
				)
				( attribute "SEC" "1"
					( Origin gFrontEnd )
				)
				( attribute "SEC_TYPE" "0402"
					( Origin gFrontEnd )
				)
				( attribute "SPOF" "TRUE"
					( Origin gFrontEnd )
				)
				( attribute "TOLERANCE" "10%"
					( Origin gFrontEnd )
				)
				( attribute "VALUE" "0.220UF"
					( Origin gFrontEnd )
				)
				( attribute "VER" "1"
					( Origin gFrontEnd )
				)
				( attribute "VOLTAGE" "16V"
					( Units "uVoltage" "V" 1.000000)
					( Origin gFrontEnd )
				)
				( attribute "XY" "(-6200,3350)"
					( Origin gFrontEnd )
				)
				( attribute "CHIPS_PART_NAME" "CAP"
					( Origin gPackager )
				)
				( attribute "CDS_PART_NAME" "CAP_0402-0.220UF,16V,10%,X7R,AA"
					( Origin gPackager )
				)
				( objectStatus "C4C17" )
				( pin "a"
					( attribute "PN" "1"
						( Origin gPackager )
					)
					( objectStatus "C4C17.1" )
				)
				( pin "b"
					( attribute "PN" "2"
						( Origin gPackager )
					)
					( objectStatus "C4C17.2" )
				)
			)
			( gate "@baseboard_fab2_lib.baseboard_fab2(sch_1):page204_i33"
				( attribute "CDS_LIB" "mstr_discrete"
					( Origin gPackager )
				)
				( attribute "CDS_LOCATION" "R6P47"
					( Origin gPackager )
				)
				( attribute "CDS_SEC" "1"
					( Origin gPackager )
				)
				( attribute "LOCATION" "R6P47"
					( Origin gFrontEnd )
				)
				( attribute "MATERIAL" "CHIP"
					( Origin gFrontEnd )
				)
				( attribute "PACK_TYPE" "0402"
					( Origin gFrontEnd )
				)
				( attribute "PART_NUMBER" "G21796-090"
					( Origin gFrontEnd )
				)
				( attribute "PHYS_PAGE" "204"
					( Origin gFrontEnd )
				)
				( attribute "ROOM" "PVCCIN_CPU0_PWR_VR"
					( Origin gFrontEnd )
				)
				( attribute "ROT" "0"
					( Origin gFrontEnd )
				)
				( attribute "SEC" "1"
					( Origin gFrontEnd )
				)
				( attribute "SEC_TYPE" "0402"
					( Origin gFrontEnd )
				)
				( attribute "TOLERANCE" "1%"
					( Origin gFrontEnd )
				)
				( attribute "VALUE" "1.0"
					( Origin gFrontEnd )
				)
				( attribute "VER" "1"
					( Origin gFrontEnd )
				)
				( attribute "WATTAGE" "1/16W"
					( Origin gFrontEnd )
				)
				( attribute "XY" "(-6100,4525)"
					( Origin gFrontEnd )
				)
				( attribute "CHIPS_PART_NAME" "RES"
					( Origin gPackager )
				)
				( attribute "CDS_PART_NAME" "RES_0402-1.0,1%,1/16W,CHIP,G21A"
					( Origin gPackager )
				)
				( objectStatus "R6P47" )
				( pin "a"
					( attribute "PN" "1"
						( Origin gPackager )
					)
					( objectStatus "R6P47.1" )
				)
				( pin "b"
					( attribute "PN" "2"
						( Origin gPackager )
					)
					( objectStatus "R6P47.2" )
				)
			)
			( gate "@baseboard_fab2_lib.baseboard_fab2(sch_1):page204_i34"
				( attribute "CDS_LIB" "mstr_discrete"
					( Origin gPackager )
				)
				( attribute "CDS_LOCATION" "C4D46"
					( Origin gPackager )
				)
				( attribute "CDS_SEC" "1"
					( Origin gPackager )
				)
				( attribute "LOCATION" "C4D46"
					( Origin gFrontEnd )
				)
				( attribute "MATERIAL" "X6S"
					( Origin gFrontEnd )
				)
				( attribute "PACK_TYPE" "0402"
					( Origin gFrontEnd )
				)
				( attribute "PART_NUMBER" "D97712-011"
					( Origin gFrontEnd )
				)
				( attribute "PHYS_PAGE" "204"
					( Origin gFrontEnd )
				)
				( attribute "ROOM" "PVCCIN_CPU0_PWR_VR"
					( Origin gFrontEnd )
				)
				( attribute "ROT" "0"
					( Origin gFrontEnd )
				)
				( attribute "SEC" "1"
					( Origin gFrontEnd )
				)
				( attribute "SEC_TYPE" "0402"
					( Origin gFrontEnd )
				)
				( attribute "TOLERANCE" "10%"
					( Origin gFrontEnd )
				)
				( attribute "VALUE" "1.0UF"
					( Origin gFrontEnd )
				)
				( attribute "VER" "1"
					( Origin gFrontEnd )
				)
				( attribute "VOLTAGE" "16V"
					( Units "uVoltage" "V" 1.000000)
					( Origin gFrontEnd )
				)
				( attribute "XY" "(-6425,3950)"
					( Origin gFrontEnd )
				)
				( attribute "CHIPS_PART_NAME" "CAP"
					( Origin gPackager )
				)
				( attribute "CDS_PART_NAME" "CAP_0402-1.0UF,16V,10%,X6S,D97A"
					( Origin gPackager )
				)
				( objectStatus "C4D46" )
				( pin "a"
					( attribute "PN" "1"
						( Origin gPackager )
					)
					( objectStatus "C4D46.1" )
				)
				( pin "b"
					( attribute "PN" "2"
						( Origin gPackager )
					)
					( objectStatus "C4D46.2" )
				)
			)
			( gate "@baseboard_fab2_lib.baseboard_fab2(sch_1):page204_i35"
				( attribute "CDS_LIB" "dev_discrete"
					( Origin gPackager )
				)
				( attribute "CDS_LOCATION" "C4C19"
					( Origin gPackager )
				)
				( attribute "CDS_SEC" "1"
					( Origin gPackager )
				)
				( attribute "LOCATION" "C4C19"
					( Origin gFrontEnd )
				)
				( attribute "MATERIAL" "X7R"
					( Origin gFrontEnd )
				)
				( attribute "PACK_TYPE" "0402V"
					( Origin gFrontEnd )
				)
				( attribute "PART_NUMBER" "A36096-030"
					( Origin gFrontEnd )
				)
				( attribute "PHYS_PAGE" "204"
					( Origin gFrontEnd )
				)
				( attribute "ROOM" "PVCCIN_CPU0_PWR_VR"
					( Origin gFrontEnd )
				)
				( attribute "ROT" "0"
					( Origin gFrontEnd )
				)
				( attribute "SEC" "1"
					( Origin gFrontEnd )
				)
				( attribute "SEC_TYPE" "0402V"
					( Origin gFrontEnd )
				)
				( attribute "TOLERANCE" "10%"
					( Origin gFrontEnd )
				)
				( attribute "VALUE" "0.1UF"
					( Origin gFrontEnd )
				)
				( attribute "VER" "1"
					( Origin gFrontEnd )
				)
				( attribute "VOLTAGE" "16V"
					( Units "uVoltage" "V" 1.000000)
					( Origin gFrontEnd )
				)
				( attribute "XY" "(-6650,3975)"
					( Origin gFrontEnd )
				)
				( attribute "CHIPS_PART_NAME" "CAP_A"
					( Origin gPackager )
				)
				( attribute "CDS_PART_NAME" "CAP_A_0402V-0.1UF,16V,10%,X7R,A"
					( Origin gPackager )
				)
				( objectStatus "C4C19" )
				( pin "a"
					( attribute "PN" "1"
						( Origin gPackager )
					)
					( objectStatus "C4C19.1" )
				)
				( pin "b"
					( attribute "PN" "2"
						( Origin gPackager )
					)
					( objectStatus "C4C19.2" )
				)
			)
			( gate "@baseboard_fab2_lib.baseboard_fab2(sch_1):page204_i36"
				( attribute "CDS_LIB" "mstr_discrete"
					( Origin gPackager )
				)
				( attribute "CDS_LOCATION" "C4C18"
					( Origin gPackager )
				)
				( attribute "CDS_SEC" "1"
					( Origin gPackager )
				)
				( attribute "LOCATION" "C4C18"
					( Origin gFrontEnd )
				)
				( attribute "MATERIAL" "X6S"
					( Origin gFrontEnd )
				)
				( attribute "PACK_TYPE" "0402"
					( Origin gFrontEnd )
				)
				( attribute "PART_NUMBER" "D97712-011"
					( Origin gFrontEnd )
				)
				( attribute "PHYS_PAGE" "204"
					( Origin gFrontEnd )
				)
				( attribute "ROOM" "PVCCIN_CPU0_PWR_VR"
					( Origin gFrontEnd )
				)
				( attribute "ROT" "0"
					( Origin gFrontEnd )
				)
				( attribute "SEC" "1"
					( Origin gFrontEnd )
				)
				( attribute "SEC_TYPE" "0402"
					( Origin gFrontEnd )
				)
				( attribute "TOLERANCE" "10%"
					( Origin gFrontEnd )
				)
				( attribute "VALUE" "1.0UF"
					( Origin gFrontEnd )
				)
				( attribute "VER" "1"
					( Origin gFrontEnd )
				)
				( attribute "VOLTAGE" "16V"
					( Units "uVoltage" "V" 1.000000)
					( Origin gFrontEnd )
				)
				( attribute "XY" "(-6875,3925)"
					( Origin gFrontEnd )
				)
				( attribute "CHIPS_PART_NAME" "CAP"
					( Origin gPackager )
				)
				( attribute "CDS_PART_NAME" "CAP_0402-1.0UF,16V,10%,X6S,D97A"
					( Origin gPackager )
				)
				( objectStatus "C4C18" )
				( pin "a"
					( attribute "PN" "1"
						( Origin gPackager )
					)
					( objectStatus "C4C18.1" )
				)
				( pin "b"
					( attribute "PN" "2"
						( Origin gPackager )
					)
					( objectStatus "C4C18.2" )
				)
			)
			( gate "@baseboard_fab2_lib.baseboard_fab2(sch_1):page204_i37"
				( attribute "CDS_LIB" "mstr_discrete"
					( Origin gPackager )
				)
				( attribute "CDS_LOCATION" "C6N10"
					( Origin gPackager )
				)
				( attribute "CDS_SEC" "1"
					( Origin gPackager )
				)
				( attribute "LOCATION" "C6N10"
					( Origin gFrontEnd )
				)
				( attribute "MATERIAL" "X6S"
					( Origin gFrontEnd )
				)
				( attribute "PACK_TYPE" "0805"
					( Origin gFrontEnd )
				)
				( attribute "PART_NUMBER" "C95333-007"
					( Origin gFrontEnd )
				)
				( attribute "PHYS_PAGE" "204"
					( Origin gFrontEnd )
				)
				( attribute "ROOM" "PVCCIN_CPU0_PWR_VR"
					( Origin gFrontEnd )
				)
				( attribute "ROT" "0"
					( Origin gFrontEnd )
				)
				( attribute "SEC" "1"
					( Origin gFrontEnd )
				)
				( attribute "SEC_TYPE" "0805"
					( Origin gFrontEnd )
				)
				( attribute "TOLERANCE" "10%"
					( Origin gFrontEnd )
				)
				( attribute "VALUE" "10UF"
					( Origin gFrontEnd )
				)
				( attribute "VER" "1"
					( Origin gFrontEnd )
				)
				( attribute "VOLTAGE" "16V"
					( Units "uVoltage" "V" 1.000000)
					( Origin gFrontEnd )
				)
				( attribute "XY" "(-7100,3975)"
					( Origin gFrontEnd )
				)
				( attribute "CHIPS_PART_NAME" "CAP"
					( Origin gPackager )
				)
				( attribute "CDS_PART_NAME" "CAP_0805-10UF,16V,10%,X6S,C953A"
					( Origin gPackager )
				)
				( objectStatus "C6N10" )
				( pin "a"
					( attribute "PN" "1"
						( Origin gPackager )
					)
					( objectStatus "C6N10.1" )
				)
				( pin "b"
					( attribute "PN" "2"
						( Origin gPackager )
					)
					( objectStatus "C6N10.2" )
				)
			)
			( gate "@baseboard_fab2_lib.baseboard_fab2(sch_1):page204_i38"
				( attribute "CDS_LIB" "mstr_discrete"
					( Origin gPackager )
				)
				( attribute "CDS_LOCATION" "C6P17"
					( Origin gPackager )
				)
				( attribute "CDS_SEC" "1"
					( Origin gPackager )
				)
				( attribute "LOCATION" "C6P17"
					( Origin gFrontEnd )
				)
				( attribute "MATERIAL" "X6S"
					( Origin gFrontEnd )
				)
				( attribute "PACK_TYPE" "0805"
					( Origin gFrontEnd )
				)
				( attribute "PART_NUMBER" "C95333-007"
					( Origin gFrontEnd )
				)
				( attribute "PHYS_PAGE" "204"
					( Origin gFrontEnd )
				)
				( attribute "ROOM" "PVCCIN_CPU0_PWR_VR"
					( Origin gFrontEnd )
				)
				( attribute "ROT" "0"
					( Origin gFrontEnd )
				)
				( attribute "SEC" "1"
					( Origin gFrontEnd )
				)
				( attribute "SEC_TYPE" "0805"
					( Origin gFrontEnd )
				)
				( attribute "TOLERANCE" "10%"
					( Origin gFrontEnd )
				)
				( attribute "VALUE" "10UF"
					( Origin gFrontEnd )
				)
				( attribute "VER" "1"
					( Origin gFrontEnd )
				)
				( attribute "VOLTAGE" "16V"
					( Units "uVoltage" "V" 1.000000)
					( Origin gFrontEnd )
				)
				( attribute "XY" "(-7325,3925)"
					( Origin gFrontEnd )
				)
				( attribute "CHIPS_PART_NAME" "CAP"
					( Origin gPackager )
				)
				( attribute "CDS_PART_NAME" "CAP_0805-10UF,16V,10%,X6S,C953A"
					( Origin gPackager )
				)
				( objectStatus "C6P17" )
				( pin "a"
					( attribute "PN" "1"
						( Origin gPackager )
					)
					( objectStatus "C6P17.1" )
				)
				( pin "b"
					( attribute "PN" "2"
						( Origin gPackager )
					)
					( objectStatus "C6P17.2" )
				)
			)
			( gate "@baseboard_fab2_lib.baseboard_fab2(sch_1):page204_i42"
				( attribute "CDS_LIB" "mstr_discrete"
					( Origin gPackager )
				)
				( attribute "CDS_LOCATION" "C6N11"
					( Origin gPackager )
				)
				( attribute "CDS_SEC" "1"
					( Origin gPackager )
				)
				( attribute "LOCATION" "C6N11"
					( Origin gFrontEnd )
				)
				( attribute "MATERIAL" "X6S"
					( Origin gFrontEnd )
				)
				( attribute "PACK_TYPE" "0805"
					( Origin gFrontEnd )
				)
				( attribute "PART_NUMBER" "C95333-007"
					( Origin gFrontEnd )
				)
				( attribute "PHYS_PAGE" "204"
					( Origin gFrontEnd )
				)
				( attribute "ROOM" "PVCCIN_CPU0_PWR_VR"
					( Origin gFrontEnd )
				)
				( attribute "ROT" "0"
					( Origin gFrontEnd )
				)
				( attribute "SEC" "1"
					( Origin gFrontEnd )
				)
				( attribute "SEC_TYPE" "0805"
					( Origin gFrontEnd )
				)
				( attribute "TOLERANCE" "10%"
					( Origin gFrontEnd )
				)
				( attribute "VALUE" "10UF"
					( Origin gFrontEnd )
				)
				( attribute "VER" "1"
					( Origin gFrontEnd )
				)
				( attribute "VOLTAGE" "16V"
					( Units "uVoltage" "V" 1.000000)
					( Origin gFrontEnd )
				)
				( attribute "XY" "(-7550,3950)"
					( Origin gFrontEnd )
				)
				( attribute "CHIPS_PART_NAME" "CAP"
					( Origin gPackager )
				)
				( attribute "CDS_PART_NAME" "CAP_0805-10UF,16V,10%,X6S,C953A"
					( Origin gPackager )
				)
				( objectStatus "C6N11" )
				( pin "a"
					( attribute "PN" "1"
						( Origin gPackager )
					)
					( objectStatus "C6N11.1" )
				)
				( pin "b"
					( attribute "PN" "2"
						( Origin gPackager )
					)
					( objectStatus "C6N11.2" )
				)
			)
			( gate "@baseboard_fab2_lib.baseboard_fab2(sch_1):page204_i45"
				( attribute "CDS_LIB" "mstr_discrete"
					( Origin gPackager )
				)
				( attribute "CDS_LOCATION" "R4C6"
					( Origin gPackager )
				)
				( attribute "CDS_SEC" "1"
					( Origin gPackager )
				)
				( attribute "LOCATION" "R4C6"
					( Origin gFrontEnd )
				)
				( attribute "MATERIAL" "CHIP"
					( Origin gFrontEnd )
				)
				( attribute "PACK_TYPE" "2010"
					( Origin gFrontEnd )
				)
				( attribute "PART_NUMBER" "E30969-002"
					( Origin gFrontEnd )
				)
				( attribute "PHYS_PAGE" "204"
					( Origin gFrontEnd )
				)
				( attribute "ROOM" "PVCCIN_CPU0_FILTER_VR"
					( Origin gFrontEnd )
				)
				( attribute "ROT" "0"
					( Origin gFrontEnd )
				)
				( attribute "SEC" "1"
					( Origin gFrontEnd )
				)
				( attribute "SEC_TYPE" "2010"
					( Origin gFrontEnd )
				)
				( attribute "TOLERANCE" "1%"
					( Origin gFrontEnd )
				)
				( attribute "VALUE" "0.001"
					( Origin gFrontEnd )
				)
				( attribute "VER" "1"
					( Origin gFrontEnd )
				)
				( attribute "WATTAGE" "1W"
					( Origin gFrontEnd )
				)
				( attribute "XY" "(-1825,2175)"
					( Origin gFrontEnd )
				)
				( attribute "CHIPS_PART_NAME" "RES"
					( Origin gPackager )
				)
				( attribute "CDS_PART_NAME" "RES_2010-0.001,1%,1W,CHIP,E309A"
					( Origin gPackager )
				)
				( objectStatus "R4C6" )
				( pin "a"
					( attribute "PN" "1"
						( Origin gPackager )
					)
					( objectStatus "R4C6.1" )
				)
				( pin "b"
					( attribute "PN" "2"
						( Origin gPackager )
					)
					( objectStatus "R4C6.2" )
				)
			)
			( gate "@baseboard_fab2_lib.baseboard_fab2(sch_1):page204_i46"
				( attribute "CDS_LIB" "mstr_discrete"
					( Origin gPackager )
				)
				( attribute "CDS_LOCATION" "L4C1"
					( Origin gPackager )
				)
				( attribute "CDS_SEC" "1"
					( Origin gPackager )
				)
				( attribute "LOCATION" "L4C1"
					( Origin gFrontEnd )
				)
				( attribute "MATERIAL" "IND"
					( Origin gFrontEnd )
				)
				( attribute "PACK_TYPE" "SM"
					( Origin gFrontEnd )
				)
				( attribute "PART_NUMBER" "D92183-019"
					( Origin gFrontEnd )
				)
				( attribute "PHYS_PAGE" "204"
					( Origin gFrontEnd )
				)
				( attribute "ROOM" "PVCCIN_CPU0_FILTER_VR"
					( Origin gFrontEnd )
				)
				( attribute "ROT" "0"
					( Origin gFrontEnd )
				)
				( attribute "SEC" "1"
					( Origin gFrontEnd )
				)
				( attribute "SEC_TYPE" "SM"
					( Origin gFrontEnd )
				)
				( attribute "VALUE" "100NH"
					( Origin gFrontEnd )
				)
				( attribute "VER" "1"
					( Origin gFrontEnd )
				)
				( attribute "XY" "(-2975,2175)"
					( Origin gFrontEnd )
				)
				( attribute "CHIPS_PART_NAME" "INDUCTOR"
					( Origin gPackager )
				)
				( attribute "CDS_PART_NAME" "INDUCTOR_SM-100NH,IND,D92183-0A"
					( Origin gPackager )
				)
				( objectStatus "L4C1" )
				( pin "ina"
					( attribute "PN" "1"
						( Origin gPackager )
					)
					( objectStatus "L4C1.1" )
				)
				( pin "inb"
					( attribute "PN" "2"
						( Origin gPackager )
					)
					( objectStatus "L4C1.2" )
				)
			)
			( gate "@baseboard_fab2_lib.baseboard_fab2(sch_1):page204_i48"
				( attribute "CDS_LIB" "mstr_discrete"
					( Origin gPackager )
				)
				( attribute "CDS_LOCATION" "C4D2"
					( Origin gPackager )
				)
				( attribute "CDS_SEC" "1"
					( Origin gPackager )
				)
				( attribute "LOCATION" "C4D2"
					( Origin gFrontEnd )
				)
				( attribute "MATERIAL" "OSCON"
					( Origin gFrontEnd )
				)
				( attribute "PACK_TYPE" "2626"
					( Origin gFrontEnd )
				)
				( attribute "PART_NUMBER" "A31228-047"
					( Origin gFrontEnd )
				)
				( attribute "PHYS_PAGE" "204"
					( Origin gFrontEnd )
				)
				( attribute "ROOM" "PVCCIN_CPU0_FILTER_VR"
					( Origin gFrontEnd )
				)
				( attribute "ROT" "0"
					( Origin gFrontEnd )
				)
				( attribute "SEC" "1"
					( Origin gFrontEnd )
				)
				( attribute "SEC_TYPE" "2626"
					( Origin gFrontEnd )
				)
				( attribute "TOLERANCE" "20%"
					( Origin gFrontEnd )
				)
				( attribute "VALUE" "270UF"
					( Origin gFrontEnd )
				)
				( attribute "VER" "1"
					( Origin gFrontEnd )
				)
				( attribute "VOLTAGE" "16V"
					( Units "uVoltage" "V" 1.000000)
					( Origin gFrontEnd )
				)
				( attribute "XY" "(-925,1975)"
					( Origin gFrontEnd )
				)
				( attribute "CHIPS_PART_NAME" "CAPP"
					( Origin gPackager )
				)
				( attribute "CDS_PART_NAME" "CAPP_2626-270UF,16V,20%,OSCON,A"
					( Origin gPackager )
				)
				( objectStatus "C4D2" )
				( pin "a"
					( attribute "PN" "1"
						( Origin gPackager )
					)
					( objectStatus "C4D2.1" )
				)
				( pin "b"
					( attribute "PN" "2"
						( Origin gPackager )
					)
					( objectStatus "C4D2.2" )
				)
			)
			( gate "@baseboard_fab2_lib.baseboard_fab2(sch_1):page204_i50"
				( attribute "CDS_LIB" "mstr_discrete"
					( Origin gPackager )
				)
				( attribute "CDS_LOCATION" "C4E16"
					( Origin gPackager )
				)
				( attribute "CDS_SEC" "1"
					( Origin gPackager )
				)
				( attribute "LOCATION" "C4E16"
					( Origin gFrontEnd )
				)
				( attribute "MATERIAL" "OSCON"
					( Origin gFrontEnd )
				)
				( attribute "PACK_TYPE" "2626"
					( Origin gFrontEnd )
				)
				( attribute "PART_NUMBER" "A31228-047"
					( Origin gFrontEnd )
				)
				( attribute "PHYS_PAGE" "204"
					( Origin gFrontEnd )
				)
				( attribute "ROOM" "PVCCIN_CPU0_FILTER_VR"
					( Origin gFrontEnd )
				)
				( attribute "ROT" "0"
					( Origin gFrontEnd )
				)
				( attribute "SEC" "1"
					( Origin gFrontEnd )
				)
				( attribute "SEC_TYPE" "2626"
					( Origin gFrontEnd )
				)
				( attribute "TOLERANCE" "20%"
					( Origin gFrontEnd )
				)
				( attribute "VALUE" "270UF"
					( Origin gFrontEnd )
				)
				( attribute "VER" "1"
					( Origin gFrontEnd )
				)
				( attribute "VOLTAGE" "16V"
					( Units "uVoltage" "V" 1.000000)
					( Origin gFrontEnd )
				)
				( attribute "XY" "(-1400,2000)"
					( Origin gFrontEnd )
				)
				( attribute "CHIPS_PART_NAME" "CAPP"
					( Origin gPackager )
				)
				( attribute "CDS_PART_NAME" "CAPP_2626-270UF,16V,20%,OSCON,A"
					( Origin gPackager )
				)
				( objectStatus "C4E16" )
				( pin "a"
					( attribute "PN" "1"
						( Origin gPackager )
					)
					( objectStatus "C4E16.1" )
				)
				( pin "b"
					( attribute "PN" "2"
						( Origin gPackager )
					)
					( objectStatus "C4E16.2" )
				)
			)
			( gate "@baseboard_fab2_lib.baseboard_fab2(sch_1):page204_i51"
				( attribute "CDS_LIB" "dev_discrete"
					( Origin gPackager )
				)
				( attribute "CDS_LOCATION" "C4C2"
					( Origin gPackager )
				)
				( attribute "CDS_SEC" "1"
					( Origin gPackager )
				)
				( attribute "LOCATION" "C4C2"
					( Origin gFrontEnd )
				)
				( attribute "MATERIAL" "EMPTY"
					( Origin gFrontEnd )
				)
				( attribute "PACK_TYPE" "0402V"
					( Origin gFrontEnd )
				)
				( attribute "PART_NUMBER" "A36096-030"
					( Origin gFrontEnd )
				)
				( attribute "PHYS_PAGE" "204"
					( Origin gFrontEnd )
				)
				( attribute "ROOM" "PVCCIN_CPU0_FILTER_VR"
					( Origin gFrontEnd )
				)
				( attribute "ROT" "0"
					( Origin gFrontEnd )
				)
				( attribute "SEC" "1"
					( Origin gPackager )
				)
				( attribute "TOLERANCE" "10%"
					( Origin gFrontEnd )
				)
				( attribute "VALUE" "0.1UF"
					( Origin gFrontEnd )
				)
				( attribute "VER" "1"
					( Origin gFrontEnd )
				)
				( attribute "VOLTAGE" "16V"
					( Units "uVoltage" "V" 1.000000)
					( Origin gFrontEnd )
				)
				( attribute "XY" "(-2225,1050)"
					( Origin gFrontEnd )
				)
				( attribute "CHIPS_PART_NAME" "CAP_A"
					( Origin gPackager )
				)
				( attribute "CDS_PART_NAME" "CAP_A_0402V-0.1UF,16V,10%,EMPTA"
					( Origin gPackager )
				)
				( objectStatus "C4C2" )
				( pin "a"
					( attribute "PN" "1"
						( Origin gPackager )
					)
					( objectStatus "C4C2.1" )
				)
				( pin "b"
					( attribute "PN" "2"
						( Origin gPackager )
					)
					( objectStatus "C4C2.2" )
				)
			)
			( gate "@baseboard_fab2_lib.baseboard_fab2(sch_1):page204_i53"
				( attribute "CDS_LIB" "mstr_analog"
					( Origin gPackager )
				)
				( attribute "CDS_LOCATION" "U4C1"
					( Origin gPackager )
				)
				( attribute "CDS_SEC" "1"
					( Origin gPackager )
				)
				( attribute "LOCATION" "U4C1"
					( Origin gFrontEnd )
				)
				( attribute "MATERIAL" "EMPTY"
					( Origin gFrontEnd )
				)
				( attribute "PACK_TYPE" "SM"
					( Origin gFrontEnd )
				)
				( attribute "PART_NUMBER" "G12194-001"
					( Origin gFrontEnd )
				)
				( attribute "PHYS_PAGE" "204"
					( Origin gFrontEnd )
				)
				( attribute "ROOM" "PVCCIN_CPU0_FILTER_VR"
					( Origin gFrontEnd )
				)
				( attribute "ROT" "2"
					( Origin gFrontEnd )
				)
				( attribute "SEC" "1"
					( Origin gFrontEnd )
				)
				( attribute "SEC_TYPE" "SM"
					( Origin gFrontEnd )
				)
				( attribute "VER" "1"
					( Origin gFrontEnd )
				)
				( attribute "XY" "(-2750,1275)"
					( Origin gFrontEnd )
				)
				( attribute "CHIPS_PART_NAME" "ADM4073"
					( Origin gPackager )
				)
				( attribute "CDS_PART_NAME" "ADM4073_SM-EMPTY,G12194-001"
					( Origin gPackager )
				)
				( objectStatus "U4C1" )
				( pin "gnd(0)"
					( attribute "PN" "1"
						( Origin gPackager )
					)
					( objectStatus "U4C1.1" )
				)
				( pin "gnd(1)"
					( attribute "PN" "2"
						( Origin gPackager )
					)
					( objectStatus "U4C1.2" )
				)
				( pin "\out\"
					( attribute "PN" "6"
						( Origin gPackager )
					)
					( objectStatus "U4C1.6" )
				)
				( pin "rsn"
					( attribute "PN" "5"
						( Origin gPackager )
					)
					( objectStatus "U4C1.5" )
				)
				( pin "rsp"
					( attribute "PN" "4"
						( Origin gPackager )
					)
					( objectStatus "U4C1.4" )
				)
				( pin "vcc"
					( attribute "PN" "3"
						( Origin gPackager )
					)
					( objectStatus "U4C1.3" )
				)
			)
			( gate "@baseboard_fab2_lib.baseboard_fab2(sch_1):page204_i60"
				( attribute "BOM_COST" "PROC_VRD_VCCIN_CPU0"
					( Origin gFrontEnd )
				)
				( attribute "CDS_LIB" "mstr_discrete"
					( Origin gPackager )
				)
				( attribute "CDS_LOCATION" "R4E14"
					( Origin gPackager )
				)
				( attribute "CDS_SEC" "1"
					( Origin gPackager )
				)
				( attribute "LOCATION" "R4E14"
					( Origin gFrontEnd )
				)
				( attribute "MATERIAL" "CHIP"
					( Origin gFrontEnd )
				)
				( attribute "PACK_TYPE" "0402"
					( Origin gFrontEnd )
				)
				( attribute "PART_NUMBER" "G21796-017"
					( Origin gFrontEnd )
				)
				( attribute "PHYS_PAGE" "204"
					( Origin gFrontEnd )
				)
				( attribute "ROOM" "PVCCIN_CPU0_VSENSE_VR"
					( Origin gFrontEnd )
				)
				( attribute "ROT" "0"
					( Origin gFrontEnd )
				)
				( attribute "SEC" "1"
					( Origin gPackager )
				)
				( attribute "TOLERANCE" "1%"
					( Origin gFrontEnd )
				)
				( attribute "VALUE" "100.0"
					( Origin gFrontEnd )
				)
				( attribute "VER" "1"
					( Origin gFrontEnd )
				)
				( attribute "WATTAGE" "1/16W"
					( Origin gFrontEnd )
				)
				( attribute "XY" "(-5475,2225)"
					( Origin gFrontEnd )
				)
				( attribute "CHIPS_PART_NAME" "RES"
					( Origin gPackager )
				)
				( attribute "CDS_PART_NAME" "RES_0402-100.0,1%,1/16W,CHIP,GA"
					( Origin gPackager )
				)
				( objectStatus "R4E14" )
				( pin "a"
					( attribute "PN" "1"
						( Origin gPackager )
					)
					( objectStatus "R4E14.1" )
				)
				( pin "b"
					( attribute "PN" "2"
						( Origin gPackager )
					)
					( objectStatus "R4E14.2" )
				)
			)
			( gate "@baseboard_fab2_lib.baseboard_fab2(sch_1):page204_i61"
				( attribute "BOM_COST" "PROC_VRD_VCCIN_CPU0"
					( Origin gFrontEnd )
				)
				( attribute "CDS_LIB" "mstr_discrete"
					( Origin gPackager )
				)
				( attribute "CDS_LOCATION" "R4E16"
					( Origin gPackager )
				)
				( attribute "CDS_SEC" "1"
					( Origin gPackager )
				)
				( attribute "LOCATION" "R4E16"
					( Origin gFrontEnd )
				)
				( attribute "MATERIAL" "CHIP"
					( Origin gFrontEnd )
				)
				( attribute "NO_XNET_CONNECTION" "1"
					( Origin gFrontEnd )
				)
				( attribute "PACK_TYPE" "0402"
					( Origin gFrontEnd )
				)
				( attribute "PART_NUMBER" "G21497-005"
					( Origin gFrontEnd )
				)
				( attribute "PHYS_PAGE" "204"
					( Origin gFrontEnd )
				)
				( attribute "ROOM" "PVCCIN_CPU0_VSENSE_VR"
					( Origin gFrontEnd )
				)
				( attribute "ROT" "0"
					( Origin gFrontEnd )
				)
				( attribute "SEC" "1"
					( Origin gPackager )
				)
				( attribute "TOLERANCE" "5%"
					( Origin gFrontEnd )
				)
				( attribute "VALUE" "0.0"
					( Origin gFrontEnd )
				)
				( attribute "VER" "1"
					( Origin gFrontEnd )
				)
				( attribute "WATTAGE" "1/16W"
					( Origin gFrontEnd )
				)
				( attribute "XY" "(-5475,1825)"
					( Origin gFrontEnd )
				)
				( attribute "CHIPS_PART_NAME" "RES"
					( Origin gPackager )
				)
				( attribute "CDS_PART_NAME" "RES_0402-0.0,5%,1/16W,CHIP,G21A"
					( Origin gPackager )
				)
				( objectStatus "R4E16" )
				( pin "a"
					( attribute "PN" "1"
						( Origin gPackager )
					)
					( objectStatus "R4E16.1" )
				)
				( pin "b"
					( attribute "PN" "2"
						( Origin gPackager )
					)
					( objectStatus "R4E16.2" )
				)
			)
			( gate "@baseboard_fab2_lib.baseboard_fab2(sch_1):page204_i62"
				( attribute "BOM_COST" "PROC_VRD_VCCIN_CPU0"
					( Origin gFrontEnd )
				)
				( attribute "CDS_LIB" "mstr_discrete"
					( Origin gPackager )
				)
				( attribute "CDS_LOCATION" "R4E17"
					( Origin gPackager )
				)
				( attribute "CDS_SEC" "1"
					( Origin gPackager )
				)
				( attribute "LOCATION" "R4E17"
					( Origin gFrontEnd )
				)
				( attribute "MATERIAL" "CHIP"
					( Origin gFrontEnd )
				)
				( attribute "NO_XNET_CONNECTION" "1"
					( Origin gFrontEnd )
				)
				( attribute "PACK_TYPE" "0402"
					( Origin gFrontEnd )
				)
				( attribute "PART_NUMBER" "G21497-005"
					( Origin gFrontEnd )
				)
				( attribute "PHYS_PAGE" "204"
					( Origin gFrontEnd )
				)
				( attribute "ROOM" "PVCCIN_CPU0_VSENSE_VR"
					( Origin gFrontEnd )
				)
				( attribute "ROT" "0"
					( Origin gFrontEnd )
				)
				( attribute "SEC" "1"
					( Origin gPackager )
				)
				( attribute "TOLERANCE" "5%"
					( Origin gFrontEnd )
				)
				( attribute "VALUE" "0.0"
					( Origin gFrontEnd )
				)
				( attribute "VER" "1"
					( Origin gFrontEnd )
				)
				( attribute "WATTAGE" "1/16W"
					( Origin gFrontEnd )
				)
				( attribute "XY" "(-5450,1375)"
					( Origin gFrontEnd )
				)
				( attribute "CHIPS_PART_NAME" "RES"
					( Origin gPackager )
				)
				( attribute "CDS_PART_NAME" "RES_0402-0.0,5%,1/16W,CHIP,G21A"
					( Origin gPackager )
				)
				( objectStatus "R4E17" )
				( pin "a"
					( attribute "PN" "1"
						( Origin gPackager )
					)
					( objectStatus "R4E17.1" )
				)
				( pin "b"
					( attribute "PN" "2"
						( Origin gPackager )
					)
					( objectStatus "R4E17.2" )
				)
			)
			( gate "@baseboard_fab2_lib.baseboard_fab2(sch_1):page204_i63"
				( attribute "BOM_COST" "PROC_VRD_VCCIN_CPU0"
					( Origin gFrontEnd )
				)
				( attribute "CDS_LIB" "mstr_discrete"
					( Origin gPackager )
				)
				( attribute "CDS_LOCATION" "R4E15"
					( Origin gPackager )
				)
				( attribute "CDS_SEC" "1"
					( Origin gPackager )
				)
				( attribute "LOCATION" "R4E15"
					( Origin gFrontEnd )
				)
				( attribute "MATERIAL" "EMPTY"
					( Origin gFrontEnd )
				)
				( attribute "NO_XNET_CONNECTION" "1"
					( Origin gFrontEnd )
				)
				( attribute "PACK_TYPE" "0402"
					( Origin gFrontEnd )
				)
				( attribute "PART_NUMBER" "G21796-026"
					( Origin gFrontEnd )
				)
				( attribute "PHYS_PAGE" "204"
					( Origin gFrontEnd )
				)
				( attribute "ROOM" "PVCCIN_CPU0_VSENSE_VR"
					( Origin gFrontEnd )
				)
				( attribute "ROT" "0"
					( Origin gFrontEnd )
				)
				( attribute "SEC" "1"
					( Origin gPackager )
				)
				( attribute "TOLERANCE" "1%"
					( Origin gFrontEnd )
				)
				( attribute "VALUE" "1.00K"
					( Origin gFrontEnd )
				)
				( attribute "VER" "2"
					( Origin gFrontEnd )
				)
				( attribute "WATTAGE" "1/16W"
					( Origin gFrontEnd )
				)
				( attribute "XY" "(-6275,1625)"
					( Origin gFrontEnd )
				)
				( attribute "CHIPS_PART_NAME" "RES"
					( Origin gPackager )
				)
				( attribute "CDS_PART_NAME" "RES_0402-1.00K,1%,1/16W,EMPTY,A"
					( Origin gPackager )
				)
				( objectStatus "R4E15" )
				( pin "a"
					( attribute "PN" "1"
						( Origin gPackager )
					)
					( objectStatus "R4E15.1" )
				)
				( pin "b"
					( attribute "PN" "2"
						( Origin gPackager )
					)
					( objectStatus "R4E15.2" )
				)
			)
			( gate "@baseboard_fab2_lib.baseboard_fab2(sch_1):page204_i64"
				( attribute "BOM_COST" "PROC_VRD_VCCIN_CPU0"
					( Origin gFrontEnd )
				)
				( attribute "CDS_LIB" "mstr_discrete"
					( Origin gPackager )
				)
				( attribute "CDS_LOCATION" "R4E18"
					( Origin gPackager )
				)
				( attribute "CDS_SEC" "1"
					( Origin gPackager )
				)
				( attribute "LOCATION" "R4E18"
					( Origin gFrontEnd )
				)
				( attribute "MATERIAL" "CHIP"
					( Origin gFrontEnd )
				)
				( attribute "PACK_TYPE" "0402"
					( Origin gFrontEnd )
				)
				( attribute "PART_NUMBER" "G21796-017"
					( Origin gFrontEnd )
				)
				( attribute "PHYS_PAGE" "204"
					( Origin gFrontEnd )
				)
				( attribute "ROOM" "PVCCIN_CPU0_VSENSE_VR"
					( Origin gFrontEnd )
				)
				( attribute "ROT" "0"
					( Origin gFrontEnd )
				)
				( attribute "SEC" "1"
					( Origin gPackager )
				)
				( attribute "TOLERANCE" "1%"
					( Origin gFrontEnd )
				)
				( attribute "VALUE" "100.0"
					( Origin gFrontEnd )
				)
				( attribute "VER" "1"
					( Origin gFrontEnd )
				)
				( attribute "WATTAGE" "1/16W"
					( Origin gFrontEnd )
				)
				( attribute "XY" "(-5450,975)"
					( Origin gFrontEnd )
				)
				( attribute "CHIPS_PART_NAME" "RES"
					( Origin gPackager )
				)
				( attribute "CDS_PART_NAME" "RES_0402-100.0,1%,1/16W,CHIP,GA"
					( Origin gPackager )
				)
				( objectStatus "R4E18" )
				( pin "a"
					( attribute "PN" "1"
						( Origin gPackager )
					)
					( objectStatus "R4E18.1" )
				)
				( pin "b"
					( attribute "PN" "2"
						( Origin gPackager )
					)
					( objectStatus "R4E18.2" )
				)
			)
			( gate "@baseboard_fab2_lib.baseboard_fab2(sch_1):page204_i67"
				( attribute "CDS_LIB" "mstr_discrete"
					( Origin gPackager )
				)
				( attribute "CDS_LOCATION" "C4C12"
					( Origin gPackager )
				)
				( attribute "CDS_SEC" "1"
					( Origin gPackager )
				)
				( attribute "LOCATION" "C4C12"
					( Origin gFrontEnd )
				)
				( attribute "MATERIAL" "OSCON"
					( Origin gFrontEnd )
				)
				( attribute "PACK_TYPE" "2626"
					( Origin gFrontEnd )
				)
				( attribute "PART_NUMBER" "A31228-047"
					( Origin gFrontEnd )
				)
				( attribute "PHYS_PAGE" "204"
					( Origin gFrontEnd )
				)
				( attribute "ROOM" "PVCCIN_CPU0_FILTER_VR"
					( Origin gFrontEnd )
				)
				( attribute "ROT" "0"
					( Origin gFrontEnd )
				)
				( attribute "SEC" "1"
					( Origin gFrontEnd )
				)
				( attribute "SEC_TYPE" "2626"
					( Origin gFrontEnd )
				)
				( attribute "TOLERANCE" "20%"
					( Origin gFrontEnd )
				)
				( attribute "VALUE" "270UF"
					( Origin gFrontEnd )
				)
				( attribute "VER" "1"
					( Origin gFrontEnd )
				)
				( attribute "VOLTAGE" "16V"
					( Units "uVoltage" "V" 1.000000)
					( Origin gFrontEnd )
				)
				( attribute "XY" "(-575,1975)"
					( Origin gFrontEnd )
				)
				( attribute "CHIPS_PART_NAME" "CAPP"
					( Origin gPackager )
				)
				( attribute "CDS_PART_NAME" "CAPP_2626-270UF,16V,20%,OSCON,A"
					( Origin gPackager )
				)
				( objectStatus "C4C12" )
				( pin "a"
					( attribute "PN" "1"
						( Origin gPackager )
					)
					( objectStatus "C4C12.1" )
				)
				( pin "b"
					( attribute "PN" "2"
						( Origin gPackager )
					)
					( objectStatus "C4C12.2" )
				)
			)
			( gate "@baseboard_fab2_lib.baseboard_fab2(sch_1):page204_i70"
				( attribute "CDS_LIB" "dev_discrete"
					( Origin gPackager )
				)
				( attribute "CDS_LOCATION" "C6R2"
					( Origin gPackager )
				)
				( attribute "CDS_SEC" "1"
					( Origin gPackager )
				)
				( attribute "LOCATION" "C6R2"
					( Origin gFrontEnd )
				)
				( attribute "MATERIAL" "X6S"
					( Origin gFrontEnd )
				)
				( attribute "PACK_TYPE" "0603V"
					( Origin gFrontEnd )
				)
				( attribute "PART_NUMBER" "E15431-004"
					( Origin gFrontEnd )
				)
				( attribute "PHYS_PAGE" "204"
					( Origin gFrontEnd )
				)
				( attribute "ROT" "0"
					( Origin gFrontEnd )
				)
				( attribute "SEC" "1"
					( Origin gFrontEnd )
				)
				( attribute "SEC_TYPE" "0603V"
					( Origin gFrontEnd )
				)
				( attribute "TOLERANCE" "20%"
					( Origin gFrontEnd )
				)
				( attribute "VALUE" "22.0UF"
					( Origin gFrontEnd )
				)
				( attribute "VER" "1"
					( Origin gFrontEnd )
				)
				( attribute "VOLTAGE" "4V"
					( Units "uVoltage" "V" 1.000000)
					( Origin gFrontEnd )
				)
				( attribute "XY" "(-775,3000)"
					( Origin gFrontEnd )
				)
				( attribute "CHIPS_PART_NAME" "CAP_A"
					( Origin gPackager )
				)
				( attribute "CDS_PART_NAME" "CAP_A_0603V-22.0UF,4V,20%,X6S,A"
					( Origin gPackager )
				)
				( objectStatus "C6R2" )
				( pin "a"
					( attribute "PN" "1"
						( Origin gPackager )
					)
					( objectStatus "C6R2.1" )
				)
				( pin "b"
					( attribute "PN" "2"
						( Origin gPackager )
					)
					( objectStatus "C6R2.2" )
				)
			)
			( gate "@baseboard_fab2_lib.baseboard_fab2(sch_1):page204_i71"
				( attribute "CDS_LIB" "mstr_discrete"
					( Origin gPackager )
				)
				( attribute "CDS_LOCATION" "EU4C2"
					( Origin gPackager )
				)
				( attribute "CDS_SEC" "1"
					( Origin gPackager )
				)
				( attribute "LOCATION" "EU4C2"
					( Origin gFrontEnd )
				)
				( attribute "MATERIAL" "IC"
					( Origin gFrontEnd )
				)
				( attribute "PACK_TYPE" "SM"
					( Origin gFrontEnd )
				)
				( attribute "PART_NUMBER" "H73688-001"
					( Origin gFrontEnd )
				)
				( attribute "PHYS_PAGE" "204"
					( Origin gFrontEnd )
				)
				( attribute "ROT" "0"
					( Origin gFrontEnd )
				)
				( attribute "SEC" "1"
					( Origin gPackager )
				)
				( attribute "VALUE" "IR35411"
					( Origin gFrontEnd )
				)
				( attribute "VER" "1"
					( Origin gFrontEnd )
				)
				( attribute "XY" "(-3500,3700)"
					( Origin gFrontEnd )
				)
				( attribute "CHIPS_PART_NAME" "IR354XX"
					( Origin gPackager )
				)
				( attribute "CDS_PART_NAME" "IR354XX_SM-IR35411,IC,H73688-0A"
					( Origin gPackager )
				)
				( objectStatus "EU4C2" )
				( pin "boost"
					( attribute "PN" "33"
						( Origin gPackager )
					)
					( objectStatus "EU4C2.33" )
				)
				( pin "en"
					( attribute "PN" "35"
						( Origin gPackager )
					)
					( objectStatus "EU4C2.35" )
				)
				( pin "gl(0)"
					( attribute "PN" "6"
						( Origin gPackager )
					)
					( objectStatus "EU4C2.6" )
				)
				( pin "gl(1)"
					( attribute "PN" "41"
						( Origin gPackager )
					)
					( objectStatus "EU4C2.41" )
				)
				( pin "iout"
					( attribute "PN" "38"
						( Origin gPackager )
					)
					( objectStatus "EU4C2.38" )
				)
				( pin "lgnd"
					( attribute "PN" "2"
						( Origin gPackager )
					)
					( objectStatus "EU4C2.2" )
				)
				( pin "nc"
					( attribute "PN" "31"
						( Origin gPackager )
					)
					( objectStatus "EU4C2.31" )
				)
				( pin "ocset"
					( attribute "PN" "37"
						( Origin gPackager )
					)
					( objectStatus "EU4C2.37" )
				)
				( pin "pgnd(0)"
					( attribute "PN" "5"
						( Origin gPackager )
					)
					( objectStatus "EU4C2.5" )
				)
				( pin "pgnd(1)"
					( attribute "PN" "7"
						( Origin gPackager )
					)
					( objectStatus "EU4C2.7" )
				)
				( pin "pgnd(2)"
					( attribute "PN" "40"
						( Origin gPackager )
					)
					( objectStatus "EU4C2.40" )
				)
				( pin "phase"
					( attribute "PN" "32"
						( Origin gPackager )
					)
					( objectStatus "EU4C2.32" )
				)
				( pin "pwm"
					( attribute "PN" "34"
						( Origin gPackager )
					)
					( objectStatus "EU4C2.34" )
				)
				( pin "refin"
					( attribute "PN" "39"
						( Origin gPackager )
					)
					( objectStatus "EU4C2.39" )
				)
				( pin "sw"
					( attribute "PN" "10"
						( Origin gPackager )
					)
					( objectStatus "EU4C2.10" )
				)
				( pin "tout_flt"
					( attribute "PN" "36"
						( Origin gPackager )
					)
					( objectStatus "EU4C2.36" )
				)
				( pin "vcc"
					( attribute "PN" "3"
						( Origin gPackager )
					)
					( objectStatus "EU4C2.3" )
				)
				( pin "vdrv"
					( attribute "PN" "4"
						( Origin gPackager )
					)
					( objectStatus "EU4C2.4" )
				)
				( pin "vin(0)"
					( attribute "PN" "25"
						( Origin gPackager )
					)
					( objectStatus "EU4C2.25" )
				)
				( pin "vin(1)"
					( attribute "PN" "30"
						( Origin gPackager )
					)
					( objectStatus "EU4C2.30" )
				)
				( pin "vos"
					( attribute "PN" "1"
						( Origin gPackager )
					)
					( objectStatus "EU4C2.1" )
				)
			)
			( gate "@baseboard_fab2_lib.baseboard_fab2(sch_1):page204_i83"
				( attribute "CDS_LIB" "mstr_discrete"
					( Origin gPackager )
				)
				( attribute "CDS_LOCATION" "R4D68"
					( Origin gPackager )
				)
				( attribute "CDS_SEC" "1"
					( Origin gPackager )
				)
				( attribute "LOCATION" "R4D68"
					( Origin gFrontEnd )
				)
				( attribute "MATERIAL" "EMPTY"
					( Origin gFrontEnd )
				)
				( attribute "PACK_TYPE" "0402"
					( Origin gFrontEnd )
				)
				( attribute "PART_NUMBER" "G21796-187"
					( Origin gFrontEnd )
				)
				( attribute "PHYS_PAGE" "204"
					( Origin gFrontEnd )
				)
				( attribute "ROT" "0"
					( Origin gFrontEnd )
				)
				( attribute "SEC" "1"
					( Origin gFrontEnd )
				)
				( attribute "SEC_TYPE" "0402"
					( Origin gFrontEnd )
				)
				( attribute "TOLERANCE" "1%"
					( Origin gFrontEnd )
				)
				( attribute "VALUE" "68.1K"
					( Origin gFrontEnd )
				)
				( attribute "VER" "2"
					( Origin gFrontEnd )
				)
				( attribute "WATTAGE" "1/16W"
					( Origin gFrontEnd )
				)
				( attribute "XY" "(-775,3850)"
					( Origin gFrontEnd )
				)
				( attribute "CHIPS_PART_NAME" "RES"
					( Origin gPackager )
				)
				( attribute "CDS_PART_NAME" "RES_0402-68.1K,1%,1/16W,EMPTY,A"
					( Origin gPackager )
				)
				( objectStatus "R4D68" )
				( pin "a"
					( attribute "PN" "1"
						( Origin gPackager )
					)
					( objectStatus "R4D68.1" )
				)
				( pin "b"
					( attribute "PN" "2"
						( Origin gPackager )
					)
					( objectStatus "R4D68.2" )
				)
			)
			( gate "@baseboard_fab2_lib.baseboard_fab2(sch_1):page205_i5"
				( attribute "BOM_COST" "PROC_VRD_VCCIN_CPU0"
					( Origin gFrontEnd )
				)
				( attribute "CDS_LIB" "dev_discrete"
					( Origin gPackager )
				)
				( attribute "CDS_LOCATION" "C6N7"
					( Origin gPackager )
				)
				( attribute "CDS_SEC" "1"
					( Origin gPackager )
				)
				( attribute "LOCATION" "C6N7"
					( Origin gFrontEnd )
				)
				( attribute "MATERIAL" "X6S"
					( Origin gFrontEnd )
				)
				( attribute "PACK_TYPE" "0603V"
					( Origin gFrontEnd )
				)
				( attribute "PART_NUMBER" "E15431-004"
					( Origin gFrontEnd )
				)
				( attribute "PHYS_PAGE" "205"
					( Origin gFrontEnd )
				)
				( attribute "ROOM" "PVSA_CPU0_PWR_VR"
					( Origin gFrontEnd )
				)
				( attribute "ROT" "0"
					( Origin gFrontEnd )
				)
				( attribute "SEC" "1"
					( Origin gFrontEnd )
				)
				( attribute "SEC_TYPE" "0603V"
					( Origin gFrontEnd )
				)
				( attribute "TOLERANCE" "20%"
					( Origin gFrontEnd )
				)
				( attribute "VALUE" "22.0UF"
					( Origin gFrontEnd )
				)
				( attribute "VER" "1"
					( Origin gFrontEnd )
				)
				( attribute "VOLTAGE" "4V"
					( Units "uVoltage" "V" 1.000000)
					( Origin gFrontEnd )
				)
				( attribute "XY" "(-1300,2875)"
					( Origin gFrontEnd )
				)
				( attribute "CHIPS_PART_NAME" "CAP_A"
					( Origin gPackager )
				)
				( attribute "CDS_PART_NAME" "CAP_A_0603V-22.0UF,4V,20%,X6S,A"
					( Origin gPackager )
				)
				( objectStatus "C6N7" )
				( pin "a"
					( attribute "PN" "1"
						( Origin gPackager )
					)
					( objectStatus "C6N7.1" )
				)
				( pin "b"
					( attribute "PN" "2"
						( Origin gPackager )
					)
					( objectStatus "C6N7.2" )
				)
			)
			( gate "@baseboard_fab2_lib.baseboard_fab2(sch_1):page205_i7"
				( attribute "CDS_LIB" "mstr_discrete"
					( Origin gPackager )
				)
				( attribute "CDS_LOCATION" "L4C2"
					( Origin gPackager )
				)
				( attribute "CDS_SEC" "1"
					( Origin gPackager )
				)
				( attribute "LOCATION" "L4C2"
					( Origin gFrontEnd )
				)
				( attribute "MATERIAL" "IND"
					( Origin gFrontEnd )
				)
				( attribute "PACK_TYPE" "SM"
					( Origin gFrontEnd )
				)
				( attribute "PART_NUMBER" "D92183-036"
					( Origin gFrontEnd )
				)
				( attribute "PHYS_PAGE" "205"
					( Origin gFrontEnd )
				)
				( attribute "ROOM" "PVSA_CPU0_PWR_VR"
					( Origin gFrontEnd )
				)
				( attribute "ROT" "0"
					( Origin gFrontEnd )
				)
				( attribute "SEC" "1"
					( Origin gFrontEnd )
				)
				( attribute "SEC_TYPE" "SM"
					( Origin gFrontEnd )
				)
				( attribute "VALUE" "0.3UH"
					( Origin gFrontEnd )
				)
				( attribute "VER" "1"
					( Origin gFrontEnd )
				)
				( attribute "XY" "(-1725,3425)"
					( Origin gFrontEnd )
				)
				( attribute "CHIPS_PART_NAME" "INDUCTOR"
					( Origin gPackager )
				)
				( attribute "CDS_PART_NAME" "INDUCTOR_SM-0.3UH,IND,D92183-0A"
					( Origin gPackager )
				)
				( objectStatus "L4C2" )
				( pin "ina"
					( attribute "PN" "1"
						( Origin gPackager )
					)
					( objectStatus "L4C2.1" )
				)
				( pin "inb"
					( attribute "PN" "2"
						( Origin gPackager )
					)
					( objectStatus "L4C2.2" )
				)
			)
			( gate "@baseboard_fab2_lib.baseboard_fab2(sch_1):page205_i12"
				( attribute "BOM_COST" "PROC_VRD_VCCIN_CPU0"
					( Origin gFrontEnd )
				)
				( attribute "CDS_LIB" "mstr_discrete"
					( Origin gPackager )
				)
				( attribute "CDS_LOCATION" "C6N1"
					( Origin gPackager )
				)
				( attribute "CDS_SEC" "1"
					( Origin gPackager )
				)
				( attribute "LOCATION" "C6N1"
					( Origin gFrontEnd )
				)
				( attribute "MATERIAL" "ALUM"
					( Origin gFrontEnd )
				)
				( attribute "PACK_TYPE" "3018"
					( Origin gFrontEnd )
				)
				( attribute "PART_NUMBER" "699013-049"
					( Origin gFrontEnd )
				)
				( attribute "PHYS_PAGE" "205"
					( Origin gFrontEnd )
				)
				( attribute "ROOM" "PVSA_CPU0_DECAP_VR"
					( Origin gFrontEnd )
				)
				( attribute "ROT" "0"
					( Origin gFrontEnd )
				)
				( attribute "SEC" "1"
					( Origin gFrontEnd )
				)
				( attribute "SEC_TYPE" "3018"
					( Origin gFrontEnd )
				)
				( attribute "TOLERANCE" "20%"
					( Origin gFrontEnd )
				)
				( attribute "VALUE" "470UF"
					( Origin gFrontEnd )
				)
				( attribute "VER" "1"
					( Origin gFrontEnd )
				)
				( attribute "VOLTAGE" "2.5V"
					( Units "uVoltage" "V" 1.000000)
					( Origin gFrontEnd )
				)
				( attribute "XY" "(-2000,1300)"
					( Origin gFrontEnd )
				)
				( attribute "CHIPS_PART_NAME" "CAPP"
					( Origin gPackager )
				)
				( attribute "CDS_PART_NAME" "CAPP_3018-470UF,2.5V,20%,ALUM,A"
					( Origin gPackager )
				)
				( objectStatus "C6N1" )
				( pin "a"
					( attribute "PN" "1"
						( Origin gPackager )
					)
					( objectStatus "C6N1.1" )
				)
				( pin "b"
					( attribute "PN" "2"
						( Origin gPackager )
					)
					( objectStatus "C6N1.2" )
				)
			)
			( gate "@baseboard_fab2_lib.baseboard_fab2(sch_1):page205_i14"
				( attribute "BOM_COST" "PROC_VRD_VCCIN_CPU0"
					( Origin gFrontEnd )
				)
				( attribute "CDS_LIB" "mstr_discrete"
					( Origin gPackager )
				)
				( attribute "CDS_LOCATION" "C6N4"
					( Origin gPackager )
				)
				( attribute "CDS_SEC" "1"
					( Origin gPackager )
				)
				( attribute "LOCATION" "C6N4"
					( Origin gFrontEnd )
				)
				( attribute "MATERIAL" "ALUM"
					( Origin gFrontEnd )
				)
				( attribute "PACK_TYPE" "3018"
					( Origin gFrontEnd )
				)
				( attribute "PART_NUMBER" "699013-049"
					( Origin gFrontEnd )
				)
				( attribute "PHYS_PAGE" "205"
					( Origin gFrontEnd )
				)
				( attribute "ROOM" "PVSA_CPU0_DECAP_VR"
					( Origin gFrontEnd )
				)
				( attribute "ROT" "2"
					( Origin gFrontEnd )
				)
				( attribute "SEC" "1"
					( Origin gFrontEnd )
				)
				( attribute "SEC_TYPE" "3018"
					( Origin gFrontEnd )
				)
				( attribute "TOLERANCE" "20%"
					( Origin gFrontEnd )
				)
				( attribute "VALUE" "470UF"
					( Origin gFrontEnd )
				)
				( attribute "VER" "1"
					( Origin gFrontEnd )
				)
				( attribute "VOLTAGE" "2.5V"
					( Units "uVoltage" "V" 1.000000)
					( Origin gFrontEnd )
				)
				( attribute "XY" "(-2250,1300)"
					( Origin gFrontEnd )
				)
				( attribute "CHIPS_PART_NAME" "CAPP"
					( Origin gPackager )
				)
				( attribute "CDS_PART_NAME" "CAPP_3018-470UF,2.5V,20%,ALUM,A"
					( Origin gPackager )
				)
				( objectStatus "C6N4" )
				( pin "a"
					( attribute "PN" "1"
						( Origin gPackager )
					)
					( objectStatus "C6N4.1" )
				)
				( pin "b"
					( attribute "PN" "2"
						( Origin gPackager )
					)
					( objectStatus "C6N4.2" )
				)
			)
			( gate "@baseboard_fab2_lib.baseboard_fab2(sch_1):page205_i16"
				( attribute "CDS_LIB" "mstr_discrete"
					( Origin gPackager )
				)
				( attribute "CDS_LOCATION" "C4C5"
					( Origin gPackager )
				)
				( attribute "CDS_SEC" "1"
					( Origin gPackager )
				)
				( attribute "LOCATION" "C4C5"
					( Origin gFrontEnd )
				)
				( attribute "MATERIAL" "X7R"
					( Origin gFrontEnd )
				)
				( attribute "PACK_TYPE" "0402"
					( Origin gFrontEnd )
				)
				( attribute "PART_NUMBER" "A36096-155"
					( Origin gFrontEnd )
				)
				( attribute "PHYS_PAGE" "205"
					( Origin gFrontEnd )
				)
				( attribute "ROOM" "PVSA_CPU0_PWR_VR"
					( Origin gFrontEnd )
				)
				( attribute "ROT" "0"
					( Origin gFrontEnd )
				)
				( attribute "SEC" "1"
					( Origin gFrontEnd )
				)
				( attribute "SEC_TYPE" "0402"
					( Origin gFrontEnd )
				)
				( attribute "TOLERANCE" "10%"
					( Origin gFrontEnd )
				)
				( attribute "VALUE" "0.22UF"
					( Origin gFrontEnd )
				)
				( attribute "VER" "1"
					( Origin gFrontEnd )
				)
				( attribute "VOLTAGE" "16V"
					( Units "uVoltage" "V" 1.000000)
					( Origin gFrontEnd )
				)
				( attribute "XY" "(-5775,4000)"
					( Origin gFrontEnd )
				)
				( attribute "CHIPS_PART_NAME" "CAP"
					( Origin gPackager )
				)
				( attribute "CDS_PART_NAME" "CAP_0402-0.22UF,16V,10%,X7R,A3A"
					( Origin gPackager )
				)
				( objectStatus "C4C5" )
				( pin "a"
					( attribute "PN" "1"
						( Origin gPackager )
					)
					( objectStatus "C4C5.1" )
				)
				( pin "b"
					( attribute "PN" "2"
						( Origin gPackager )
					)
					( objectStatus "C4C5.2" )
				)
			)
			( gate "@baseboard_fab2_lib.baseboard_fab2(sch_1):page205_i18"
				( attribute "CDS_LIB" "dev_discrete"
					( Origin gPackager )
				)
				( attribute "CDS_LOCATION" "C4C4"
					( Origin gPackager )
				)
				( attribute "CDS_SEC" "1"
					( Origin gPackager )
				)
				( attribute "LOCATION" "C4C4"
					( Origin gFrontEnd )
				)
				( attribute "MATERIAL" "X6S"
					( Origin gFrontEnd )
				)
				( attribute "PACK_TYPE" "0402V"
					( Origin gFrontEnd )
				)
				( attribute "PART_NUMBER" "D97712-004"
					( Origin gFrontEnd )
				)
				( attribute "PHYS_PAGE" "205"
					( Origin gFrontEnd )
				)
				( attribute "ROOM" "PVSA_CPU0_PWR_VR"
					( Origin gFrontEnd )
				)
				( attribute "ROT" "2"
					( Origin gFrontEnd )
				)
				( attribute "SEC" "1"
					( Origin gFrontEnd )
				)
				( attribute "SEC_TYPE" "0402V"
					( Origin gFrontEnd )
				)
				( attribute "TOLERANCE" "10%"
					( Origin gFrontEnd )
				)
				( attribute "VALUE" "1.0UF"
					( Origin gFrontEnd )
				)
				( attribute "VER" "1"
					( Origin gFrontEnd )
				)
				( attribute "VOLTAGE" "6.3V"
					( Units "uVoltage" "V" 1.000000)
					( Origin gFrontEnd )
				)
				( attribute "XY" "(-5875,4000)"
					( Origin gFrontEnd )
				)
				( attribute "CHIPS_PART_NAME" "CAP_A"
					( Origin gPackager )
				)
				( attribute "CDS_PART_NAME" "CAP_A_0402V-1.0UF,6.3V,10%,X6SA"
					( Origin gPackager )
				)
				( objectStatus "C4C4" )
				( pin "a"
					( attribute "PN" "1"
						( Origin gPackager )
					)
					( objectStatus "C4C4.1" )
				)
				( pin "b"
					( attribute "PN" "2"
						( Origin gPackager )
					)
					( objectStatus "C4C4.2" )
				)
			)
			( gate "@baseboard_fab2_lib.baseboard_fab2(sch_1):page205_i19"
				( attribute "CDS_LIB" "mstr_discrete"
					( Origin gPackager )
				)
				( attribute "CDS_LOCATION" "R6N3"
					( Origin gPackager )
				)
				( attribute "CDS_SEC" "1"
					( Origin gPackager )
				)
				( attribute "LOCATION" "R6N3"
					( Origin gFrontEnd )
				)
				( attribute "MATERIAL" "CHIP"
					( Origin gFrontEnd )
				)
				( attribute "PACK_TYPE" "0402"
					( Origin gFrontEnd )
				)
				( attribute "PART_NUMBER" "G21796-090"
					( Origin gFrontEnd )
				)
				( attribute "PHYS_PAGE" "205"
					( Origin gFrontEnd )
				)
				( attribute "ROOM" "PVSA_CPU0_PWR_VR"
					( Origin gFrontEnd )
				)
				( attribute "ROT" "0"
					( Origin gFrontEnd )
				)
				( attribute "SEC" "1"
					( Origin gFrontEnd )
				)
				( attribute "SEC_TYPE" "0402"
					( Origin gFrontEnd )
				)
				( attribute "TOLERANCE" "1%"
					( Origin gFrontEnd )
				)
				( attribute "VALUE" "1.0"
					( Origin gFrontEnd )
				)
				( attribute "VER" "1"
					( Origin gFrontEnd )
				)
				( attribute "WATTAGE" "1/16W"
					( Origin gFrontEnd )
				)
				( attribute "XY" "(-6075,4525)"
					( Origin gFrontEnd )
				)
				( attribute "CHIPS_PART_NAME" "RES"
					( Origin gPackager )
				)
				( attribute "CDS_PART_NAME" "RES_0402-1.0,1%,1/16W,CHIP,G21A"
					( Origin gPackager )
				)
				( objectStatus "R6N3" )
				( pin "a"
					( attribute "PN" "1"
						( Origin gPackager )
					)
					( objectStatus "R6N3.1" )
				)
				( pin "b"
					( attribute "PN" "2"
						( Origin gPackager )
					)
					( objectStatus "R6N3.2" )
				)
			)
			( gate "@baseboard_fab2_lib.baseboard_fab2(sch_1):page205_i20"
				( attribute "CDS_LIB" "mstr_discrete"
					( Origin gPackager )
				)
				( attribute "CDS_LOCATION" "C4C6"
					( Origin gPackager )
				)
				( attribute "CDS_SEC" "1"
					( Origin gPackager )
				)
				( attribute "LOCATION" "C4C6"
					( Origin gFrontEnd )
				)
				( attribute "MATERIAL" "X6S"
					( Origin gFrontEnd )
				)
				( attribute "PACK_TYPE" "0402"
					( Origin gFrontEnd )
				)
				( attribute "PART_NUMBER" "D97712-011"
					( Origin gFrontEnd )
				)
				( attribute "PHYS_PAGE" "205"
					( Origin gFrontEnd )
				)
				( attribute "ROOM" "PVSA_CPU0_PWR_VR"
					( Origin gFrontEnd )
				)
				( attribute "ROT" "0"
					( Origin gFrontEnd )
				)
				( attribute "SEC" "1"
					( Origin gFrontEnd )
				)
				( attribute "SEC_TYPE" "0402"
					( Origin gFrontEnd )
				)
				( attribute "TOLERANCE" "10%"
					( Origin gFrontEnd )
				)
				( attribute "VALUE" "1.0UF"
					( Origin gFrontEnd )
				)
				( attribute "VER" "1"
					( Origin gFrontEnd )
				)
				( attribute "VOLTAGE" "16V"
					( Units "uVoltage" "V" 1.000000)
					( Origin gFrontEnd )
				)
				( attribute "XY" "(-6350,3950)"
					( Origin gFrontEnd )
				)
				( attribute "CHIPS_PART_NAME" "CAP"
					( Origin gPackager )
				)
				( attribute "CDS_PART_NAME" "CAP_0402-1.0UF,16V,10%,X6S,D97A"
					( Origin gPackager )
				)
				( objectStatus "C4C6" )
				( pin "a"
					( attribute "PN" "1"
						( Origin gPackager )
					)
					( objectStatus "C4C6.1" )
				)
				( pin "b"
					( attribute "PN" "2"
						( Origin gPackager )
					)
					( objectStatus "C4C6.2" )
				)
			)
			( gate "@baseboard_fab2_lib.baseboard_fab2(sch_1):page205_i24"
				( attribute "BOM_COST" "PROC_VRD_VCCIN_CPU0"
					( Origin gFrontEnd )
				)
				( attribute "CDS_LIB" "mstr_discrete"
					( Origin gPackager )
				)
				( attribute "CDS_LOCATION" "R4C5"
					( Origin gPackager )
				)
				( attribute "CDS_SEC" "1"
					( Origin gPackager )
				)
				( attribute "LOCATION" "R4C5"
					( Origin gFrontEnd )
				)
				( attribute "MATERIAL" "CHIP"
					( Origin gFrontEnd )
				)
				( attribute "PACK_TYPE" "0402"
					( Origin gFrontEnd )
				)
				( attribute "PART_NUMBER" "G21796-017"
					( Origin gFrontEnd )
				)
				( attribute "PHYS_PAGE" "205"
					( Origin gFrontEnd )
				)
				( attribute "ROOM" "PVSA_CPU0_VSENSE_VR"
					( Origin gFrontEnd )
				)
				( attribute "ROT" "0"
					( Origin gFrontEnd )
				)
				( attribute "SEC" "1"
					( Origin gFrontEnd )
				)
				( attribute "SEC_TYPE" "0402"
					( Origin gFrontEnd )
				)
				( attribute "TOLERANCE" "1%"
					( Origin gFrontEnd )
				)
				( attribute "VALUE" "100.0"
					( Origin gFrontEnd )
				)
				( attribute "VER" "1"
					( Origin gFrontEnd )
				)
				( attribute "WATTAGE" "1/16W"
					( Origin gFrontEnd )
				)
				( attribute "XY" "(-5100,2425)"
					( Origin gFrontEnd )
				)
				( attribute "CHIPS_PART_NAME" "RES"
					( Origin gPackager )
				)
				( attribute "CDS_PART_NAME" "RES_0402-100.0,1%,1/16W,CHIP,GA"
					( Origin gPackager )
				)
				( objectStatus "R4C5" )
				( pin "a"
					( attribute "PN" "1"
						( Origin gPackager )
					)
					( objectStatus "R4C5.1" )
				)
				( pin "b"
					( attribute "PN" "2"
						( Origin gPackager )
					)
					( objectStatus "R4C5.2" )
				)
			)
			( gate "@baseboard_fab2_lib.baseboard_fab2(sch_1):page205_i25"
				( attribute "CDS_LIB" "mstr_discrete"
					( Origin gPackager )
				)
				( attribute "CDS_LOCATION" "C4C8"
					( Origin gPackager )
				)
				( attribute "CDS_SEC" "1"
					( Origin gPackager )
				)
				( attribute "LOCATION" "C4C8"
					( Origin gFrontEnd )
				)
				( attribute "MATERIAL" "X7R"
					( Origin gFrontEnd )
				)
				( attribute "PACK_TYPE" "0402"
					( Origin gFrontEnd )
				)
				( attribute "PART_NUMBER" "A36096-104"
					( Origin gFrontEnd )
				)
				( attribute "PHYS_PAGE" "205"
					( Origin gFrontEnd )
				)
				( attribute "ROOM" "PVSA_CPU0_PWR_VR"
					( Origin gFrontEnd )
				)
				( attribute "ROT" "2"
					( Origin gFrontEnd )
				)
				( attribute "SEC" "1"
					( Origin gFrontEnd )
				)
				( attribute "SEC_TYPE" "0402"
					( Origin gFrontEnd )
				)
				( attribute "SPOF" "TRUE"
					( Origin gFrontEnd )
				)
				( attribute "TOLERANCE" "10%"
					( Origin gFrontEnd )
				)
				( attribute "VALUE" "0.220UF"
					( Origin gFrontEnd )
				)
				( attribute "VER" "1"
					( Origin gFrontEnd )
				)
				( attribute "VOLTAGE" "16V"
					( Units "uVoltage" "V" 1.000000)
					( Origin gFrontEnd )
				)
				( attribute "XY" "(-6400,3350)"
					( Origin gFrontEnd )
				)
				( attribute "CHIPS_PART_NAME" "CAP"
					( Origin gPackager )
				)
				( attribute "CDS_PART_NAME" "CAP_0402-0.220UF,16V,10%,X7R,AA"
					( Origin gPackager )
				)
				( objectStatus "C4C8" )
				( pin "a"
					( attribute "PN" "1"
						( Origin gPackager )
					)
					( objectStatus "C4C8.1" )
				)
				( pin "b"
					( attribute "PN" "2"
						( Origin gPackager )
					)
					( objectStatus "C4C8.2" )
				)
			)
			( gate "@baseboard_fab2_lib.baseboard_fab2(sch_1):page205_i26"
				( attribute "BOM_COST" "PROC_VRD_VCCIN_CPU0"
					( Origin gFrontEnd )
				)
				( attribute "CDS_LIB" "mstr_discrete"
					( Origin gPackager )
				)
				( attribute "CDS_LOCATION" "R4C4"
					( Origin gPackager )
				)
				( attribute "CDS_SEC" "1"
					( Origin gPackager )
				)
				( attribute "LOCATION" "R4C4"
					( Origin gFrontEnd )
				)
				( attribute "MATERIAL" "CHIP"
					( Origin gFrontEnd )
				)
				( attribute "PACK_TYPE" "0402"
					( Origin gFrontEnd )
				)
				( attribute "PART_NUMBER" "G21497-005"
					( Origin gFrontEnd )
				)
				( attribute "PHYS_PAGE" "205"
					( Origin gFrontEnd )
				)
				( attribute "ROOM" "PVSA_CPU0_VSENSE_VR"
					( Origin gFrontEnd )
				)
				( attribute "ROT" "0"
					( Origin gFrontEnd )
				)
				( attribute "SEC" "1"
					( Origin gFrontEnd )
				)
				( attribute "SEC_TYPE" "0402"
					( Origin gFrontEnd )
				)
				( attribute "TOLERANCE" "5%"
					( Origin gFrontEnd )
				)
				( attribute "VALUE" "0.0"
					( Origin gFrontEnd )
				)
				( attribute "VER" "1"
					( Origin gFrontEnd )
				)
				( attribute "WATTAGE" "1/16W"
					( Origin gFrontEnd )
				)
				( attribute "XY" "(-5075,2025)"
					( Origin gFrontEnd )
				)
				( attribute "CHIPS_PART_NAME" "RES"
					( Origin gPackager )
				)
				( attribute "CDS_PART_NAME" "RES_0402-0.0,5%,1/16W,CHIP,G21A"
					( Origin gPackager )
				)
				( objectStatus "R4C4" )
				( pin "a"
					( attribute "PN" "1"
						( Origin gPackager )
					)
					( objectStatus "R4C4.1" )
				)
				( pin "b"
					( attribute "PN" "2"
						( Origin gPackager )
					)
					( objectStatus "R4C4.2" )
				)
			)
			( gate "@baseboard_fab2_lib.baseboard_fab2(sch_1):page205_i29"
				( attribute "BOM_COST" "PROC_VRD_VCCIN_CPU0"
					( Origin gFrontEnd )
				)
				( attribute "CDS_LIB" "mstr_discrete"
					( Origin gPackager )
				)
				( attribute "CDS_LOCATION" "R4C1"
					( Origin gPackager )
				)
				( attribute "CDS_SEC" "1"
					( Origin gPackager )
				)
				( attribute "LOCATION" "R4C1"
					( Origin gFrontEnd )
				)
				( attribute "MATERIAL" "CHIP"
					( Origin gFrontEnd )
				)
				( attribute "PACK_TYPE" "0402"
					( Origin gFrontEnd )
				)
				( attribute "PART_NUMBER" "G21796-017"
					( Origin gFrontEnd )
				)
				( attribute "PHYS_PAGE" "205"
					( Origin gFrontEnd )
				)
				( attribute "ROOM" "PVSA_CPU0_VSENSE_VR"
					( Origin gFrontEnd )
				)
				( attribute "ROT" "0"
					( Origin gFrontEnd )
				)
				( attribute "SEC" "1"
					( Origin gFrontEnd )
				)
				( attribute "SEC_TYPE" "0402"
					( Origin gFrontEnd )
				)
				( attribute "TOLERANCE" "1%"
					( Origin gFrontEnd )
				)
				( attribute "VALUE" "100.0"
					( Origin gFrontEnd )
				)
				( attribute "VER" "1"
					( Origin gFrontEnd )
				)
				( attribute "WATTAGE" "1/16W"
					( Origin gFrontEnd )
				)
				( attribute "XY" "(-5075,1200)"
					( Origin gFrontEnd )
				)
				( attribute "CHIPS_PART_NAME" "RES"
					( Origin gPackager )
				)
				( attribute "CDS_PART_NAME" "RES_0402-100.0,1%,1/16W,CHIP,GA"
					( Origin gPackager )
				)
				( objectStatus "R4C1" )
				( pin "a"
					( attribute "PN" "1"
						( Origin gPackager )
					)
					( objectStatus "R4C1.1" )
				)
				( pin "b"
					( attribute "PN" "2"
						( Origin gPackager )
					)
					( objectStatus "R4C1.2" )
				)
			)
			( gate "@baseboard_fab2_lib.baseboard_fab2(sch_1):page205_i30"
				( attribute "BOM_COST" "PROC_VRD_VCCIN_CPU0"
					( Origin gFrontEnd )
				)
				( attribute "CDS_LIB" "mstr_discrete"
					( Origin gPackager )
				)
				( attribute "CDS_LOCATION" "R4C2"
					( Origin gPackager )
				)
				( attribute "CDS_SEC" "1"
					( Origin gPackager )
				)
				( attribute "LOCATION" "R4C2"
					( Origin gFrontEnd )
				)
				( attribute "MATERIAL" "CHIP"
					( Origin gFrontEnd )
				)
				( attribute "PACK_TYPE" "0402"
					( Origin gFrontEnd )
				)
				( attribute "PART_NUMBER" "G21497-005"
					( Origin gFrontEnd )
				)
				( attribute "PHYS_PAGE" "205"
					( Origin gFrontEnd )
				)
				( attribute "ROOM" "PVSA_CPU0_VSENSE_VR"
					( Origin gFrontEnd )
				)
				( attribute "ROT" "0"
					( Origin gFrontEnd )
				)
				( attribute "SEC" "1"
					( Origin gFrontEnd )
				)
				( attribute "SEC_TYPE" "0402"
					( Origin gFrontEnd )
				)
				( attribute "TOLERANCE" "5%"
					( Origin gFrontEnd )
				)
				( attribute "VALUE" "0.0"
					( Origin gFrontEnd )
				)
				( attribute "VER" "1"
					( Origin gFrontEnd )
				)
				( attribute "WATTAGE" "1/16W"
					( Origin gFrontEnd )
				)
				( attribute "XY" "(-5075,1575)"
					( Origin gFrontEnd )
				)
				( attribute "CHIPS_PART_NAME" "RES"
					( Origin gPackager )
				)
				( attribute "CDS_PART_NAME" "RES_0402-0.0,5%,1/16W,CHIP,G21A"
					( Origin gPackager )
				)
				( objectStatus "R4C2" )
				( pin "a"
					( attribute "PN" "1"
						( Origin gPackager )
					)
					( objectStatus "R4C2.1" )
				)
				( pin "b"
					( attribute "PN" "2"
						( Origin gPackager )
					)
					( objectStatus "R4C2.2" )
				)
			)
			( gate "@baseboard_fab2_lib.baseboard_fab2(sch_1):page205_i31"
				( attribute "CDS_LIB" "dev_discrete"
					( Origin gPackager )
				)
				( attribute "CDS_LOCATION" "C4C10"
					( Origin gPackager )
				)
				( attribute "CDS_SEC" "1"
					( Origin gPackager )
				)
				( attribute "LOCATION" "C4C10"
					( Origin gFrontEnd )
				)
				( attribute "MATERIAL" "X7R"
					( Origin gFrontEnd )
				)
				( attribute "PACK_TYPE" "0402V"
					( Origin gFrontEnd )
				)
				( attribute "PART_NUMBER" "A36096-030"
					( Origin gFrontEnd )
				)
				( attribute "PHYS_PAGE" "205"
					( Origin gFrontEnd )
				)
				( attribute "ROOM" "PVSA_CPU0_PWR_VR"
					( Origin gFrontEnd )
				)
				( attribute "ROT" "0"
					( Origin gFrontEnd )
				)
				( attribute "SEC" "1"
					( Origin gFrontEnd )
				)
				( attribute "SEC_TYPE" "0402V"
					( Origin gFrontEnd )
				)
				( attribute "TOLERANCE" "10%"
					( Origin gFrontEnd )
				)
				( attribute "VALUE" "0.1UF"
					( Origin gFrontEnd )
				)
				( attribute "VER" "1"
					( Origin gFrontEnd )
				)
				( attribute "VOLTAGE" "16V"
					( Units "uVoltage" "V" 1.000000)
					( Origin gFrontEnd )
				)
				( attribute "XY" "(-6600,4000)"
					( Origin gFrontEnd )
				)
				( attribute "CHIPS_PART_NAME" "CAP_A"
					( Origin gPackager )
				)
				( attribute "CDS_PART_NAME" "CAP_A_0402V-0.1UF,16V,10%,X7R,A"
					( Origin gPackager )
				)
				( objectStatus "C4C10" )
				( pin "a"
					( attribute "PN" "1"
						( Origin gPackager )
					)
					( objectStatus "C4C10.1" )
				)
				( pin "b"
					( attribute "PN" "2"
						( Origin gPackager )
					)
					( objectStatus "C4C10.2" )
				)
			)
			( gate "@baseboard_fab2_lib.baseboard_fab2(sch_1):page205_i32"
				( attribute "CDS_LIB" "mstr_discrete"
					( Origin gPackager )
				)
				( attribute "CDS_LOCATION" "C4C9"
					( Origin gPackager )
				)
				( attribute "CDS_SEC" "1"
					( Origin gPackager )
				)
				( attribute "LOCATION" "C4C9"
					( Origin gFrontEnd )
				)
				( attribute "MATERIAL" "X6S"
					( Origin gFrontEnd )
				)
				( attribute "PACK_TYPE" "0402"
					( Origin gFrontEnd )
				)
				( attribute "PART_NUMBER" "D97712-011"
					( Origin gFrontEnd )
				)
				( attribute "PHYS_PAGE" "205"
					( Origin gFrontEnd )
				)
				( attribute "ROOM" "PVSA_CPU0_PWR_VR"
					( Origin gFrontEnd )
				)
				( attribute "ROT" "0"
					( Origin gFrontEnd )
				)
				( attribute "SEC" "1"
					( Origin gFrontEnd )
				)
				( attribute "SEC_TYPE" "0402"
					( Origin gFrontEnd )
				)
				( attribute "TOLERANCE" "10%"
					( Origin gFrontEnd )
				)
				( attribute "VALUE" "1.0UF"
					( Origin gFrontEnd )
				)
				( attribute "VER" "1"
					( Origin gFrontEnd )
				)
				( attribute "VOLTAGE" "16V"
					( Units "uVoltage" "V" 1.000000)
					( Origin gFrontEnd )
				)
				( attribute "XY" "(-6850,3950)"
					( Origin gFrontEnd )
				)
				( attribute "CHIPS_PART_NAME" "CAP"
					( Origin gPackager )
				)
				( attribute "CDS_PART_NAME" "CAP_0402-1.0UF,16V,10%,X6S,D97A"
					( Origin gPackager )
				)
				( objectStatus "C4C9" )
				( pin "a"
					( attribute "PN" "1"
						( Origin gPackager )
					)
					( objectStatus "C4C9.1" )
				)
				( pin "b"
					( attribute "PN" "2"
						( Origin gPackager )
					)
					( objectStatus "C4C9.2" )
				)
			)
			( gate "@baseboard_fab2_lib.baseboard_fab2(sch_1):page205_i33"
				( attribute "CDS_LIB" "mstr_discrete"
					( Origin gPackager )
				)
				( attribute "CDS_LOCATION" "C6N2"
					( Origin gPackager )
				)
				( attribute "CDS_SEC" "1"
					( Origin gPackager )
				)
				( attribute "LOCATION" "C6N2"
					( Origin gFrontEnd )
				)
				( attribute "MATERIAL" "X6S"
					( Origin gFrontEnd )
				)
				( attribute "PACK_TYPE" "0805"
					( Origin gFrontEnd )
				)
				( attribute "PART_NUMBER" "C95333-007"
					( Origin gFrontEnd )
				)
				( attribute "PHYS_PAGE" "205"
					( Origin gFrontEnd )
				)
				( attribute "ROOM" "PVSA_CPU0_PWR_VR"
					( Origin gFrontEnd )
				)
				( attribute "ROT" "0"
					( Origin gFrontEnd )
				)
				( attribute "SEC" "1"
					( Origin gFrontEnd )
				)
				( attribute "SEC_TYPE" "0805"
					( Origin gFrontEnd )
				)
				( attribute "TOLERANCE" "10%"
					( Origin gFrontEnd )
				)
				( attribute "VALUE" "10UF"
					( Origin gFrontEnd )
				)
				( attribute "VER" "1"
					( Origin gFrontEnd )
				)
				( attribute "VOLTAGE" "16V"
					( Units "uVoltage" "V" 1.000000)
					( Origin gFrontEnd )
				)
				( attribute "XY" "(-7100,3975)"
					( Origin gFrontEnd )
				)
				( attribute "CHIPS_PART_NAME" "CAP"
					( Origin gPackager )
				)
				( attribute "CDS_PART_NAME" "CAP_0805-10UF,16V,10%,X6S,C953A"
					( Origin gPackager )
				)
				( objectStatus "C6N2" )
				( pin "a"
					( attribute "PN" "1"
						( Origin gPackager )
					)
					( objectStatus "C6N2.1" )
				)
				( pin "b"
					( attribute "PN" "2"
						( Origin gPackager )
					)
					( objectStatus "C6N2.2" )
				)
			)
			( gate "@baseboard_fab2_lib.baseboard_fab2(sch_1):page205_i34"
				( attribute "CDS_LIB" "mstr_discrete"
					( Origin gPackager )
				)
				( attribute "CDS_LOCATION" "C6N3"
					( Origin gPackager )
				)
				( attribute "CDS_SEC" "1"
					( Origin gPackager )
				)
				( attribute "LOCATION" "C6N3"
					( Origin gFrontEnd )
				)
				( attribute "MATERIAL" "X6S"
					( Origin gFrontEnd )
				)
				( attribute "PACK_TYPE" "0805"
					( Origin gFrontEnd )
				)
				( attribute "PART_NUMBER" "C95333-007"
					( Origin gFrontEnd )
				)
				( attribute "PHYS_PAGE" "205"
					( Origin gFrontEnd )
				)
				( attribute "ROOM" "PVSA_CPU0_PWR_VR"
					( Origin gFrontEnd )
				)
				( attribute "ROT" "0"
					( Origin gFrontEnd )
				)
				( attribute "SEC" "1"
					( Origin gFrontEnd )
				)
				( attribute "SEC_TYPE" "0805"
					( Origin gFrontEnd )
				)
				( attribute "TOLERANCE" "10%"
					( Origin gFrontEnd )
				)
				( attribute "VALUE" "10UF"
					( Origin gFrontEnd )
				)
				( attribute "VER" "1"
					( Origin gFrontEnd )
				)
				( attribute "VOLTAGE" "16V"
					( Units "uVoltage" "V" 1.000000)
					( Origin gFrontEnd )
				)
				( attribute "XY" "(-7325,3950)"
					( Origin gFrontEnd )
				)
				( attribute "CHIPS_PART_NAME" "CAP"
					( Origin gPackager )
				)
				( attribute "CDS_PART_NAME" "CAP_0805-10UF,16V,10%,X6S,C953A"
					( Origin gPackager )
				)
				( objectStatus "C6N3" )
				( pin "a"
					( attribute "PN" "1"
						( Origin gPackager )
					)
					( objectStatus "C6N3.1" )
				)
				( pin "b"
					( attribute "PN" "2"
						( Origin gPackager )
					)
					( objectStatus "C6N3.2" )
				)
			)
			( gate "@baseboard_fab2_lib.baseboard_fab2(sch_1):page205_i35"
				( attribute "CDS_LIB" "mstr_discrete"
					( Origin gPackager )
				)
				( attribute "CDS_LOCATION" "C6N6"
					( Origin gPackager )
				)
				( attribute "CDS_SEC" "1"
					( Origin gPackager )
				)
				( attribute "LOCATION" "C6N6"
					( Origin gFrontEnd )
				)
				( attribute "MATERIAL" "X6S"
					( Origin gFrontEnd )
				)
				( attribute "PACK_TYPE" "0805"
					( Origin gFrontEnd )
				)
				( attribute "PART_NUMBER" "C95333-007"
					( Origin gFrontEnd )
				)
				( attribute "PHYS_PAGE" "205"
					( Origin gFrontEnd )
				)
				( attribute "ROOM" "PVSA_CPU0_PWR_VR"
					( Origin gFrontEnd )
				)
				( attribute "ROT" "0"
					( Origin gFrontEnd )
				)
				( attribute "SEC" "1"
					( Origin gFrontEnd )
				)
				( attribute "SEC_TYPE" "0805"
					( Origin gFrontEnd )
				)
				( attribute "TOLERANCE" "10%"
					( Origin gFrontEnd )
				)
				( attribute "VALUE" "10UF"
					( Origin gFrontEnd )
				)
				( attribute "VER" "1"
					( Origin gFrontEnd )
				)
				( attribute "VOLTAGE" "16V"
					( Units "uVoltage" "V" 1.000000)
					( Origin gFrontEnd )
				)
				( attribute "XY" "(-7575,4000)"
					( Origin gFrontEnd )
				)
				( attribute "CHIPS_PART_NAME" "CAP"
					( Origin gPackager )
				)
				( attribute "CDS_PART_NAME" "CAP_0805-10UF,16V,10%,X6S,C953A"
					( Origin gPackager )
				)
				( objectStatus "C6N6" )
				( pin "a"
					( attribute "PN" "1"
						( Origin gPackager )
					)
					( objectStatus "C6N6.1" )
				)
				( pin "b"
					( attribute "PN" "2"
						( Origin gPackager )
					)
					( objectStatus "C6N6.2" )
				)
			)
			( gate "@baseboard_fab2_lib.baseboard_fab2(sch_1):page205_i37"
				( attribute "BOM_COST" "PROC_VRD_VCCIN_CPU0"
					( Origin gFrontEnd )
				)
				( attribute "CDS_LIB" "mstr_discrete"
					( Origin gPackager )
				)
				( attribute "CDS_LOCATION" "R4C3"
					( Origin gPackager )
				)
				( attribute "CDS_SEC" "1"
					( Origin gPackager )
				)
				( attribute "LOCATION" "R4C3"
					( Origin gFrontEnd )
				)
				( attribute "MATERIAL" "EMPTY"
					( Origin gFrontEnd )
				)
				( attribute "NO_XNET_CONNECTION" "1"
					( Origin gFrontEnd )
				)
				( attribute "PACK_TYPE" "0402"
					( Origin gFrontEnd )
				)
				( attribute "PART_NUMBER" "G21796-026"
					( Origin gFrontEnd )
				)
				( attribute "PHYS_PAGE" "205"
					( Origin gFrontEnd )
				)
				( attribute "ROOM" "PVSA_CPU0_VSENSE_VR"
					( Origin gFrontEnd )
				)
				( attribute "ROT" "0"
					( Origin gFrontEnd )
				)
				( attribute "SEC" "1"
					( Origin gFrontEnd )
				)
				( attribute "SEC_TYPE" "0402"
					( Origin gFrontEnd )
				)
				( attribute "TOLERANCE" "1%"
					( Origin gFrontEnd )
				)
				( attribute "VALUE" "1.00K"
					( Origin gFrontEnd )
				)
				( attribute "VER" "2"
					( Origin gFrontEnd )
				)
				( attribute "WATTAGE" "1/16W"
					( Origin gFrontEnd )
				)
				( attribute "XY" "(-5750,1825)"
					( Origin gFrontEnd )
				)
				( attribute "CHIPS_PART_NAME" "RES"
					( Origin gPackager )
				)
				( attribute "CDS_PART_NAME" "RES_0402-1.00K,1%,1/16W,EMPTY,A"
					( Origin gPackager )
				)
				( objectStatus "R4C3" )
				( pin "a"
					( attribute "PN" "1"
						( Origin gPackager )
					)
					( objectStatus "R4C3.1" )
				)
				( pin "b"
					( attribute "PN" "2"
						( Origin gPackager )
					)
					( objectStatus "R4C3.2" )
				)
			)
			( gate "@baseboard_fab2_lib.baseboard_fab2(sch_1):page205_i43"
				( attribute "CDS_LIB" "dev_discrete"
					( Origin gPackager )
				)
				( attribute "CDS_LOCATION" "C4C11"
					( Origin gPackager )
				)
				( attribute "CDS_SEC" "1"
					( Origin gPackager )
				)
				( attribute "LOCATION" "C4C11"
					( Origin gFrontEnd )
				)
				( attribute "MATERIAL" "X6S"
					( Origin gFrontEnd )
				)
				( attribute "PACK_TYPE" "0603V"
					( Origin gFrontEnd )
				)
				( attribute "PART_NUMBER" "E15431-004"
					( Origin gFrontEnd )
				)
				( attribute "PHYS_PAGE" "205"
					( Origin gFrontEnd )
				)
				( attribute "ROT" "0"
					( Origin gFrontEnd )
				)
				( attribute "SEC" "1"
					( Origin gFrontEnd )
				)
				( attribute "SEC_TYPE" "0603V"
					( Origin gFrontEnd )
				)
				( attribute "TOLERANCE" "20%"
					( Origin gFrontEnd )
				)
				( attribute "VALUE" "22.0UF"
					( Origin gFrontEnd )
				)
				( attribute "VER" "1"
					( Origin gFrontEnd )
				)
				( attribute "VOLTAGE" "4V"
					( Units "uVoltage" "V" 1.000000)
					( Origin gFrontEnd )
				)
				( attribute "XY" "(-950,2875)"
					( Origin gFrontEnd )
				)
				( attribute "CHIPS_PART_NAME" "CAP_A"
					( Origin gPackager )
				)
				( attribute "CDS_PART_NAME" "CAP_A_0603V-22.0UF,4V,20%,X6S,A"
					( Origin gPackager )
				)
				( objectStatus "C4C11" )
				( pin "a"
					( attribute "PN" "1"
						( Origin gPackager )
					)
					( objectStatus "C4C11.1" )
				)
				( pin "b"
					( attribute "PN" "2"
						( Origin gPackager )
					)
					( objectStatus "C4C11.2" )
				)
			)
			( gate "@baseboard_fab2_lib.baseboard_fab2(sch_1):page205_i45"
				( attribute "CDS_LIB" "mstr_discrete"
					( Origin gPackager )
				)
				( attribute "CDS_LOCATION" "R6N4"
					( Origin gPackager )
				)
				( attribute "CDS_SEC" "1"
					( Origin gPackager )
				)
				( attribute "LOCATION" "R6N4"
					( Origin gFrontEnd )
				)
				( attribute "MATERIAL" "CHIP"
					( Origin gFrontEnd )
				)
				( attribute "PACK_TYPE" "0402"
					( Origin gFrontEnd )
				)
				( attribute "PART_NUMBER" "G21796-208"
					( Origin gFrontEnd )
				)
				( attribute "PHYS_PAGE" "205"
					( Origin gFrontEnd )
				)
				( attribute "ROT" "0"
					( Origin gFrontEnd )
				)
				( attribute "SEC" "1"
					( Origin gPackager )
				)
				( attribute "TOLERANCE" "1.0%"
					( Origin gFrontEnd )
				)
				( attribute "VALUE" "51.1"
					( Origin gFrontEnd )
				)
				( attribute "VER" "2"
					( Origin gFrontEnd )
				)
				( attribute "WATTAGE" "1/16W"
					( Origin gFrontEnd )
				)
				( attribute "XY" "(-625,2875)"
					( Origin gFrontEnd )
				)
				( attribute "CHIPS_PART_NAME" "RES"
					( Origin gPackager )
				)
				( attribute "CDS_PART_NAME" "RES_0402-51.1,1.0%,1/16W,CHIP,A"
					( Origin gPackager )
				)
				( objectStatus "R6N4" )
				( pin "a"
					( attribute "PN" "1"
						( Origin gPackager )
					)
					( objectStatus "R6N4.1" )
				)
				( pin "b"
					( attribute "PN" "2"
						( Origin gPackager )
					)
					( objectStatus "R6N4.2" )
				)
			)
			( gate "@baseboard_fab2_lib.baseboard_fab2(sch_1):page205_i46"
				( attribute "CDS_LIB" "mstr_discrete"
					( Origin gPackager )
				)
				( attribute "CDS_LOCATION" "EU4C1"
					( Origin gPackager )
				)
				( attribute "CDS_SEC" "1"
					( Origin gPackager )
				)
				( attribute "LOCATION" "EU4C1"
					( Origin gFrontEnd )
				)
				( attribute "MATERIAL" "IC"
					( Origin gFrontEnd )
				)
				( attribute "PACK_TYPE" "SM"
					( Origin gFrontEnd )
				)
				( attribute "PART_NUMBER" "H73684-001"
					( Origin gFrontEnd )
				)
				( attribute "PHYS_PAGE" "205"
					( Origin gFrontEnd )
				)
				( attribute "ROT" "0"
					( Origin gFrontEnd )
				)
				( attribute "SEC" "1"
					( Origin gPackager )
				)
				( attribute "VALUE" "IR35412"
					( Origin gFrontEnd )
				)
				( attribute "VER" "1"
					( Origin gFrontEnd )
				)
				( attribute "XY" "(-3500,3725)"
					( Origin gFrontEnd )
				)
				( attribute "CHIPS_PART_NAME" "IR354XX"
					( Origin gPackager )
				)
				( attribute "CDS_PART_NAME" "IR354XX_SM-IR35412,IC,H73684-0A"
					( Origin gPackager )
				)
				( objectStatus "EU4C1" )
				( pin "boost"
					( attribute "PN" "33"
						( Origin gPackager )
					)
					( objectStatus "EU4C1.33" )
				)
				( pin "en"
					( attribute "PN" "35"
						( Origin gPackager )
					)
					( objectStatus "EU4C1.35" )
				)
				( pin "gl(0)"
					( attribute "PN" "6"
						( Origin gPackager )
					)
					( objectStatus "EU4C1.6" )
				)
				( pin "gl(1)"
					( attribute "PN" "41"
						( Origin gPackager )
					)
					( objectStatus "EU4C1.41" )
				)
				( pin "iout"
					( attribute "PN" "38"
						( Origin gPackager )
					)
					( objectStatus "EU4C1.38" )
				)
				( pin "lgnd"
					( attribute "PN" "2"
						( Origin gPackager )
					)
					( objectStatus "EU4C1.2" )
				)
				( pin "nc"
					( attribute "PN" "31"
						( Origin gPackager )
					)
					( objectStatus "EU4C1.31" )
				)
				( pin "ocset"
					( attribute "PN" "37"
						( Origin gPackager )
					)
					( objectStatus "EU4C1.37" )
				)
				( pin "pgnd(0)"
					( attribute "PN" "5"
						( Origin gPackager )
					)
					( objectStatus "EU4C1.5" )
				)
				( pin "pgnd(1)"
					( attribute "PN" "7"
						( Origin gPackager )
					)
					( objectStatus "EU4C1.7" )
				)
				( pin "pgnd(2)"
					( attribute "PN" "40"
						( Origin gPackager )
					)
					( objectStatus "EU4C1.40" )
				)
				( pin "phase"
					( attribute "PN" "32"
						( Origin gPackager )
					)
					( objectStatus "EU4C1.32" )
				)
				( pin "pwm"
					( attribute "PN" "34"
						( Origin gPackager )
					)
					( objectStatus "EU4C1.34" )
				)
				( pin "refin"
					( attribute "PN" "39"
						( Origin gPackager )
					)
					( objectStatus "EU4C1.39" )
				)
				( pin "sw"
					( attribute "PN" "10"
						( Origin gPackager )
					)
					( objectStatus "EU4C1.10" )
				)
				( pin "tout_flt"
					( attribute "PN" "36"
						( Origin gPackager )
					)
					( objectStatus "EU4C1.36" )
				)
				( pin "vcc"
					( attribute "PN" "3"
						( Origin gPackager )
					)
					( objectStatus "EU4C1.3" )
				)
				( pin "vdrv"
					( attribute "PN" "4"
						( Origin gPackager )
					)
					( objectStatus "EU4C1.4" )
				)
				( pin "vin(0)"
					( attribute "PN" "25"
						( Origin gPackager )
					)
					( objectStatus "EU4C1.25" )
				)
				( pin "vin(1)"
					( attribute "PN" "30"
						( Origin gPackager )
					)
					( objectStatus "EU4C1.30" )
				)
				( pin "vos"
					( attribute "PN" "1"
						( Origin gPackager )
					)
					( objectStatus "EU4C1.1" )
				)
			)
			( gate "@baseboard_fab2_lib.baseboard_fab2(sch_1):page205_i62"
				( attribute "CDS_LIB" "mstr_discrete"
					( Origin gPackager )
				)
				( attribute "CDS_LOCATION" "R4C13"
					( Origin gPackager )
				)
				( attribute "CDS_SEC" "1"
					( Origin gPackager )
				)
				( attribute "LOCATION" "R4C13"
					( Origin gFrontEnd )
				)
				( attribute "MATERIAL" "EMPTY"
					( Origin gFrontEnd )
				)
				( attribute "PACK_TYPE" "0402"
					( Origin gFrontEnd )
				)
				( attribute "PART_NUMBER" "G21796-187"
					( Origin gFrontEnd )
				)
				( attribute "PHYS_PAGE" "205"
					( Origin gFrontEnd )
				)
				( attribute "ROT" "0"
					( Origin gFrontEnd )
				)
				( attribute "SEC" "1"
					( Origin gPackager )
				)
				( attribute "TOLERANCE" "1%"
					( Origin gFrontEnd )
				)
				( attribute "VALUE" "68.1K"
					( Origin gFrontEnd )
				)
				( attribute "VER" "2"
					( Origin gFrontEnd )
				)
				( attribute "WATTAGE" "1/16W"
					( Origin gFrontEnd )
				)
				( attribute "XY" "(-1125,3900)"
					( Origin gFrontEnd )
				)
				( attribute "CHIPS_PART_NAME" "RES"
					( Origin gPackager )
				)
				( attribute "CDS_PART_NAME" "RES_0402-68.1K,1%,1/16W,EMPTY,A"
					( Origin gPackager )
				)
				( objectStatus "R4C13" )
				( pin "a"
					( attribute "PN" "1"
						( Origin gPackager )
					)
					( objectStatus "R4C13.1" )
				)
				( pin "b"
					( attribute "PN" "2"
						( Origin gPackager )
					)
					( objectStatus "R4C13.2" )
				)
			)
			( gate "@baseboard_fab2_lib.baseboard_fab2(sch_1):page206_i4"
				( attribute "CDS_LIB" "mstr_discrete"
					( Origin gPackager )
				)
				( attribute "CDS_LOCATION" "R9P1"
					( Origin gPackager )
				)
				( attribute "CDS_SEC" "1"
					( Origin gPackager )
				)
				( attribute "LOCATION" "R9P1"
					( Origin gFrontEnd )
				)
				( attribute "MATERIAL" "CHIP"
					( Origin gFrontEnd )
				)
				( attribute "PACK_TYPE" "0402"
					( Origin gFrontEnd )
				)
				( attribute "PART_NUMBER" "G21796-017"
					( Origin gFrontEnd )
				)
				( attribute "PHYS_PAGE" "206"
					( Origin gFrontEnd )
				)
				( attribute "ROOM" "PVCCIN_CPU1_VR"
					( Origin gFrontEnd )
				)
				( attribute "ROT" "0"
					( Origin gFrontEnd )
				)
				( attribute "SEC" "1"
					( Origin gFrontEnd )
				)
				( attribute "SEC_TYPE" "0402"
					( Origin gFrontEnd )
				)
				( attribute "TOLERANCE" "1%"
					( Origin gFrontEnd )
				)
				( attribute "VALUE" "100.0"
					( Origin gFrontEnd )
				)
				( attribute "VER" "2"
					( Origin gFrontEnd )
				)
				( attribute "WATTAGE" "1/16W"
					( Origin gFrontEnd )
				)
				( attribute "XY" "(-1375,3750)"
					( Origin gFrontEnd )
				)
				( attribute "CHIPS_PART_NAME" "RES"
					( Origin gPackager )
				)
				( attribute "CDS_PART_NAME" "RES_0402-100.0,1%,1/16W,CHIP,GA"
					( Origin gPackager )
				)
				( objectStatus "R9P1" )
				( pin "a"
					( attribute "PN" "1"
						( Origin gPackager )
					)
					( objectStatus "R9P1.1" )
				)
				( pin "b"
					( attribute "PN" "2"
						( Origin gPackager )
					)
					( objectStatus "R9P1.2" )
				)
			)
			( gate "@baseboard_fab2_lib.baseboard_fab2(sch_1):page206_i6"
				( attribute "CDS_LIB" "mstr_discrete"
					( Origin gPackager )
				)
				( attribute "CDS_LOCATION" "R1D6"
					( Origin gPackager )
				)
				( attribute "CDS_SEC" "1"
					( Origin gPackager )
				)
				( attribute "LOCATION" "R1D6"
					( Origin gFrontEnd )
				)
				( attribute "MATERIAL" "CHIP"
					( Origin gFrontEnd )
				)
				( attribute "PACK_TYPE" "0402"
					( Origin gFrontEnd )
				)
				( attribute "PART_NUMBER" "G21796-026"
					( Origin gFrontEnd )
				)
				( attribute "PHYS_PAGE" "206"
					( Origin gFrontEnd )
				)
				( attribute "ROOM" "PVCCIN_CPU1_VR"
					( Origin gFrontEnd )
				)
				( attribute "ROT" "2"
					( Origin gFrontEnd )
				)
				( attribute "SEC" "1"
					( Origin gFrontEnd )
				)
				( attribute "SEC_TYPE" "0402"
					( Origin gFrontEnd )
				)
				( attribute "TOLERANCE" "1%"
					( Origin gFrontEnd )
				)
				( attribute "VALUE" "1.00K"
					( Origin gFrontEnd )
				)
				( attribute "VER" "2"
					( Origin gFrontEnd )
				)
				( attribute "WATTAGE" "1/16W"
					( Origin gFrontEnd )
				)
				( attribute "XY" "(-3075,4000)"
					( Origin gFrontEnd )
				)
				( attribute "CHIPS_PART_NAME" "RES"
					( Origin gPackager )
				)
				( attribute "CDS_PART_NAME" "RES_0402-1.00K,1%,1/16W,CHIP,GA"
					( Origin gPackager )
				)
				( objectStatus "R1D6" )
				( pin "a"
					( attribute "PN" "1"
						( Origin gPackager )
					)
					( objectStatus "R1D6.1" )
				)
				( pin "b"
					( attribute "PN" "2"
						( Origin gPackager )
					)
					( objectStatus "R1D6.2" )
				)
			)
			( gate "@baseboard_fab2_lib.baseboard_fab2(sch_1):page206_i7"
				( attribute "CDS_LIB" "mstr_discrete"
					( Origin gPackager )
				)
				( attribute "CDS_LOCATION" "R1D7"
					( Origin gPackager )
				)
				( attribute "CDS_SEC" "1"
					( Origin gPackager )
				)
				( attribute "LOCATION" "R1D7"
					( Origin gFrontEnd )
				)
				( attribute "MATERIAL" "CHIP"
					( Origin gFrontEnd )
				)
				( attribute "PACK_TYPE" "0402"
					( Origin gFrontEnd )
				)
				( attribute "PART_NUMBER" "G21796-311"
					( Origin gFrontEnd )
				)
				( attribute "PHYS_PAGE" "206"
					( Origin gFrontEnd )
				)
				( attribute "ROOM" "PVCCIN_CPU1_VR"
					( Origin gFrontEnd )
				)
				( attribute "ROT" "0"
					( Origin gFrontEnd )
				)
				( attribute "SEC" "1"
					( Origin gFrontEnd )
				)
				( attribute "SEC_TYPE" "0402"
					( Origin gFrontEnd )
				)
				( attribute "TOLERANCE" "1.0%"
					( Origin gFrontEnd )
				)
				( attribute "VALUE" "2.26K"
					( Origin gFrontEnd )
				)
				( attribute "VER" "2"
					( Origin gFrontEnd )
				)
				( attribute "WATTAGE" "1/16W"
					( Origin gFrontEnd )
				)
				( attribute "XY" "(-2050,4100)"
					( Origin gFrontEnd )
				)
				( attribute "CHIPS_PART_NAME" "RES"
					( Origin gPackager )
				)
				( attribute "CDS_PART_NAME" "RES_0402-2.26K,1.0%,1/16W,CHIPA"
					( Origin gPackager )
				)
				( objectStatus "R1D7" )
				( pin "a"
					( attribute "PN" "1"
						( Origin gPackager )
					)
					( objectStatus "R1D7.1" )
				)
				( pin "b"
					( attribute "PN" "2"
						( Origin gPackager )
					)
					( objectStatus "R1D7.2" )
				)
			)
			( gate "@baseboard_fab2_lib.baseboard_fab2(sch_1):page206_i27"
				( attribute "CDS_LIB" "mstr_discrete"
					( Origin gPackager )
				)
				( attribute "CDS_LOCATION" "R1C23"
					( Origin gPackager )
				)
				( attribute "CDS_SEC" "1"
					( Origin gPackager )
				)
				( attribute "LOCATION" "R1C23"
					( Origin gFrontEnd )
				)
				( attribute "MATERIAL" "CHIP"
					( Origin gFrontEnd )
				)
				( attribute "PACK_TYPE" "0402"
					( Origin gFrontEnd )
				)
				( attribute "PART_NUMBER" "G21497-005"
					( Origin gFrontEnd )
				)
				( attribute "PHYS_PAGE" "206"
					( Origin gFrontEnd )
				)
				( attribute "ROOM" "PVCCIN_CPU1_VR"
					( Origin gFrontEnd )
				)
				( attribute "ROT" "0"
					( Origin gFrontEnd )
				)
				( attribute "SEC" "1"
					( Origin gFrontEnd )
				)
				( attribute "SEC_TYPE" "0402"
					( Origin gFrontEnd )
				)
				( attribute "TOLERANCE" "5%"
					( Origin gFrontEnd )
				)
				( attribute "VALUE" "0.0"
					( Origin gFrontEnd )
				)
				( attribute "VER" "1"
					( Origin gFrontEnd )
				)
				( attribute "WATTAGE" "1/16W"
					( Origin gFrontEnd )
				)
				( attribute "XY" "(-2000,1775)"
					( Origin gFrontEnd )
				)
				( attribute "CHIPS_PART_NAME" "RES"
					( Origin gPackager )
				)
				( attribute "CDS_PART_NAME" "RES_0402-0.0,5%,1/16W,CHIP,G21A"
					( Origin gPackager )
				)
				( objectStatus "R1C23" )
				( pin "a"
					( attribute "PN" "1"
						( Origin gPackager )
					)
					( objectStatus "R1C23.1" )
				)
				( pin "b"
					( attribute "PN" "2"
						( Origin gPackager )
					)
					( objectStatus "R1C23.2" )
				)
			)
			( gate "@baseboard_fab2_lib.baseboard_fab2(sch_1):page206_i28"
				( attribute "CDS_LIB" "mstr_discrete"
					( Origin gPackager )
				)
				( attribute "CDS_LOCATION" "R1C25"
					( Origin gPackager )
				)
				( attribute "CDS_SEC" "1"
					( Origin gPackager )
				)
				( attribute "LOCATION" "R1C25"
					( Origin gFrontEnd )
				)
				( attribute "MATERIAL" "CHIP"
					( Origin gFrontEnd )
				)
				( attribute "PACK_TYPE" "0402"
					( Origin gFrontEnd )
				)
				( attribute "PART_NUMBER" "G21497-005"
					( Origin gFrontEnd )
				)
				( attribute "PHYS_PAGE" "206"
					( Origin gFrontEnd )
				)
				( attribute "ROOM" "PVCCIN_CPU1_VR"
					( Origin gFrontEnd )
				)
				( attribute "ROT" "0"
					( Origin gFrontEnd )
				)
				( attribute "SEC" "1"
					( Origin gFrontEnd )
				)
				( attribute "SEC_TYPE" "0402"
					( Origin gFrontEnd )
				)
				( attribute "TOLERANCE" "5%"
					( Origin gFrontEnd )
				)
				( attribute "VALUE" "0.0"
					( Origin gFrontEnd )
				)
				( attribute "VER" "1"
					( Origin gFrontEnd )
				)
				( attribute "WATTAGE" "1/16W"
					( Origin gFrontEnd )
				)
				( attribute "XY" "(-2000,1525)"
					( Origin gFrontEnd )
				)
				( attribute "CHIPS_PART_NAME" "RES"
					( Origin gPackager )
				)
				( attribute "CDS_PART_NAME" "RES_0402-0.0,5%,1/16W,CHIP,G21A"
					( Origin gPackager )
				)
				( objectStatus "R1C25" )
				( pin "a"
					( attribute "PN" "1"
						( Origin gPackager )
					)
					( objectStatus "R1C25.1" )
				)
				( pin "b"
					( attribute "PN" "2"
						( Origin gPackager )
					)
					( objectStatus "R1C25.2" )
				)
			)
			( gate "@baseboard_fab2_lib.baseboard_fab2(sch_1):page206_i29"
				( attribute "CDS_LIB" "dev_discrete"
					( Origin gPackager )
				)
				( attribute "CDS_LOCATION" "C1C13"
					( Origin gPackager )
				)
				( attribute "CDS_SEC" "1"
					( Origin gPackager )
				)
				( attribute "LOCATION" "C1C13"
					( Origin gFrontEnd )
				)
				( attribute "MATERIAL" "X6S"
					( Origin gFrontEnd )
				)
				( attribute "PACK_TYPE" "0402V"
					( Origin gFrontEnd )
				)
				( attribute "PART_NUMBER" "D97712-004"
					( Origin gFrontEnd )
				)
				( attribute "PHYS_PAGE" "206"
					( Origin gFrontEnd )
				)
				( attribute "ROOM" "PVCCIN_CPU1_VR"
					( Origin gFrontEnd )
				)
				( attribute "ROT" "0"
					( Origin gFrontEnd )
				)
				( attribute "SEC" "1"
					( Origin gPackager )
				)
				( attribute "TOLERANCE" "10%"
					( Origin gFrontEnd )
				)
				( attribute "VALUE" "1.0UF"
					( Origin gFrontEnd )
				)
				( attribute "VER" "1"
					( Origin gFrontEnd )
				)
				( attribute "VOLTAGE" "6.3V"
					( Units "uVoltage" "V" 1.000000)
					( Origin gFrontEnd )
				)
				( attribute "XY" "(-1575,1000)"
					( Origin gFrontEnd )
				)
				( attribute "CHIPS_PART_NAME" "CAP_A"
					( Origin gPackager )
				)
				( attribute "CDS_PART_NAME" "CAP_A_0402V-1.0UF,6.3V,10%,X6SA"
					( Origin gPackager )
				)
				( objectStatus "C1C13" )
				( pin "a"
					( attribute "PN" "1"
						( Origin gPackager )
					)
					( objectStatus "C1C13.1" )
				)
				( pin "b"
					( attribute "PN" "2"
						( Origin gPackager )
					)
					( objectStatus "C1C13.2" )
				)
			)
			( gate "@baseboard_fab2_lib.baseboard_fab2(sch_1):page206_i31"
				( attribute "CDS_LIB" "dev_discrete"
					( Origin gPackager )
				)
				( attribute "CDS_LOCATION" "C1C14"
					( Origin gPackager )
				)
				( attribute "CDS_SEC" "1"
					( Origin gPackager )
				)
				( attribute "LOCATION" "C1C14"
					( Origin gFrontEnd )
				)
				( attribute "MATERIAL" "X7R"
					( Origin gFrontEnd )
				)
				( attribute "PACK_TYPE" "0402V"
					( Origin gFrontEnd )
				)
				( attribute "PART_NUMBER" "A36096-030"
					( Origin gFrontEnd )
				)
				( attribute "PHYS_PAGE" "206"
					( Origin gFrontEnd )
				)
				( attribute "ROOM" "PVCCIN_CPU1_VR"
					( Origin gFrontEnd )
				)
				( attribute "ROT" "0"
					( Origin gFrontEnd )
				)
				( attribute "SEC" "1"
					( Origin gFrontEnd )
				)
				( attribute "SEC_TYPE" "0402V"
					( Origin gFrontEnd )
				)
				( attribute "TOLERANCE" "10%"
					( Origin gFrontEnd )
				)
				( attribute "VALUE" "0.1UF"
					( Origin gFrontEnd )
				)
				( attribute "VER" "1"
					( Origin gFrontEnd )
				)
				( attribute "VOLTAGE" "16V"
					( Units "uVoltage" "V" 1.000000)
					( Origin gFrontEnd )
				)
				( attribute "XY" "(-1975,1000)"
					( Origin gFrontEnd )
				)
				( attribute "CHIPS_PART_NAME" "CAP_A"
					( Origin gPackager )
				)
				( attribute "CDS_PART_NAME" "CAP_A_0402V-0.1UF,16V,10%,X7R,A"
					( Origin gPackager )
				)
				( objectStatus "C1C14" )
				( pin "a"
					( attribute "PN" "1"
						( Origin gPackager )
					)
					( objectStatus "C1C14.1" )
				)
				( pin "b"
					( attribute "PN" "2"
						( Origin gPackager )
					)
					( objectStatus "C1C14.2" )
				)
			)
			( gate "@baseboard_fab2_lib.baseboard_fab2(sch_1):page206_i33"
				( attribute "CDS_LIB" "mstr_discrete"
					( Origin gPackager )
				)
				( attribute "CDS_LOCATION" "R1D53"
					( Origin gPackager )
				)
				( attribute "CDS_SEC" "1"
					( Origin gPackager )
				)
				( attribute "LOCATION" "R1D53"
					( Origin gFrontEnd )
				)
				( attribute "MATERIAL" "EMPTY"
					( Origin gFrontEnd )
				)
				( attribute "PACK_TYPE" "0402"
					( Origin gFrontEnd )
				)
				( attribute "PART_NUMBER" "G21796-311"
					( Origin gFrontEnd )
				)
				( attribute "PHYS_PAGE" "206"
					( Origin gFrontEnd )
				)
				( attribute "ROOM" "PVCCIN_CPU1_VR"
					( Origin gFrontEnd )
				)
				( attribute "ROT" "0"
					( Origin gFrontEnd )
				)
				( attribute "SEC" "1"
					( Origin gFrontEnd )
				)
				( attribute "SEC_TYPE" "0402"
					( Origin gFrontEnd )
				)
				( attribute "TOLERANCE" "1.0%"
					( Origin gFrontEnd )
				)
				( attribute "VALUE" "2.26K"
					( Origin gFrontEnd )
				)
				( attribute "VER" "2"
					( Origin gFrontEnd )
				)
				( attribute "WATTAGE" "1/16W"
					( Origin gFrontEnd )
				)
				( attribute "XY" "(-2375,4125)"
					( Origin gFrontEnd )
				)
				( attribute "CHIPS_PART_NAME" "RES"
					( Origin gPackager )
				)
				( attribute "CDS_PART_NAME" "RES_0402-2.26K,1.0%,1/16W,EMPTA"
					( Origin gPackager )
				)
				( objectStatus "R1D53" )
				( pin "a"
					( attribute "PN" "1"
						( Origin gPackager )
					)
					( objectStatus "R1D53.1" )
				)
				( pin "b"
					( attribute "PN" "2"
						( Origin gPackager )
					)
					( objectStatus "R1D53.2" )
				)
			)
			( gate "@baseboard_fab2_lib.baseboard_fab2(sch_1):page206_i34"
				( attribute "CDS_LIB" "mstr_discrete"
					( Origin gPackager )
				)
				( attribute "CDS_LOCATION" "R1C18"
					( Origin gPackager )
				)
				( attribute "CDS_SEC" "1"
					( Origin gPackager )
				)
				( attribute "LOCATION" "R1C18"
					( Origin gFrontEnd )
				)
				( attribute "MATERIAL" "EMPTY"
					( Origin gFrontEnd )
				)
				( attribute "PACK_TYPE" "0402"
					( Origin gFrontEnd )
				)
				( attribute "PART_NUMBER" "G21796-311"
					( Origin gFrontEnd )
				)
				( attribute "PHYS_PAGE" "206"
					( Origin gFrontEnd )
				)
				( attribute "ROOM" "PVCCIN_CPU1_VR"
					( Origin gFrontEnd )
				)
				( attribute "ROT" "0"
					( Origin gFrontEnd )
				)
				( attribute "SEC" "1"
					( Origin gFrontEnd )
				)
				( attribute "SEC_TYPE" "0402"
					( Origin gFrontEnd )
				)
				( attribute "TOLERANCE" "1.0%"
					( Origin gFrontEnd )
				)
				( attribute "VALUE" "2.26K"
					( Origin gFrontEnd )
				)
				( attribute "VER" "2"
					( Origin gFrontEnd )
				)
				( attribute "WATTAGE" "1/16W"
					( Origin gFrontEnd )
				)
				( attribute "XY" "(-2225,3750)"
					( Origin gFrontEnd )
				)
				( attribute "CHIPS_PART_NAME" "RES"
					( Origin gPackager )
				)
				( attribute "CDS_PART_NAME" "RES_0402-2.26K,1.0%,1/16W,EMPTA"
					( Origin gPackager )
				)
				( objectStatus "R1C18" )
				( pin "a"
					( attribute "PN" "1"
						( Origin gPackager )
					)
					( objectStatus "R1C18.1" )
				)
				( pin "b"
					( attribute "PN" "2"
						( Origin gPackager )
					)
					( objectStatus "R1C18.2" )
				)
			)
			( gate "@baseboard_fab2_lib.baseboard_fab2(sch_1):page206_i35"
				( attribute "CDS_LIB" "mstr_discrete"
					( Origin gPackager )
				)
				( attribute "CDS_LOCATION" "R1C28"
					( Origin gPackager )
				)
				( attribute "CDS_SEC" "1"
					( Origin gPackager )
				)
				( attribute "LOCATION" "R1C28"
					( Origin gFrontEnd )
				)
				( attribute "MATERIAL" "CHIP"
					( Origin gFrontEnd )
				)
				( attribute "PACK_TYPE" "0402"
					( Origin gFrontEnd )
				)
				( attribute "PART_NUMBER" "G21796-026"
					( Origin gFrontEnd )
				)
				( attribute "PHYS_PAGE" "206"
					( Origin gFrontEnd )
				)
				( attribute "ROOM" "PVCCIN_CPU1_VR"
					( Origin gFrontEnd )
				)
				( attribute "ROT" "0"
					( Origin gFrontEnd )
				)
				( attribute "SEC" "1"
					( Origin gFrontEnd )
				)
				( attribute "SEC_TYPE" "0402"
					( Origin gFrontEnd )
				)
				( attribute "TOLERANCE" "1%"
					( Origin gFrontEnd )
				)
				( attribute "VALUE" "1.00K"
					( Origin gFrontEnd )
				)
				( attribute "VER" "2"
					( Origin gFrontEnd )
				)
				( attribute "WATTAGE" "1/16W"
					( Origin gFrontEnd )
				)
				( attribute "XY" "(-2725,3925)"
					( Origin gFrontEnd )
				)
				( attribute "CHIPS_PART_NAME" "RES"
					( Origin gPackager )
				)
				( attribute "CDS_PART_NAME" "RES_0402-1.00K,1%,1/16W,CHIP,GA"
					( Origin gPackager )
				)
				( objectStatus "R1C28" )
				( pin "a"
					( attribute "PN" "1"
						( Origin gPackager )
					)
					( objectStatus "R1C28.1" )
				)
				( pin "b"
					( attribute "PN" "2"
						( Origin gPackager )
					)
					( objectStatus "R1C28.2" )
				)
			)
			( gate "@baseboard_fab2_lib.baseboard_fab2(sch_1):page206_i36"
				( attribute "CDS_LIB" "mstr_discrete"
					( Origin gPackager )
				)
				( attribute "CDS_LOCATION" "R1D8"
					( Origin gPackager )
				)
				( attribute "CDS_SEC" "1"
					( Origin gPackager )
				)
				( attribute "LOCATION" "R1D8"
					( Origin gFrontEnd )
				)
				( attribute "MATERIAL" "CHIP"
					( Origin gFrontEnd )
				)
				( attribute "PACK_TYPE" "0402"
					( Origin gFrontEnd )
				)
				( attribute "PART_NUMBER" "G21796-026"
					( Origin gFrontEnd )
				)
				( attribute "PHYS_PAGE" "206"
					( Origin gFrontEnd )
				)
				( attribute "ROOM" "PVCCIN_CPU1_VR"
					( Origin gFrontEnd )
				)
				( attribute "ROT" "2"
					( Origin gFrontEnd )
				)
				( attribute "SEC" "1"
					( Origin gFrontEnd )
				)
				( attribute "SEC_TYPE" "0402"
					( Origin gFrontEnd )
				)
				( attribute "TOLERANCE" "1%"
					( Origin gFrontEnd )
				)
				( attribute "VALUE" "1.00K"
					( Origin gFrontEnd )
				)
				( attribute "VER" "2"
					( Origin gFrontEnd )
				)
				( attribute "WATTAGE" "1/16W"
					( Origin gFrontEnd )
				)
				( attribute "XY" "(-2875,3925)"
					( Origin gFrontEnd )
				)
				( attribute "CHIPS_PART_NAME" "RES"
					( Origin gPackager )
				)
				( attribute "CDS_PART_NAME" "RES_0402-1.00K,1%,1/16W,CHIP,GA"
					( Origin gPackager )
				)
				( objectStatus "R1D8" )
				( pin "a"
					( attribute "PN" "1"
						( Origin gPackager )
					)
					( objectStatus "R1D8.1" )
				)
				( pin "b"
					( attribute "PN" "2"
						( Origin gPackager )
					)
					( objectStatus "R1D8.2" )
				)
			)
			( gate "@baseboard_fab2_lib.baseboard_fab2(sch_1):page206_i37"
				( attribute "CDS_LIB" "mstr_discrete"
					( Origin gPackager )
				)
				( attribute "CDS_LOCATION" "R1D3"
					( Origin gPackager )
				)
				( attribute "CDS_SEC" "1"
					( Origin gPackager )
				)
				( attribute "LOCATION" "R1D3"
					( Origin gFrontEnd )
				)
				( attribute "MATERIAL" "CHIP"
					( Origin gFrontEnd )
				)
				( attribute "PACK_TYPE" "0402"
					( Origin gFrontEnd )
				)
				( attribute "PART_NUMBER" "G21497-005"
					( Origin gFrontEnd )
				)
				( attribute "PHYS_PAGE" "206"
					( Origin gFrontEnd )
				)
				( attribute "ROOM" "PVCCIN_CPU1_VR"
					( Origin gFrontEnd )
				)
				( attribute "ROT" "0"
					( Origin gFrontEnd )
				)
				( attribute "SEC" "1"
					( Origin gFrontEnd )
				)
				( attribute "SEC_TYPE" "0402"
					( Origin gFrontEnd )
				)
				( attribute "TOLERANCE" "5%"
					( Origin gFrontEnd )
				)
				( attribute "VALUE" "0.0"
					( Origin gFrontEnd )
				)
				( attribute "VER" "1"
					( Origin gFrontEnd )
				)
				( attribute "WATTAGE" "1/16W"
					( Origin gFrontEnd )
				)
				( attribute "XY" "(-2125,2925)"
					( Origin gFrontEnd )
				)
				( attribute "CHIPS_PART_NAME" "RES"
					( Origin gPackager )
				)
				( attribute "CDS_PART_NAME" "RES_0402-0.0,5%,1/16W,CHIP,G21A"
					( Origin gPackager )
				)
				( objectStatus "R1D3" )
				( pin "a"
					( attribute "PN" "1"
						( Origin gPackager )
					)
					( objectStatus "R1D3.1" )
				)
				( pin "b"
					( attribute "PN" "2"
						( Origin gPackager )
					)
					( objectStatus "R1D3.2" )
				)
			)
			( gate "@baseboard_fab2_lib.baseboard_fab2(sch_1):page206_i38"
				( attribute "CDS_LIB" "mstr_discrete"
					( Origin gPackager )
				)
				( attribute "CDS_LOCATION" "R1D2"
					( Origin gPackager )
				)
				( attribute "CDS_SEC" "1"
					( Origin gPackager )
				)
				( attribute "LOCATION" "R1D2"
					( Origin gFrontEnd )
				)
				( attribute "MATERIAL" "CHIP"
					( Origin gFrontEnd )
				)
				( attribute "PACK_TYPE" "0402"
					( Origin gFrontEnd )
				)
				( attribute "PART_NUMBER" "G21497-005"
					( Origin gFrontEnd )
				)
				( attribute "PHYS_PAGE" "206"
					( Origin gFrontEnd )
				)
				( attribute "ROOM" "PVCCIN_CPU1_VR"
					( Origin gFrontEnd )
				)
				( attribute "ROT" "0"
					( Origin gFrontEnd )
				)
				( attribute "SEC" "1"
					( Origin gFrontEnd )
				)
				( attribute "SEC_TYPE" "0402"
					( Origin gFrontEnd )
				)
				( attribute "TOLERANCE" "5%"
					( Origin gFrontEnd )
				)
				( attribute "VALUE" "0.0"
					( Origin gFrontEnd )
				)
				( attribute "VER" "1"
					( Origin gFrontEnd )
				)
				( attribute "WATTAGE" "1/16W"
					( Origin gFrontEnd )
				)
				( attribute "XY" "(-2500,2775)"
					( Origin gFrontEnd )
				)
				( attribute "CHIPS_PART_NAME" "RES"
					( Origin gPackager )
				)
				( attribute "CDS_PART_NAME" "RES_0402-0.0,5%,1/16W,CHIP,G21A"
					( Origin gPackager )
				)
				( objectStatus "R1D2" )
				( pin "a"
					( attribute "PN" "1"
						( Origin gPackager )
					)
					( objectStatus "R1D2.1" )
				)
				( pin "b"
					( attribute "PN" "2"
						( Origin gPackager )
					)
					( objectStatus "R1D2.2" )
				)
			)
			( gate "@baseboard_fab2_lib.baseboard_fab2(sch_1):page206_i41"
				( attribute "CDS_LIB" "dev_discrete"
					( Origin gPackager )
				)
				( attribute "CDS_LOCATION" "C1C7"
					( Origin gPackager )
				)
				( attribute "CDS_SEC" "1"
					( Origin gPackager )
				)
				( attribute "LOCATION" "C1C7"
					( Origin gFrontEnd )
				)
				( attribute "MATERIAL" "X6S"
					( Origin gFrontEnd )
				)
				( attribute "PACK_TYPE" "0402V"
					( Origin gFrontEnd )
				)
				( attribute "PART_NUMBER" "D97712-004"
					( Origin gFrontEnd )
				)
				( attribute "PHYS_PAGE" "206"
					( Origin gFrontEnd )
				)
				( attribute "ROOM" "PVCCIN_CPU1_VR"
					( Origin gFrontEnd )
				)
				( attribute "ROT" "0"
					( Origin gFrontEnd )
				)
				( attribute "SEC" "1"
					( Origin gPackager )
				)
				( attribute "TOLERANCE" "10%"
					( Origin gFrontEnd )
				)
				( attribute "VALUE" "1.0UF"
					( Origin gFrontEnd )
				)
				( attribute "VER" "1"
					( Origin gFrontEnd )
				)
				( attribute "VOLTAGE" "6.3V"
					( Units "uVoltage" "V" 1.000000)
					( Origin gFrontEnd )
				)
				( attribute "XY" "(-3650,3925)"
					( Origin gFrontEnd )
				)
				( attribute "CHIPS_PART_NAME" "CAP_A"
					( Origin gPackager )
				)
				( attribute "CDS_PART_NAME" "CAP_A_0402V-1.0UF,6.3V,10%,X6SA"
					( Origin gPackager )
				)
				( objectStatus "C1C7" )
				( pin "a"
					( attribute "PN" "1"
						( Origin gPackager )
					)
					( objectStatus "C1C7.1" )
				)
				( pin "b"
					( attribute "PN" "2"
						( Origin gPackager )
					)
					( objectStatus "C1C7.2" )
				)
			)
			( gate "@baseboard_fab2_lib.baseboard_fab2(sch_1):page206_i42"
				( attribute "CDS_LIB" "dev_discrete"
					( Origin gPackager )
				)
				( attribute "CDS_LOCATION" "C1C9"
					( Origin gPackager )
				)
				( attribute "CDS_SEC" "1"
					( Origin gPackager )
				)
				( attribute "LOCATION" "C1C9"
					( Origin gFrontEnd )
				)
				( attribute "MATERIAL" "X7R"
					( Origin gFrontEnd )
				)
				( attribute "PACK_TYPE" "0402V"
					( Origin gFrontEnd )
				)
				( attribute "PART_NUMBER" "A36096-030"
					( Origin gFrontEnd )
				)
				( attribute "PHYS_PAGE" "206"
					( Origin gFrontEnd )
				)
				( attribute "ROOM" "PVCCIN_CPU1_VR"
					( Origin gFrontEnd )
				)
				( attribute "ROT" "0"
					( Origin gFrontEnd )
				)
				( attribute "SEC" "1"
					( Origin gFrontEnd )
				)
				( attribute "SEC_TYPE" "0402V"
					( Origin gFrontEnd )
				)
				( attribute "TOLERANCE" "10%"
					( Origin gFrontEnd )
				)
				( attribute "VALUE" "0.1UF"
					( Origin gFrontEnd )
				)
				( attribute "VER" "1"
					( Origin gFrontEnd )
				)
				( attribute "VOLTAGE" "16V"
					( Units "uVoltage" "V" 1.000000)
					( Origin gFrontEnd )
				)
				( attribute "XY" "(-4050,3925)"
					( Origin gFrontEnd )
				)
				( attribute "CHIPS_PART_NAME" "CAP_A"
					( Origin gPackager )
				)
				( attribute "CDS_PART_NAME" "CAP_A_0402V-0.1UF,16V,10%,X7R,A"
					( Origin gPackager )
				)
				( objectStatus "C1C9" )
				( pin "a"
					( attribute "PN" "1"
						( Origin gPackager )
					)
					( objectStatus "C1C9.1" )
				)
				( pin "b"
					( attribute "PN" "2"
						( Origin gPackager )
					)
					( objectStatus "C1C9.2" )
				)
			)
			( gate "@baseboard_fab2_lib.baseboard_fab2(sch_1):page206_i46"
				( attribute "CDS_LIB" "mstr_discrete"
					( Origin gPackager )
				)
				( attribute "CDS_LOCATION" "R1C14"
					( Origin gPackager )
				)
				( attribute "CDS_SEC" "1"
					( Origin gPackager )
				)
				( attribute "LOCATION" "R1C14"
					( Origin gFrontEnd )
				)
				( attribute "MATERIAL" "CHIP"
					( Origin gFrontEnd )
				)
				( attribute "PACK_TYPE" "0402"
					( Origin gFrontEnd )
				)
				( attribute "PART_NUMBER" "G21497-005"
					( Origin gFrontEnd )
				)
				( attribute "PHYS_PAGE" "206"
					( Origin gFrontEnd )
				)
				( attribute "ROOM" "PVCCIN_CPU1_VR"
					( Origin gFrontEnd )
				)
				( attribute "ROT" "0"
					( Origin gFrontEnd )
				)
				( attribute "SEC" "1"
					( Origin gFrontEnd )
				)
				( attribute "SEC_TYPE" "0402"
					( Origin gFrontEnd )
				)
				( attribute "TOLERANCE" "5%"
					( Origin gFrontEnd )
				)
				( attribute "VALUE" "0.0"
					( Origin gFrontEnd )
				)
				( attribute "VER" "2"
					( Origin gFrontEnd )
				)
				( attribute "WATTAGE" "1/16W"
					( Origin gFrontEnd )
				)
				( attribute "XY" "(-4350,4275)"
					( Origin gFrontEnd )
				)
				( attribute "CHIPS_PART_NAME" "RES"
					( Origin gPackager )
				)
				( attribute "CDS_PART_NAME" "RES_0402-0.0,5%,1/16W,CHIP,G21A"
					( Origin gPackager )
				)
				( objectStatus "R1C14" )
				( pin "a"
					( attribute "PN" "1"
						( Origin gPackager )
					)
					( objectStatus "R1C14.1" )
				)
				( pin "b"
					( attribute "PN" "2"
						( Origin gPackager )
					)
					( objectStatus "R1C14.2" )
				)
			)
			( gate "@baseboard_fab2_lib.baseboard_fab2(sch_1):page206_i49"
				( attribute "CDS_LIB" "mstr_discrete"
					( Origin gPackager )
				)
				( attribute "CDS_LOCATION" "R1C13"
					( Origin gPackager )
				)
				( attribute "CDS_SEC" "1"
					( Origin gPackager )
				)
				( attribute "LOCATION" "R1C13"
					( Origin gFrontEnd )
				)
				( attribute "MATERIAL" "CHIP"
					( Origin gFrontEnd )
				)
				( attribute "PACK_TYPE" "0402"
					( Origin gFrontEnd )
				)
				( attribute "PART_NUMBER" "G21796-160"
					( Origin gFrontEnd )
				)
				( attribute "PHYS_PAGE" "206"
					( Origin gFrontEnd )
				)
				( attribute "ROOM" "PVCCIN_CPU1_VR"
					( Origin gFrontEnd )
				)
				( attribute "ROT" "0"
					( Origin gFrontEnd )
				)
				( attribute "SEC" "1"
					( Origin gFrontEnd )
				)
				( attribute "SEC_TYPE" "0402"
					( Origin gFrontEnd )
				)
				( attribute "TOLERANCE" "1%"
					( Origin gFrontEnd )
				)
				( attribute "VALUE" "100.0K"
					( Origin gFrontEnd )
				)
				( attribute "VER" "2"
					( Origin gFrontEnd )
				)
				( attribute "WATTAGE" "1/16W"
					( Origin gFrontEnd )
				)
				( attribute "XY" "(-6150,4575)"
					( Origin gFrontEnd )
				)
				( attribute "CHIPS_PART_NAME" "RES"
					( Origin gPackager )
				)
				( attribute "CDS_PART_NAME" "RES_0402-100.0K,1%,1/16W,CHIP,B"
					( Origin gPackager )
				)
				( objectStatus "R1C13" )
				( pin "a"
					( attribute "PN" "1"
						( Origin gPackager )
					)
					( objectStatus "R1C13.1" )
				)
				( pin "b"
					( attribute "PN" "2"
						( Origin gPackager )
					)
					( objectStatus "R1C13.2" )
				)
			)
			( gate "@baseboard_fab2_lib.baseboard_fab2(sch_1):page206_i53"
				( attribute "CDS_LIB" "mstr_discrete"
					( Origin gPackager )
				)
				( attribute "CDS_LOCATION" "R9P2"
					( Origin gPackager )
				)
				( attribute "CDS_SEC" "1"
					( Origin gPackager )
				)
				( attribute "LOCATION" "R9P2"
					( Origin gFrontEnd )
				)
				( attribute "MATERIAL" "CHIP"
					( Origin gFrontEnd )
				)
				( attribute "PACK_TYPE" "0402"
					( Origin gFrontEnd )
				)
				( attribute "PART_NUMBER" "G21796-047"
					( Origin gFrontEnd )
				)
				( attribute "PHYS_PAGE" "206"
					( Origin gFrontEnd )
				)
				( attribute "ROOM" "PVCCIN_CPU1_VR"
					( Origin gFrontEnd )
				)
				( attribute "ROT" "0"
					( Origin gFrontEnd )
				)
				( attribute "SEC" "1"
					( Origin gFrontEnd )
				)
				( attribute "SEC_TYPE" "0402"
					( Origin gFrontEnd )
				)
				( attribute "TOLERANCE" "1%"
					( Origin gFrontEnd )
				)
				( attribute "VALUE" "49.9"
					( Origin gFrontEnd )
				)
				( attribute "VER" "2"
					( Origin gFrontEnd )
				)
				( attribute "WATTAGE" "1/16W"
					( Origin gFrontEnd )
				)
				( attribute "XY" "(-5650,4450)"
					( Origin gFrontEnd )
				)
				( attribute "CHIPS_PART_NAME" "RES"
					( Origin gPackager )
				)
				( attribute "CDS_PART_NAME" "RES_0402-49.9,1%,1/16W,CHIP,G2A"
					( Origin gPackager )
				)
				( objectStatus "R9P2" )
				( pin "a"
					( attribute "PN" "1"
						( Origin gPackager )
					)
					( objectStatus "R9P2.1" )
				)
				( pin "b"
					( attribute "PN" "2"
						( Origin gPackager )
					)
					( objectStatus "R9P2.2" )
				)
			)
			( gate "@baseboard_fab2_lib.baseboard_fab2(sch_1):page206_i54"
				( attribute "CDS_LIB" "mstr_discrete"
					( Origin gPackager )
				)
				( attribute "CDS_LOCATION" "R1D9"
					( Origin gPackager )
				)
				( attribute "CDS_SEC" "1"
					( Origin gPackager )
				)
				( attribute "LOCATION" "R1D9"
					( Origin gFrontEnd )
				)
				( attribute "MATERIAL" "CHIP"
					( Origin gFrontEnd )
				)
				( attribute "PACK_TYPE" "0402"
					( Origin gFrontEnd )
				)
				( attribute "PART_NUMBER" "G21796-009"
					( Origin gFrontEnd )
				)
				( attribute "PHYS_PAGE" "206"
					( Origin gFrontEnd )
				)
				( attribute "ROOM" "PVCCIN_CPU1_VR"
					( Origin gFrontEnd )
				)
				( attribute "ROT" "0"
					( Origin gFrontEnd )
				)
				( attribute "SEC" "1"
					( Origin gPackager )
				)
				( attribute "TOLERANCE" "1%"
					( Origin gFrontEnd )
				)
				( attribute "VALUE" "150.0"
					( Origin gFrontEnd )
				)
				( attribute "VER" "1"
					( Origin gFrontEnd )
				)
				( attribute "WATTAGE" "1/16W"
					( Origin gFrontEnd )
				)
				( attribute "XY" "(-5375,3900)"
					( Origin gFrontEnd )
				)
				( attribute "CHIPS_PART_NAME" "RES"
					( Origin gPackager )
				)
				( attribute "CDS_PART_NAME" "RES_0402-150.0,1%,1/16W,CHIP,GA"
					( Origin gPackager )
				)
				( objectStatus "R1D9" )
				( pin "a"
					( attribute "PN" "1"
						( Origin gPackager )
					)
					( objectStatus "R1D9.1" )
				)
				( pin "b"
					( attribute "PN" "2"
						( Origin gPackager )
					)
					( objectStatus "R1D9.2" )
				)
			)
			( gate "@baseboard_fab2_lib.baseboard_fab2(sch_1):page206_i56"
				( attribute "CDS_LIB" "mstr_discrete"
					( Origin gPackager )
				)
				( attribute "CDS_LOCATION" "R1C16"
					( Origin gPackager )
				)
				( attribute "CDS_SEC" "1"
					( Origin gPackager )
				)
				( attribute "LOCATION" "R1C16"
					( Origin gFrontEnd )
				)
				( attribute "MATERIAL" "CHIP"
					( Origin gFrontEnd )
				)
				( attribute "PACK_TYPE" "0402"
					( Origin gFrontEnd )
				)
				( attribute "PART_NUMBER" "G21796-003"
					( Origin gFrontEnd )
				)
				( attribute "PHYS_PAGE" "206"
					( Origin gFrontEnd )
				)
				( attribute "ROOM" "PVCCIN_CPU1_VR"
					( Origin gFrontEnd )
				)
				( attribute "ROT" "0"
					( Origin gFrontEnd )
				)
				( attribute "SEC" "1"
					( Origin gFrontEnd )
				)
				( attribute "SEC_TYPE" "0402"
					( Origin gFrontEnd )
				)
				( attribute "TOLERANCE" "1%"
					( Origin gFrontEnd )
				)
				( attribute "VALUE" "1.5K"
					( Origin gFrontEnd )
				)
				( attribute "VER" "2"
					( Origin gFrontEnd )
				)
				( attribute "WATTAGE" "1/16W"
					( Origin gFrontEnd )
				)
				( attribute "XY" "(-6150,4225)"
					( Origin gFrontEnd )
				)
				( attribute "CHIPS_PART_NAME" "RES"
					( Origin gPackager )
				)
				( attribute "CDS_PART_NAME" "RES_0402-1.5K,1%,1/16W,CHIP,G2A"
					( Origin gPackager )
				)
				( objectStatus "R1C16" )
				( pin "a"
					( attribute "PN" "1"
						( Origin gPackager )
					)
					( objectStatus "R1C16.1" )
				)
				( pin "b"
					( attribute "PN" "2"
						( Origin gPackager )
					)
					( objectStatus "R1C16.2" )
				)
			)
			( gate "@baseboard_fab2_lib.baseboard_fab2(sch_1):page206_i68"
				( attribute "CDS_LIB" "mstr_discrete"
					( Origin gPackager )
				)
				( attribute "CDS_LOCATION" "C1C16"
					( Origin gPackager )
				)
				( attribute "CDS_SEC" "1"
					( Origin gPackager )
				)
				( attribute "LOCATION" "C1C16"
					( Origin gFrontEnd )
				)
				( attribute "MATERIAL" "X7R"
					( Origin gFrontEnd )
				)
				( attribute "NO_XNET_CONNECTION" "1"
					( Origin gFrontEnd )
				)
				( attribute "PACK_TYPE" "0402LF"
					( Origin gFrontEnd )
				)
				( attribute "PART_NUMBER" "A36096-050"
					( Origin gFrontEnd )
				)
				( attribute "PHYS_PAGE" "206"
					( Origin gFrontEnd )
				)
				( attribute "ROOM" "PVCCIN_CPU1_VR"
					( Origin gFrontEnd )
				)
				( attribute "ROT" "0"
					( Origin gFrontEnd )
				)
				( attribute "SEC" "1"
					( Origin gFrontEnd )
				)
				( attribute "SEC_TYPE" "0402LF"
					( Origin gFrontEnd )
				)
				( attribute "TOLERANCE" "10%"
					( Origin gFrontEnd )
				)
				( attribute "VALUE" "220PF"
					( Origin gFrontEnd )
				)
				( attribute "VER" "1"
					( Origin gFrontEnd )
				)
				( attribute "VOLTAGE" "50V"
					( Units "uVoltage" "V" 1.000000)
					( Origin gFrontEnd )
				)
				( attribute "XY" "(-5650,2075)"
					( Origin gFrontEnd )
				)
				( attribute "CHIPS_PART_NAME" "CAP"
					( Origin gPackager )
				)
				( attribute "CDS_PART_NAME" "CAP_0402LF-220PF,50V,10%,X7R,AA"
					( Origin gPackager )
				)
				( objectStatus "C1C16" )
				( pin "a"
					( attribute "PN" "1"
						( Origin gPackager )
					)
					( objectStatus "C1C16.1" )
				)
				( pin "b"
					( attribute "PN" "2"
						( Origin gPackager )
					)
					( objectStatus "C1C16.2" )
				)
			)
			( gate "@baseboard_fab2_lib.baseboard_fab2(sch_1):page206_i69"
				( attribute "CDS_LIB" "mstr_discrete"
					( Origin gPackager )
				)
				( attribute "CDS_LOCATION" "C1C10"
					( Origin gPackager )
				)
				( attribute "CDS_SEC" "1"
					( Origin gPackager )
				)
				( attribute "LOCATION" "C1C10"
					( Origin gFrontEnd )
				)
				( attribute "MATERIAL" "X7R"
					( Origin gFrontEnd )
				)
				( attribute "PACK_TYPE" "0402LF"
					( Origin gFrontEnd )
				)
				( attribute "PART_NUMBER" "A36096-050"
					( Origin gFrontEnd )
				)
				( attribute "PHYS_PAGE" "206"
					( Origin gFrontEnd )
				)
				( attribute "ROOM" "PVCCIN_CPU1_VR"
					( Origin gFrontEnd )
				)
				( attribute "ROT" "0"
					( Origin gFrontEnd )
				)
				( attribute "SEC" "1"
					( Origin gFrontEnd )
				)
				( attribute "SEC_TYPE" "0402LF"
					( Origin gFrontEnd )
				)
				( attribute "TOLERANCE" "10%"
					( Origin gFrontEnd )
				)
				( attribute "VALUE" "220PF"
					( Origin gFrontEnd )
				)
				( attribute "VER" "1"
					( Origin gFrontEnd )
				)
				( attribute "VOLTAGE" "50V"
					( Units "uVoltage" "V" 1.000000)
					( Origin gFrontEnd )
				)
				( attribute "XY" "(-5925,1275)"
					( Origin gFrontEnd )
				)
				( attribute "CHIPS_PART_NAME" "CAP"
					( Origin gPackager )
				)
				( attribute "CDS_PART_NAME" "CAP_0402LF-220PF,50V,10%,X7R,AA"
					( Origin gPackager )
				)
				( objectStatus "C1C10" )
				( pin "a"
					( attribute "PN" "1"
						( Origin gPackager )
					)
					( objectStatus "C1C10.1" )
				)
				( pin "b"
					( attribute "PN" "2"
						( Origin gPackager )
					)
					( objectStatus "C1C10.2" )
				)
			)
			( gate "@baseboard_fab2_lib.baseboard_fab2(sch_1):page206_i71"
				( attribute "CDS_LIB" "mstr_discrete"
					( Origin gPackager )
				)
				( attribute "CDS_LOCATION" "C1C11"
					( Origin gPackager )
				)
				( attribute "CDS_SEC" "1"
					( Origin gPackager )
				)
				( attribute "LOCATION" "C1C11"
					( Origin gFrontEnd )
				)
				( attribute "MATERIAL" "X7R"
					( Origin gFrontEnd )
				)
				( attribute "PACK_TYPE" "0402LF"
					( Origin gFrontEnd )
				)
				( attribute "PART_NUMBER" "A36096-050"
					( Origin gFrontEnd )
				)
				( attribute "PHYS_PAGE" "206"
					( Origin gFrontEnd )
				)
				( attribute "ROOM" "PVCCIN_CPU1_VR"
					( Origin gFrontEnd )
				)
				( attribute "ROT" "2"
					( Origin gFrontEnd )
				)
				( attribute "SEC" "1"
					( Origin gFrontEnd )
				)
				( attribute "SEC_TYPE" "0402LF"
					( Origin gFrontEnd )
				)
				( attribute "TOLERANCE" "10%"
					( Origin gFrontEnd )
				)
				( attribute "VALUE" "220PF"
					( Origin gFrontEnd )
				)
				( attribute "VER" "1"
					( Origin gFrontEnd )
				)
				( attribute "VOLTAGE" "50V"
					( Units "uVoltage" "V" 1.000000)
					( Origin gFrontEnd )
				)
				( attribute "XY" "(-6150,1000)"
					( Origin gFrontEnd )
				)
				( attribute "CHIPS_PART_NAME" "CAP"
					( Origin gPackager )
				)
				( attribute "CDS_PART_NAME" "CAP_0402LF-220PF,50V,10%,X7R,AA"
					( Origin gPackager )
				)
				( objectStatus "C1C11" )
				( pin "a"
					( attribute "PN" "1"
						( Origin gPackager )
					)
					( objectStatus "C1C11.1" )
				)
				( pin "b"
					( attribute "PN" "2"
						( Origin gPackager )
					)
					( objectStatus "C1C11.2" )
				)
			)
			( gate "@baseboard_fab2_lib.baseboard_fab2(sch_1):page206_i73"
				( attribute "CDS_LIB" "mstr_discrete"
					( Origin gPackager )
				)
				( attribute "CDS_LOCATION" "C1C8"
					( Origin gPackager )
				)
				( attribute "CDS_SEC" "1"
					( Origin gPackager )
				)
				( attribute "LOCATION" "C1C8"
					( Origin gFrontEnd )
				)
				( attribute "MATERIAL" "X7R"
					( Origin gFrontEnd )
				)
				( attribute "PACK_TYPE" "0402LF"
					( Origin gFrontEnd )
				)
				( attribute "PART_NUMBER" "A36096-046"
					( Origin gFrontEnd )
				)
				( attribute "PHYS_PAGE" "206"
					( Origin gFrontEnd )
				)
				( attribute "ROOM" "PVCCIN_CPU1_VR"
					( Origin gFrontEnd )
				)
				( attribute "ROT" "2"
					( Origin gFrontEnd )
				)
				( attribute "SEC" "1"
					( Origin gFrontEnd )
				)
				( attribute "SEC_TYPE" "0402LF"
					( Origin gFrontEnd )
				)
				( attribute "TOLERANCE" "10%"
					( Origin gFrontEnd )
				)
				( attribute "VALUE" "1000PF"
					( Origin gFrontEnd )
				)
				( attribute "VER" "1"
					( Origin gFrontEnd )
				)
				( attribute "VOLTAGE" "50V"
					( Units "uVoltage" "V" 1.000000)
					( Origin gFrontEnd )
				)
				( attribute "XY" "(-6425,4200)"
					( Origin gFrontEnd )
				)
				( attribute "CHIPS_PART_NAME" "CAP"
					( Origin gPackager )
				)
				( attribute "CDS_PART_NAME" "CAP_0402LF-1000PF,50V,10%,X7R,A"
					( Origin gPackager )
				)
				( objectStatus "C1C8" )
				( pin "a"
					( attribute "PN" "1"
						( Origin gPackager )
					)
					( objectStatus "C1C8.1" )
				)
				( pin "b"
					( attribute "PN" "2"
						( Origin gPackager )
					)
					( objectStatus "C1C8.2" )
				)
			)
			( gate "@baseboard_fab2_lib.baseboard_fab2(sch_1):page206_i77"
				( attribute "CDS_LIB" "mstr_discrete"
					( Origin gPackager )
				)
				( attribute "CDS_LOCATION" "R1C21"
					( Origin gPackager )
				)
				( attribute "CDS_SEC" "1"
					( Origin gPackager )
				)
				( attribute "LOCATION" "R1C21"
					( Origin gFrontEnd )
				)
				( attribute "MATERIAL" "CHIP"
					( Origin gFrontEnd )
				)
				( attribute "NO_XNET_CONNECTION" "1"
					( Origin gFrontEnd )
				)
				( attribute "PACK_TYPE" "0402"
					( Origin gFrontEnd )
				)
				( attribute "PART_NUMBER" "G21796-066"
					( Origin gFrontEnd )
				)
				( attribute "PHYS_PAGE" "206"
					( Origin gFrontEnd )
				)
				( attribute "ROOM" "PVCCIN_CPU1_VR"
					( Origin gFrontEnd )
				)
				( attribute "ROT" "0"
					( Origin gFrontEnd )
				)
				( attribute "SEC" "1"
					( Origin gFrontEnd )
				)
				( attribute "SEC_TYPE" "0402"
					( Origin gFrontEnd )
				)
				( attribute "TOLERANCE" "1%"
					( Origin gFrontEnd )
				)
				( attribute "VALUE" "10.0"
					( Origin gFrontEnd )
				)
				( attribute "VER" "1"
					( Origin gFrontEnd )
				)
				( attribute "WATTAGE" "1/16W"
					( Origin gFrontEnd )
				)
				( attribute "XY" "(-6350,2075)"
					( Origin gFrontEnd )
				)
				( attribute "CHIPS_PART_NAME" "RES"
					( Origin gPackager )
				)
				( attribute "CDS_PART_NAME" "RES_0402-10.0,1%,1/16W,CHIP,G2A"
					( Origin gPackager )
				)
				( objectStatus "R1C21" )
				( pin "a"
					( attribute "PN" "1"
						( Origin gPackager )
					)
					( objectStatus "R1C21.1" )
				)
				( pin "b"
					( attribute "PN" "2"
						( Origin gPackager )
					)
					( objectStatus "R1C21.2" )
				)
			)
			( gate "@baseboard_fab2_lib.baseboard_fab2(sch_1):page206_i78"
				( attribute "CDS_LIB" "mstr_discrete"
					( Origin gPackager )
				)
				( attribute "CDS_LOCATION" "C1D1"
					( Origin gPackager )
				)
				( attribute "CDS_SEC" "1"
					( Origin gPackager )
				)
				( attribute "LOCATION" "C1D1"
					( Origin gFrontEnd )
				)
				( attribute "MATERIAL" "X7R"
					( Origin gFrontEnd )
				)
				( attribute "NO_XNET_CONNECTION" "1"
					( Origin gFrontEnd )
				)
				( attribute "PACK_TYPE" "0402LF"
					( Origin gFrontEnd )
				)
				( attribute "PART_NUMBER" "A36096-050"
					( Origin gFrontEnd )
				)
				( attribute "PHYS_PAGE" "206"
					( Origin gFrontEnd )
				)
				( attribute "ROOM" "PVCCIN_CPU1_VR"
					( Origin gFrontEnd )
				)
				( attribute "ROT" "0"
					( Origin gFrontEnd )
				)
				( attribute "SEC" "1"
					( Origin gFrontEnd )
				)
				( attribute "SEC_TYPE" "0402LF"
					( Origin gFrontEnd )
				)
				( attribute "TOLERANCE" "10%"
					( Origin gFrontEnd )
				)
				( attribute "VALUE" "220PF"
					( Origin gFrontEnd )
				)
				( attribute "VER" "1"
					( Origin gFrontEnd )
				)
				( attribute "VOLTAGE" "50V"
					( Units "uVoltage" "V" 1.000000)
					( Origin gFrontEnd )
				)
				( attribute "XY" "(-6550,2375)"
					( Origin gFrontEnd )
				)
				( attribute "CHIPS_PART_NAME" "CAP"
					( Origin gPackager )
				)
				( attribute "CDS_PART_NAME" "CAP_0402LF-220PF,50V,10%,X7R,AA"
					( Origin gPackager )
				)
				( objectStatus "C1D1" )
				( pin "a"
					( attribute "PN" "1"
						( Origin gPackager )
					)
					( objectStatus "C1D1.1" )
				)
				( pin "b"
					( attribute "PN" "2"
						( Origin gPackager )
					)
					( objectStatus "C1D1.2" )
				)
			)
			( gate "@baseboard_fab2_lib.baseboard_fab2(sch_1):page206_i79"
				( attribute "CDS_LIB" "mstr_discrete"
					( Origin gPackager )
				)
				( attribute "CDS_LOCATION" "R1D4"
					( Origin gPackager )
				)
				( attribute "CDS_SEC" "1"
					( Origin gPackager )
				)
				( attribute "LOCATION" "R1D4"
					( Origin gFrontEnd )
				)
				( attribute "MATERIAL" "CHIP"
					( Origin gFrontEnd )
				)
				( attribute "NO_XNET_CONNECTION" "1"
					( Origin gFrontEnd )
				)
				( attribute "PACK_TYPE" "0402"
					( Origin gFrontEnd )
				)
				( attribute "PART_NUMBER" "G21796-066"
					( Origin gFrontEnd )
				)
				( attribute "PHYS_PAGE" "206"
					( Origin gFrontEnd )
				)
				( attribute "ROOM" "PVCCIN_CPU1_VR"
					( Origin gFrontEnd )
				)
				( attribute "ROT" "0"
					( Origin gFrontEnd )
				)
				( attribute "SEC" "1"
					( Origin gFrontEnd )
				)
				( attribute "SEC_TYPE" "0402"
					( Origin gFrontEnd )
				)
				( attribute "TOLERANCE" "1%"
					( Origin gFrontEnd )
				)
				( attribute "VALUE" "10.0"
					( Origin gFrontEnd )
				)
				( attribute "VER" "1"
					( Origin gFrontEnd )
				)
				( attribute "WATTAGE" "1/16W"
					( Origin gFrontEnd )
				)
				( attribute "XY" "(-6775,2575)"
					( Origin gFrontEnd )
				)
				( attribute "CHIPS_PART_NAME" "RES"
					( Origin gPackager )
				)
				( attribute "CDS_PART_NAME" "RES_0402-10.0,1%,1/16W,CHIP,G2A"
					( Origin gPackager )
				)
				( objectStatus "R1D4" )
				( pin "a"
					( attribute "PN" "1"
						( Origin gPackager )
					)
					( objectStatus "R1D4.1" )
				)
				( pin "b"
					( attribute "PN" "2"
						( Origin gPackager )
					)
					( objectStatus "R1D4.2" )
				)
			)
			( gate "@baseboard_fab2_lib.baseboard_fab2(sch_1):page206_i111"
				( attribute "CDS_LIB" "mstr_discrete"
					( Origin gPackager )
				)
				( attribute "CDS_LOCATION" "R9N7"
					( Origin gPackager )
				)
				( attribute "CDS_SEC" "1"
					( Origin gPackager )
				)
				( attribute "LOCATION" "R9N7"
					( Origin gFrontEnd )
				)
				( attribute "MATERIAL" "CHIP"
					( Origin gFrontEnd )
				)
				( attribute "PACK_TYPE" "0402"
					( Origin gFrontEnd )
				)
				( attribute "PART_NUMBER" "G21796-043"
					( Origin gFrontEnd )
				)
				( attribute "PHYS_PAGE" "206"
					( Origin gFrontEnd )
				)
				( attribute "ROOM" "PVCCIN_CPU1_VR"
					( Origin gFrontEnd )
				)
				( attribute "ROT" "0"
					( Origin gFrontEnd )
				)
				( attribute "SEC" "1"
					( Origin gFrontEnd )
				)
				( attribute "SEC_TYPE" "0402"
					( Origin gFrontEnd )
				)
				( attribute "TOLERANCE" "1%"
					( Origin gFrontEnd )
				)
				( attribute "VALUE" "3.16K"
					( Origin gFrontEnd )
				)
				( attribute "VER" "2"
					( Origin gFrontEnd )
				)
				( attribute "WATTAGE" "1/16W"
					( Origin gFrontEnd )
				)
				( attribute "XY" "(-4500,925)"
					( Origin gFrontEnd )
				)
				( attribute "CHIPS_PART_NAME" "RES"
					( Origin gPackager )
				)
				( attribute "CDS_PART_NAME" "RES_0402-3.16K,1%,1/16W,CHIP,GA"
					( Origin gPackager )
				)
				( objectStatus "R9N7" )
				( pin "a"
					( attribute "PN" "1"
						( Origin gPackager )
					)
					( objectStatus "R9N7.1" )
				)
				( pin "b"
					( attribute "PN" "2"
						( Origin gPackager )
					)
					( objectStatus "R9N7.2" )
				)
			)
			( gate "@baseboard_fab2_lib.baseboard_fab2(sch_1):page206_i112"
				( attribute "CDS_LIB" "mstr_discrete"
					( Origin gPackager )
				)
				( attribute "CDS_LOCATION" "R9N8"
					( Origin gPackager )
				)
				( attribute "CDS_SEC" "1"
					( Origin gPackager )
				)
				( attribute "LOCATION" "R9N8"
					( Origin gFrontEnd )
				)
				( attribute "MATERIAL" "CHIP"
					( Origin gFrontEnd )
				)
				( attribute "PACK_TYPE" "0402"
					( Origin gFrontEnd )
				)
				( attribute "PART_NUMBER" "G21796-082"
					( Origin gFrontEnd )
				)
				( attribute "PHYS_PAGE" "206"
					( Origin gFrontEnd )
				)
				( attribute "ROOM" "PVCCIN_CPU1_VR"
					( Origin gFrontEnd )
				)
				( attribute "ROT" "0"
					( Origin gFrontEnd )
				)
				( attribute "SEC" "1"
					( Origin gFrontEnd )
				)
				( attribute "SEC_TYPE" "0402"
					( Origin gFrontEnd )
				)
				( attribute "TOLERANCE" "1%"
					( Origin gFrontEnd )
				)
				( attribute "VALUE" "4.02K"
					( Origin gFrontEnd )
				)
				( attribute "VER" "2"
					( Origin gFrontEnd )
				)
				( attribute "WATTAGE" "1/16W"
					( Origin gFrontEnd )
				)
				( attribute "XY" "(-4825,925)"
					( Origin gFrontEnd )
				)
				( attribute "CHIPS_PART_NAME" "RES"
					( Origin gPackager )
				)
				( attribute "CDS_PART_NAME" "RES_0402-4.02K,1%,1/16W,CHIP,GA"
					( Origin gPackager )
				)
				( objectStatus "R9N8" )
				( pin "a"
					( attribute "PN" "1"
						( Origin gPackager )
					)
					( objectStatus "R9N8.1" )
				)
				( pin "b"
					( attribute "PN" "2"
						( Origin gPackager )
					)
					( objectStatus "R9N8.2" )
				)
			)
			( gate "@baseboard_fab2_lib.baseboard_fab2(sch_1):page206_i113"
				( attribute "CDS_LIB" "mstr_discrete"
					( Origin gPackager )
				)
				( attribute "CDS_LOCATION" "R1C30"
					( Origin gPackager )
				)
				( attribute "CDS_SEC" "1"
					( Origin gPackager )
				)
				( attribute "LOCATION" "R1C30"
					( Origin gFrontEnd )
				)
				( attribute "MATERIAL" "CHIP"
					( Origin gFrontEnd )
				)
				( attribute "PACK_TYPE" "0402"
					( Origin gFrontEnd )
				)
				( attribute "PART_NUMBER" "G21796-250"
					( Origin gFrontEnd )
				)
				( attribute "PHYS_PAGE" "206"
					( Origin gFrontEnd )
				)
				( attribute "ROOM" "PVCCIN_CPU1_VR"
					( Origin gFrontEnd )
				)
				( attribute "ROT" "0"
					( Origin gFrontEnd )
				)
				( attribute "SEC" "1"
					( Origin gFrontEnd )
				)
				( attribute "SEC_TYPE" "0402"
					( Origin gFrontEnd )
				)
				( attribute "TOLERANCE" "1.0%"
					( Origin gFrontEnd )
				)
				( attribute "VALUE" "22.1"
					( Origin gFrontEnd )
				)
				( attribute "VER" "1"
					( Origin gFrontEnd )
				)
				( attribute "WATTAGE" "1/16W"
					( Origin gFrontEnd )
				)
				( attribute "XY" "(-1200,3375)"
					( Origin gFrontEnd )
				)
				( attribute "CHIPS_PART_NAME" "RES"
					( Origin gPackager )
				)
				( attribute "CDS_PART_NAME" "RES_0402-22.1,1.0%,1/16W,CHIP,A"
					( Origin gPackager )
				)
				( objectStatus "R1C30" )
				( pin "a"
					( attribute "PN" "1"
						( Origin gPackager )
					)
					( objectStatus "R1C30.1" )
				)
				( pin "b"
					( attribute "PN" "2"
						( Origin gPackager )
					)
					( objectStatus "R1C30.2" )
				)
			)
			( gate "@baseboard_fab2_lib.baseboard_fab2(sch_1):page206_i114"
				( attribute "CDS_LIB" "mstr_discrete"
					( Origin gPackager )
				)
				( attribute "CDS_LOCATION" "C1C23"
					( Origin gPackager )
				)
				( attribute "CDS_SEC" "1"
					( Origin gPackager )
				)
				( attribute "LOCATION" "C1C23"
					( Origin gFrontEnd )
				)
				( attribute "MATERIAL" "X7R"
					( Origin gFrontEnd )
				)
				( attribute "PACK_TYPE" "0402LF"
					( Origin gFrontEnd )
				)
				( attribute "PART_NUMBER" "A36096-046"
					( Origin gFrontEnd )
				)
				( attribute "PHYS_PAGE" "206"
					( Origin gFrontEnd )
				)
				( attribute "ROOM" "PVCCIN_CPU1_VR"
					( Origin gFrontEnd )
				)
				( attribute "ROT" "0"
					( Origin gFrontEnd )
				)
				( attribute "SEC" "1"
					( Origin gFrontEnd )
				)
				( attribute "SEC_TYPE" "0402LF"
					( Origin gFrontEnd )
				)
				( attribute "TOLERANCE" "10%"
					( Origin gFrontEnd )
				)
				( attribute "VALUE" "1000PF"
					( Origin gFrontEnd )
				)
				( attribute "VER" "1"
					( Origin gFrontEnd )
				)
				( attribute "VOLTAGE" "50V"
					( Units "uVoltage" "V" 1.000000)
					( Origin gFrontEnd )
				)
				( attribute "XY" "(-1450,2150)"
					( Origin gFrontEnd )
				)
				( attribute "CHIPS_PART_NAME" "CAP"
					( Origin gPackager )
				)
				( attribute "CDS_PART_NAME" "CAP_0402LF-1000PF,50V,10%,X7R,A"
					( Origin gPackager )
				)
				( objectStatus "C1C23" )
				( pin "a"
					( attribute "PN" "1"
						( Origin gPackager )
					)
					( objectStatus "C1C23.1" )
				)
				( pin "b"
					( attribute "PN" "2"
						( Origin gPackager )
					)
					( objectStatus "C1C23.2" )
				)
			)
			( gate "@baseboard_fab2_lib.baseboard_fab2(sch_1):page206_i116"
				( attribute "CDS_LIB" "mstr_discrete"
					( Origin gPackager )
				)
				( attribute "CDS_LOCATION" "R1D1"
					( Origin gPackager )
				)
				( attribute "CDS_SEC" "1"
					( Origin gPackager )
				)
				( attribute "LOCATION" "R1D1"
					( Origin gFrontEnd )
				)
				( attribute "MATERIAL" "CHIP"
					( Origin gFrontEnd )
				)
				( attribute "PACK_TYPE" "0402"
					( Origin gFrontEnd )
				)
				( attribute "PART_NUMBER" "G21796-074"
					( Origin gFrontEnd )
				)
				( attribute "PHYS_PAGE" "206"
					( Origin gFrontEnd )
				)
				( attribute "ROT" "0"
					( Origin gFrontEnd )
				)
				( attribute "SEC" "1"
					( Origin gFrontEnd )
				)
				( attribute "SEC_TYPE" "0402"
					( Origin gFrontEnd )
				)
				( attribute "TOLERANCE" "1%"
					( Origin gFrontEnd )
				)
				( attribute "VALUE" "33.2"
					( Origin gFrontEnd )
				)
				( attribute "VER" "1"
					( Origin gFrontEnd )
				)
				( attribute "WATTAGE" "1/16W"
					( Origin gFrontEnd )
				)
				( attribute "XY" "(-2175,2725)"
					( Origin gFrontEnd )
				)
				( attribute "CHIPS_PART_NAME" "RES"
					( Origin gPackager )
				)
				( attribute "CDS_PART_NAME" "RES_0402-33.2,1%,1/16W,CHIP,G2A"
					( Origin gPackager )
				)
				( objectStatus "R1D1" )
				( pin "a"
					( attribute "PN" "1"
						( Origin gPackager )
					)
					( objectStatus "R1D1.1" )
				)
				( pin "b"
					( attribute "PN" "2"
						( Origin gPackager )
					)
					( objectStatus "R1D1.2" )
				)
			)
			( gate "@baseboard_fab2_lib.baseboard_fab2(sch_1):page206_i117"
				( attribute "CDS_LIB" "mstr_discrete"
					( Origin gPackager )
				)
				( attribute "CDS_LOCATION" "R9P3"
					( Origin gPackager )
				)
				( attribute "CDS_SEC" "1"
					( Origin gPackager )
				)
				( attribute "LOCATION" "R9P3"
					( Origin gFrontEnd )
				)
				( attribute "MATERIAL" "CHIP"
					( Origin gFrontEnd )
				)
				( attribute "PACK_TYPE" "0402"
					( Origin gFrontEnd )
				)
				( attribute "PART_NUMBER" "G21796-074"
					( Origin gFrontEnd )
				)
				( attribute "PHYS_PAGE" "206"
					( Origin gFrontEnd )
				)
				( attribute "ROT" "0"
					( Origin gFrontEnd )
				)
				( attribute "SEC" "1"
					( Origin gFrontEnd )
				)
				( attribute "SEC_TYPE" "0402"
					( Origin gFrontEnd )
				)
				( attribute "TOLERANCE" "1%"
					( Origin gFrontEnd )
				)
				( attribute "VALUE" "33.2"
					( Origin gFrontEnd )
				)
				( attribute "VER" "1"
					( Origin gFrontEnd )
				)
				( attribute "WATTAGE" "1/16W"
					( Origin gFrontEnd )
				)
				( attribute "XY" "(-2425,3025)"
					( Origin gFrontEnd )
				)
				( attribute "CHIPS_PART_NAME" "RES"
					( Origin gPackager )
				)
				( attribute "CDS_PART_NAME" "RES_0402-33.2,1%,1/16W,CHIP,G2A"
					( Origin gPackager )
				)
				( objectStatus "R9P3" )
				( pin "a"
					( attribute "PN" "1"
						( Origin gPackager )
					)
					( objectStatus "R9P3.1" )
				)
				( pin "b"
					( attribute "PN" "2"
						( Origin gPackager )
					)
					( objectStatus "R9P3.2" )
				)
			)
			( gate "@baseboard_fab2_lib.baseboard_fab2(sch_1):page206_i119"
				( attribute "CDS_LIB" "mstr_discrete"
					( Origin gPackager )
				)
				( attribute "CDS_LOCATION" "R9N16"
					( Origin gPackager )
				)
				( attribute "CDS_SEC" "1"
					( Origin gPackager )
				)
				( attribute "LOCATION" "R9N16"
					( Origin gFrontEnd )
				)
				( attribute "MATERIAL" "CHIP"
					( Origin gFrontEnd )
				)
				( attribute "PACK_TYPE" "0402"
					( Origin gFrontEnd )
				)
				( attribute "PART_NUMBER" "G21497-005"
					( Origin gFrontEnd )
				)
				( attribute "PHYS_PAGE" "206"
					( Origin gFrontEnd )
				)
				( attribute "ROOM" "PVCCIN_CPU0_VR"
					( Origin gFrontEnd )
				)
				( attribute "ROT" "0"
					( Origin gFrontEnd )
				)
				( attribute "SEC" "1"
					( Origin gFrontEnd )
				)
				( attribute "SEC_TYPE" "0402"
					( Origin gFrontEnd )
				)
				( attribute "TOLERANCE" "5%"
					( Origin gFrontEnd )
				)
				( attribute "VALUE" "0.0"
					( Origin gFrontEnd )
				)
				( attribute "VER" "1"
					( Origin gFrontEnd )
				)
				( attribute "WATTAGE" "1/16W"
					( Origin gFrontEnd )
				)
				( attribute "XY" "(-5200,2275)"
					( Origin gFrontEnd )
				)
				( attribute "CHIPS_PART_NAME" "RES"
					( Origin gPackager )
				)
				( attribute "CDS_PART_NAME" "RES_0402-0.0,5%,1/16W,CHIP,G21A"
					( Origin gPackager )
				)
				( objectStatus "R9N16" )
				( pin "a"
					( attribute "PN" "1"
						( Origin gPackager )
					)
					( objectStatus "R9N16.1" )
				)
				( pin "b"
					( attribute "PN" "2"
						( Origin gPackager )
					)
					( objectStatus "R9N16.2" )
				)
			)
			( gate "@baseboard_fab2_lib.baseboard_fab2(sch_1):page206_i120"
				( attribute "BOM_COST" "SM_CONTROLLER"
					( Origin gFrontEnd )
				)
				( attribute "CDS_LIB" "mstr_discrete"
					( Origin gPackager )
				)
				( attribute "CDS_LOCATION" "R9N14"
					( Origin gPackager )
				)
				( attribute "CDS_SEC" "1"
					( Origin gPackager )
				)
				( attribute "LOCATION" "R9N14"
					( Origin gFrontEnd )
				)
				( attribute "MATERIAL" "CHIP"
					( Origin gFrontEnd )
				)
				( attribute "PACK_TYPE" "0402"
					( Origin gFrontEnd )
				)
				( attribute "PART_NUMBER" "G21796-026"
					( Origin gFrontEnd )
				)
				( attribute "PHYS_PAGE" "206"
					( Origin gFrontEnd )
				)
				( attribute "ROOM" "BMC"
					( Origin gFrontEnd )
				)
				( attribute "ROT" "0"
					( Origin gFrontEnd )
				)
				( attribute "SEC" "1"
					( Origin gFrontEnd )
				)
				( attribute "SEC_TYPE" "0402"
					( Origin gFrontEnd )
				)
				( attribute "TOLERANCE" "1%"
					( Origin gFrontEnd )
				)
				( attribute "VALUE" "1.00K"
					( Origin gFrontEnd )
				)
				( attribute "VER" "2"
					( Origin gFrontEnd )
				)
				( attribute "WATTAGE" "1/16W"
					( Origin gFrontEnd )
				)
				( attribute "XY" "(-4650,4400)"
					( Origin gFrontEnd )
				)
				( attribute "CHIPS_PART_NAME" "RES"
					( Origin gPackager )
				)
				( attribute "CDS_PART_NAME" "RES_0402-1.00K,1%,1/16W,CHIP,GA"
					( Origin gPackager )
				)
				( objectStatus "R9N14" )
				( pin "a"
					( attribute "PN" "1"
						( Origin gPackager )
					)
					( objectStatus "R9N14.1" )
				)
				( pin "b"
					( attribute "PN" "2"
						( Origin gPackager )
					)
					( objectStatus "R9N14.2" )
				)
			)
			( gate "@baseboard_fab2_lib.baseboard_fab2(sch_1):page206_i122"
				( attribute "CDS_LIB" "mstr_discrete"
					( Origin gPackager )
				)
				( attribute "CDS_LOCATION" "R9N15"
					( Origin gPackager )
				)
				( attribute "CDS_SEC" "1"
					( Origin gPackager )
				)
				( attribute "LOCATION" "R9N15"
					( Origin gFrontEnd )
				)
				( attribute "MATERIAL" "CHIP"
					( Origin gFrontEnd )
				)
				( attribute "PACK_TYPE" "0402"
					( Origin gFrontEnd )
				)
				( attribute "PART_NUMBER" "G21497-005"
					( Origin gFrontEnd )
				)
				( attribute "PHYS_PAGE" "206"
					( Origin gFrontEnd )
				)
				( attribute "ROOM" "PVCCIN_CPU0_VR"
					( Origin gFrontEnd )
				)
				( attribute "ROT" "0"
					( Origin gFrontEnd )
				)
				( attribute "SEC" "1"
					( Origin gFrontEnd )
				)
				( attribute "SEC_TYPE" "0402"
					( Origin gFrontEnd )
				)
				( attribute "TOLERANCE" "5%"
					( Origin gFrontEnd )
				)
				( attribute "VALUE" "0.0"
					( Origin gFrontEnd )
				)
				( attribute "VER" "2"
					( Origin gFrontEnd )
				)
				( attribute "WATTAGE" "1/16W"
					( Origin gFrontEnd )
				)
				( attribute "XY" "(-6950,3525)"
					( Origin gFrontEnd )
				)
				( attribute "CHIPS_PART_NAME" "RES"
					( Origin gPackager )
				)
				( attribute "CDS_PART_NAME" "RES_0402-0.0,5%,1/16W,CHIP,G21A"
					( Origin gPackager )
				)
				( objectStatus "R9N15" )
				( pin "a"
					( attribute "PN" "1"
						( Origin gPackager )
					)
					( objectStatus "R9N15.1" )
				)
				( pin "b"
					( attribute "PN" "2"
						( Origin gPackager )
					)
					( objectStatus "R9N15.2" )
				)
			)
			( gate "@baseboard_fab2_lib.baseboard_fab2(sch_1):page206_i123"
				( attribute "CDS_LIB" "mstr_discrete"
					( Origin gPackager )
				)
				( attribute "CDS_LOCATION" "R9N17"
					( Origin gPackager )
				)
				( attribute "CDS_SEC" "1"
					( Origin gPackager )
				)
				( attribute "LOCATION" "R9N17"
					( Origin gFrontEnd )
				)
				( attribute "MATERIAL" "CHIP"
					( Origin gFrontEnd )
				)
				( attribute "PACK_TYPE" "0402"
					( Origin gFrontEnd )
				)
				( attribute "PART_NUMBER" "G21497-005"
					( Origin gFrontEnd )
				)
				( attribute "PHYS_PAGE" "206"
					( Origin gFrontEnd )
				)
				( attribute "ROOM" "PVCCIN_CPU0_VR"
					( Origin gFrontEnd )
				)
				( attribute "ROT" "0"
					( Origin gFrontEnd )
				)
				( attribute "SEC" "1"
					( Origin gFrontEnd )
				)
				( attribute "SEC_TYPE" "0402"
					( Origin gFrontEnd )
				)
				( attribute "TOLERANCE" "5%"
					( Origin gFrontEnd )
				)
				( attribute "VALUE" "0.0"
					( Origin gFrontEnd )
				)
				( attribute "VER" "2"
					( Origin gFrontEnd )
				)
				( attribute "WATTAGE" "1/16W"
					( Origin gFrontEnd )
				)
				( attribute "XY" "(-6550,3525)"
					( Origin gFrontEnd )
				)
				( attribute "CHIPS_PART_NAME" "RES"
					( Origin gPackager )
				)
				( attribute "CDS_PART_NAME" "RES_0402-0.0,5%,1/16W,CHIP,G21A"
					( Origin gPackager )
				)
				( objectStatus "R9N17" )
				( pin "a"
					( attribute "PN" "1"
						( Origin gPackager )
					)
					( objectStatus "R9N17.1" )
				)
				( pin "b"
					( attribute "PN" "2"
						( Origin gPackager )
					)
					( objectStatus "R9N17.2" )
				)
			)
			( gate "@baseboard_fab2_lib.baseboard_fab2(sch_1):page206_i124"
				( attribute "CDS_LIB" "mstr_discrete"
					( Origin gPackager )
				)
				( attribute "CDS_LOCATION" "R9N12"
					( Origin gPackager )
				)
				( attribute "CDS_SEC" "1"
					( Origin gPackager )
				)
				( attribute "LOCATION" "R9N12"
					( Origin gFrontEnd )
				)
				( attribute "MATERIAL" "CHIP"
					( Origin gFrontEnd )
				)
				( attribute "PACK_TYPE" "0402"
					( Origin gFrontEnd )
				)
				( attribute "PART_NUMBER" "G21497-005"
					( Origin gFrontEnd )
				)
				( attribute "PHYS_PAGE" "206"
					( Origin gFrontEnd )
				)
				( attribute "ROOM" "PVCCIN_CPU0_VR"
					( Origin gFrontEnd )
				)
				( attribute "ROT" "0"
					( Origin gFrontEnd )
				)
				( attribute "SEC" "1"
					( Origin gFrontEnd )
				)
				( attribute "SEC_TYPE" "0402"
					( Origin gFrontEnd )
				)
				( attribute "TOLERANCE" "5%"
					( Origin gFrontEnd )
				)
				( attribute "VALUE" "0.0"
					( Origin gFrontEnd )
				)
				( attribute "VER" "2"
					( Origin gFrontEnd )
				)
				( attribute "WATTAGE" "1/16W"
					( Origin gFrontEnd )
				)
				( attribute "XY" "(-6150,3550)"
					( Origin gFrontEnd )
				)
				( attribute "CHIPS_PART_NAME" "RES"
					( Origin gPackager )
				)
				( attribute "CDS_PART_NAME" "RES_0402-0.0,5%,1/16W,CHIP,G21A"
					( Origin gPackager )
				)
				( objectStatus "R9N12" )
				( pin "a"
					( attribute "PN" "1"
						( Origin gPackager )
					)
					( objectStatus "R9N12.1" )
				)
				( pin "b"
					( attribute "PN" "2"
						( Origin gPackager )
					)
					( objectStatus "R9N12.2" )
				)
			)
			( gate "@baseboard_fab2_lib.baseboard_fab2(sch_1):page206_i125"
				( attribute "CDS_LIB" "mstr_discrete"
					( Origin gPackager )
				)
				( attribute "CDS_LOCATION" "R9N10"
					( Origin gPackager )
				)
				( attribute "CDS_SEC" "1"
					( Origin gPackager )
				)
				( attribute "LOCATION" "R9N10"
					( Origin gFrontEnd )
				)
				( attribute "MATERIAL" "CHIP"
					( Origin gFrontEnd )
				)
				( attribute "PACK_TYPE" "0402"
					( Origin gFrontEnd )
				)
				( attribute "PART_NUMBER" "G21497-005"
					( Origin gFrontEnd )
				)
				( attribute "PHYS_PAGE" "206"
					( Origin gFrontEnd )
				)
				( attribute "ROOM" "PVCCIN_CPU0_VR"
					( Origin gFrontEnd )
				)
				( attribute "ROT" "0"
					( Origin gFrontEnd )
				)
				( attribute "SEC" "1"
					( Origin gFrontEnd )
				)
				( attribute "SEC_TYPE" "0402"
					( Origin gFrontEnd )
				)
				( attribute "TOLERANCE" "5%"
					( Origin gFrontEnd )
				)
				( attribute "VALUE" "0.0"
					( Origin gFrontEnd )
				)
				( attribute "VER" "2"
					( Origin gFrontEnd )
				)
				( attribute "WATTAGE" "1/16W"
					( Origin gFrontEnd )
				)
				( attribute "XY" "(-5725,3550)"
					( Origin gFrontEnd )
				)
				( attribute "CHIPS_PART_NAME" "RES"
					( Origin gPackager )
				)
				( attribute "CDS_PART_NAME" "RES_0402-0.0,5%,1/16W,CHIP,G21A"
					( Origin gPackager )
				)
				( objectStatus "R9N10" )
				( pin "a"
					( attribute "PN" "1"
						( Origin gPackager )
					)
					( objectStatus "R9N10.1" )
				)
				( pin "b"
					( attribute "PN" "2"
						( Origin gPackager )
					)
					( objectStatus "R9N10.2" )
				)
			)
			( gate "@baseboard_fab2_lib.baseboard_fab2(sch_1):page206_i126"
				( attribute "CDS_LIB" "mstr_discrete"
					( Origin gPackager )
				)
				( attribute "CDS_LOCATION" "R9N9"
					( Origin gPackager )
				)
				( attribute "CDS_SEC" "1"
					( Origin gPackager )
				)
				( attribute "LOCATION" "R9N9"
					( Origin gFrontEnd )
				)
				( attribute "MATERIAL" "CHIP"
					( Origin gFrontEnd )
				)
				( attribute "PACK_TYPE" "0402"
					( Origin gFrontEnd )
				)
				( attribute "PART_NUMBER" "G21497-005"
					( Origin gFrontEnd )
				)
				( attribute "PHYS_PAGE" "206"
					( Origin gFrontEnd )
				)
				( attribute "ROOM" "PVCCIN_CPU0_VR"
					( Origin gFrontEnd )
				)
				( attribute "ROT" "0"
					( Origin gFrontEnd )
				)
				( attribute "SEC" "1"
					( Origin gFrontEnd )
				)
				( attribute "SEC_TYPE" "0402"
					( Origin gFrontEnd )
				)
				( attribute "TOLERANCE" "5%"
					( Origin gFrontEnd )
				)
				( attribute "VALUE" "0.0"
					( Origin gFrontEnd )
				)
				( attribute "VER" "2"
					( Origin gFrontEnd )
				)
				( attribute "WATTAGE" "1/16W"
					( Origin gFrontEnd )
				)
				( attribute "XY" "(-5275,3550)"
					( Origin gFrontEnd )
				)
				( attribute "CHIPS_PART_NAME" "RES"
					( Origin gPackager )
				)
				( attribute "CDS_PART_NAME" "RES_0402-0.0,5%,1/16W,CHIP,G21A"
					( Origin gPackager )
				)
				( objectStatus "R9N9" )
				( pin "a"
					( attribute "PN" "1"
						( Origin gPackager )
					)
					( objectStatus "R9N9.1" )
				)
				( pin "b"
					( attribute "PN" "2"
						( Origin gPackager )
					)
					( objectStatus "R9N9.2" )
				)
			)
			( gate "@baseboard_fab2_lib.baseboard_fab2(sch_1):page206_i128"
				( attribute "CDS_LIB" "mstr_discrete"
					( Origin gPackager )
				)
				( attribute "CDS_LOCATION" "R9N5"
					( Origin gPackager )
				)
				( attribute "CDS_SEC" "1"
					( Origin gPackager )
				)
				( attribute "LOCATION" "R9N5"
					( Origin gFrontEnd )
				)
				( attribute "MATERIAL" "CHIP"
					( Origin gFrontEnd )
				)
				( attribute "PACK_TYPE" "0402"
					( Origin gFrontEnd )
				)
				( attribute "PART_NUMBER" "G21497-005"
					( Origin gFrontEnd )
				)
				( attribute "PHYS_PAGE" "206"
					( Origin gFrontEnd )
				)
				( attribute "ROOM" "PVCCIN_CPU0_VR"
					( Origin gFrontEnd )
				)
				( attribute "ROT" "0"
					( Origin gFrontEnd )
				)
				( attribute "SEC" "1"
					( Origin gFrontEnd )
				)
				( attribute "SEC_TYPE" "0402"
					( Origin gFrontEnd )
				)
				( attribute "TOLERANCE" "5%"
					( Origin gFrontEnd )
				)
				( attribute "VALUE" "0.0"
					( Origin gFrontEnd )
				)
				( attribute "VER" "1"
					( Origin gFrontEnd )
				)
				( attribute "WATTAGE" "1/16W"
					( Origin gFrontEnd )
				)
				( attribute "XY" "(-6875,1350)"
					( Origin gFrontEnd )
				)
				( attribute "CHIPS_PART_NAME" "RES"
					( Origin gPackager )
				)
				( attribute "CDS_PART_NAME" "RES_0402-0.0,5%,1/16W,CHIP,G21A"
					( Origin gPackager )
				)
				( objectStatus "R9N5" )
				( pin "a"
					( attribute "PN" "1"
						( Origin gPackager )
					)
					( objectStatus "R9N5.1" )
				)
				( pin "b"
					( attribute "PN" "2"
						( Origin gPackager )
					)
					( objectStatus "R9N5.2" )
				)
			)
			( gate "@baseboard_fab2_lib.baseboard_fab2(sch_1):page206_i130"
				( attribute "CDS_LIB" "mstr_controller"
					( Origin gPackager )
				)
				( attribute "CDS_LMAN_SYM_OUTLINE" "-400,900,400,-900"
					( Origin gPackager )
				)
				( attribute "CDS_LOCATION" "EU1C2"
					( Origin gPackager )
				)
				( attribute "CDS_SEC" "1"
					( Origin gPackager )
				)
				( attribute "LOCATION" "EU1C2"
					( Origin gFrontEnd )
				)
				( attribute "MATERIAL" "IC"
					( Origin gFrontEnd )
				)
				( attribute "PACK_TYPE" "QFN"
					( Origin gFrontEnd )
				)
				( attribute "PART_NUMBER" "H79206-001"
					( Origin gFrontEnd )
				)
				( attribute "PHYS_PAGE" "206"
					( Origin gFrontEnd )
				)
				( attribute "ROT" "0"
					( Origin gFrontEnd )
				)
				( attribute "SEC" "1"
					( Origin gFrontEnd )
				)
				( attribute "SEC_TYPE" "QFN"
					( Origin gFrontEnd )
				)
				( attribute "VER" "1"
					( Origin gFrontEnd )
				)
				( attribute "XY" "(-3825,2625)"
					( Origin gFrontEnd )
				)
				( attribute "CHIPS_PART_NAME" "PXE1610B"
					( Origin gPackager )
				)
				( attribute "CDS_PART_NAME" "PXE1610B_QFN-IC,H79206-001"
					( Origin gPackager )
				)
				( objectStatus "EU1C2" )
				( pin "airef1"
					( attribute "PN" "23"
						( Origin gPackager )
					)
					( objectStatus "EU1C2.23" )
				)
				( pin "airef2"
					( attribute "PN" "25"
						( Origin gPackager )
					)
					( objectStatus "EU1C2.25" )
				)
				( pin "airef3"
					( attribute "PN" "27"
						( Origin gPackager )
					)
					( objectStatus "EU1C2.27" )
				)
				( pin "airef4"
					( attribute "PN" "29"
						( Origin gPackager )
					)
					( objectStatus "EU1C2.29" )
				)
				( pin "airef5"
					( attribute "PN" "31"
						( Origin gPackager )
					)
					( objectStatus "EU1C2.31" )
				)
				( pin "airef6"
					( attribute "PN" "33"
						( Origin gPackager )
					)
					( objectStatus "EU1C2.33" )
				)
				( pin "aisen1"
					( attribute "PN" "24"
						( Origin gPackager )
					)
					( objectStatus "EU1C2.24" )
				)
				( pin "aisen2"
					( attribute "PN" "26"
						( Origin gPackager )
					)
					( objectStatus "EU1C2.26" )
				)
				( pin "aisen3"
					( attribute "PN" "28"
						( Origin gPackager )
					)
					( objectStatus "EU1C2.28" )
				)
				( pin "aisen4"
					( attribute "PN" "30"
						( Origin gPackager )
					)
					( objectStatus "EU1C2.30" )
				)
				( pin "aisen5"
					( attribute "PN" "32"
						( Origin gPackager )
					)
					( objectStatus "EU1C2.32" )
				)
				( pin "aisen6"
					( attribute "PN" "34"
						( Origin gPackager )
					)
					( objectStatus "EU1C2.34" )
				)
				( pin "apwm1"
					( attribute "PN" "7"
						( Origin gPackager )
					)
					( objectStatus "EU1C2.7" )
				)
				( pin "apwm2"
					( attribute "PN" "6"
						( Origin gPackager )
					)
					( objectStatus "EU1C2.6" )
				)
				( pin "apwm3"
					( attribute "PN" "5"
						( Origin gPackager )
					)
					( objectStatus "EU1C2.5" )
				)
				( pin "apwm4"
					( attribute "PN" "4"
						( Origin gPackager )
					)
					( objectStatus "EU1C2.4" )
				)
				( pin "apwm5"
					( attribute "PN" "3"
						( Origin gPackager )
					)
					( objectStatus "EU1C2.3" )
				)
				( pin "apwm6"
					( attribute "PN" "2"
						( Origin gPackager )
					)
					( objectStatus "EU1C2.2" )
				)
				( pin "atsen"
					( attribute "PN" "43"
						( Origin gPackager )
					)
					( objectStatus "EU1C2.43" )
				)
				( pin "avref"
					( attribute "PN" "22"
						( Origin gPackager )
					)
					( objectStatus "EU1C2.22" )
				)
				( pin "avren"
					( attribute "PN" "12"
						( Origin gPackager )
					)
					( objectStatus "EU1C2.12" )
				)
				( pin "avrrdy"
					( attribute "PN" "11"
						( Origin gPackager )
					)
					( objectStatus "EU1C2.11" )
				)
				( pin "avsen"
					( attribute "PN" "21"
						( Origin gPackager )
					)
					( objectStatus "EU1C2.21" )
				)
				( pin "biref1"
					( attribute "PN" "37"
						( Origin gPackager )
					)
					( objectStatus "EU1C2.37" )
				)
				( pin "bisen1"
					( attribute "PN" "38"
						( Origin gPackager )
					)
					( objectStatus "EU1C2.38" )
				)
				( pin "bpwm1"
					( attribute "PN" "1"
						( Origin gPackager )
					)
					( objectStatus "EU1C2.1" )
				)
				( pin "btsen"
					( attribute "PN" "42"
						( Origin gPackager )
					)
					( objectStatus "EU1C2.42" )
				)
				( pin "bvref"
					( attribute "PN" "36"
						( Origin gPackager )
					)
					( objectStatus "EU1C2.36" )
				)
				( pin "bvsen"
					( attribute "PN" "35"
						( Origin gPackager )
					)
					( objectStatus "EU1C2.35" )
				)
				( pin "iinsen"
					( attribute "PN" "46"
						( Origin gPackager )
					)
					( objectStatus "EU1C2.46" )
				)
				( pin "mp0"
					( attribute "PN" "15"
						( Origin gPackager )
					)
					( objectStatus "EU1C2.15" )
				)
				( pin "mp1"
					( attribute "PN" "16"
						( Origin gPackager )
					)
					( objectStatus "EU1C2.16" )
				)
				( pin "mp2"
					( attribute "PN" "20"
						( Origin gPackager )
					)
					( objectStatus "EU1C2.20" )
				)
				( pin "mp3"
					( attribute "PN" "39"
						( Origin gPackager )
					)
					( objectStatus "EU1C2.39" )
				)
				( pin "mp4"
					( attribute "PN" "40"
						( Origin gPackager )
					)
					( objectStatus "EU1C2.40" )
				)
				( pin "pinalrt_n"
					( attribute "PN" "14"
						( Origin gPackager )
					)
					( objectStatus "EU1C2.14" )
				)
				( pin "reset_n"
					( attribute "PN" "10"
						( Origin gPackager )
					)
					( objectStatus "EU1C2.10" )
				)
				( pin "scl"
					( attribute "PN" "9"
						( Origin gPackager )
					)
					( objectStatus "EU1C2.9" )
				)
				( pin "sda"
					( attribute "PN" "8"
						( Origin gPackager )
					)
					( objectStatus "EU1C2.8" )
				)
				( pin "thpad"
					( attribute "PN" "49"
						( Origin gPackager )
					)
					( objectStatus "EU1C2.49" )
				)
				( pin "valrt_n"
					( attribute "PN" "19"
						( Origin gPackager )
					)
					( objectStatus "EU1C2.19" )
				)
				( pin "vclk"
					( attribute "PN" "17"
						( Origin gPackager )
					)
					( objectStatus "EU1C2.17" )
				)
				( pin "vd12"
					( attribute "PN" "48"
						( Origin gPackager )
					)
					( objectStatus "EU1C2.48" )
				)
				( pin "vdd"
					( attribute "PN" "47"
						( Origin gPackager )
					)
					( objectStatus "EU1C2.47" )
				)
				( pin "vdio"
					( attribute "PN" "18"
						( Origin gPackager )
					)
					( objectStatus "EU1C2.18" )
				)
				( pin "vinsen"
					( attribute "PN" "45"
						( Origin gPackager )
					)
					( objectStatus "EU1C2.45" )
				)
				( pin "vrhot_n"
					( attribute "PN" "13"
						( Origin gPackager )
					)
					( objectStatus "EU1C2.13" )
				)
				( pin "xaddr1"
					( attribute "PN" "44"
						( Origin gPackager )
					)
					( objectStatus "EU1C2.44" )
				)
				( pin "xaddr2"
					( attribute "PN" "41"
						( Origin gPackager )
					)
					( objectStatus "EU1C2.41" )
				)
			)
			( gate "@baseboard_fab2_lib.baseboard_fab2(sch_1):page207_i8"
				( attribute "BOM_COST" "PROC_VRD_VCCIN_CPU0"
					( Origin gFrontEnd )
				)
				( attribute "CDS_LIB" "dev_discrete"
					( Origin gPackager )
				)
				( attribute "CDS_LOCATION" "C9R8"
					( Origin gPackager )
				)
				( attribute "CDS_SEC" "1"
					( Origin gPackager )
				)
				( attribute "LOCATION" "C9R8"
					( Origin gFrontEnd )
				)
				( attribute "MATERIAL" "X6S"
					( Origin gFrontEnd )
				)
				( attribute "PACK_TYPE" "0603V"
					( Origin gFrontEnd )
				)
				( attribute "PART_NUMBER" "E15431-004"
					( Origin gFrontEnd )
				)
				( attribute "PHYS_PAGE" "207"
					( Origin gFrontEnd )
				)
				( attribute "ROOM" "PVCCIN_CPU1_PWR_VR"
					( Origin gFrontEnd )
				)
				( attribute "ROT" "0"
					( Origin gFrontEnd )
				)
				( attribute "SEC" "1"
					( Origin gFrontEnd )
				)
				( attribute "SEC_TYPE" "0603V"
					( Origin gFrontEnd )
				)
				( attribute "TOLERANCE" "20%"
					( Origin gFrontEnd )
				)
				( attribute "VALUE" "22.0UF"
					( Origin gFrontEnd )
				)
				( attribute "VER" "1"
					( Origin gFrontEnd )
				)
				( attribute "VOLTAGE" "4V"
					( Units "uVoltage" "V" 1.000000)
					( Origin gFrontEnd )
				)
				( attribute "XY" "(-1425,3325)"
					( Origin gFrontEnd )
				)
				( attribute "CHIPS_PART_NAME" "CAP_A"
					( Origin gPackager )
				)
				( attribute "CDS_PART_NAME" "CAP_A_0603V-22.0UF,4V,20%,X6S,A"
					( Origin gPackager )
				)
				( objectStatus "C9R8" )
				( pin "a"
					( attribute "PN" "1"
						( Origin gPackager )
					)
					( objectStatus "C9R8.1" )
				)
				( pin "b"
					( attribute "PN" "2"
						( Origin gPackager )
					)
					( objectStatus "C9R8.2" )
				)
			)
			( gate "@baseboard_fab2_lib.baseboard_fab2(sch_1):page207_i10"
				( attribute "CDS_LIB" "mstr_discrete"
					( Origin gPackager )
				)
				( attribute "CDS_LOCATION" "L1E1"
					( Origin gPackager )
				)
				( attribute "CDS_SEC" "1"
					( Origin gPackager )
				)
				( attribute "LOCATION" "L1E1"
					( Origin gFrontEnd )
				)
				( attribute "MATERIAL" "IND"
					( Origin gFrontEnd )
				)
				( attribute "PACK_TYPE" "SM"
					( Origin gFrontEnd )
				)
				( attribute "PART_NUMBER" "D92183-034"
					( Origin gFrontEnd )
				)
				( attribute "PHYS_PAGE" "207"
					( Origin gFrontEnd )
				)
				( attribute "ROOM" "PVCCIN_CPU1_PWR_VR"
					( Origin gFrontEnd )
				)
				( attribute "ROT" "0"
					( Origin gFrontEnd )
				)
				( attribute "SEC" "1"
					( Origin gPackager )
				)
				( attribute "VALUE" "0.12UH"
					( Origin gFrontEnd )
				)
				( attribute "VER" "1"
					( Origin gFrontEnd )
				)
				( attribute "XY" "(-2000,3525)"
					( Origin gFrontEnd )
				)
				( attribute "CHIPS_PART_NAME" "INDUCTOR"
					( Origin gPackager )
				)
				( attribute "CDS_PART_NAME" "INDUCTOR_SM-0.12UH,IND,D92183-A"
					( Origin gPackager )
				)
				( objectStatus "L1E1" )
				( pin "ina"
					( attribute "PN" "1"
						( Origin gPackager )
					)
					( objectStatus "L1E1.1" )
				)
				( pin "inb"
					( attribute "PN" "2"
						( Origin gPackager )
					)
					( objectStatus "L1E1.2" )
				)
			)
			( gate "@baseboard_fab2_lib.baseboard_fab2(sch_1):page207_i16"
				( attribute "CDS_LIB" "mstr_discrete"
					( Origin gPackager )
				)
				( attribute "CDS_LOCATION" "L1D3"
					( Origin gPackager )
				)
				( attribute "CDS_SEC" "1"
					( Origin gPackager )
				)
				( attribute "LOCATION" "L1D3"
					( Origin gFrontEnd )
				)
				( attribute "MATERIAL" "IND"
					( Origin gFrontEnd )
				)
				( attribute "PACK_TYPE" "SM"
					( Origin gFrontEnd )
				)
				( attribute "PART_NUMBER" "D92183-034"
					( Origin gFrontEnd )
				)
				( attribute "PHYS_PAGE" "207"
					( Origin gFrontEnd )
				)
				( attribute "ROOM" "PVCCIN_CPU1_PWR_VR"
					( Origin gFrontEnd )
				)
				( attribute "ROT" "0"
					( Origin gFrontEnd )
				)
				( attribute "SEC" "1"
					( Origin gPackager )
				)
				( attribute "VALUE" "0.12UH"
					( Origin gFrontEnd )
				)
				( attribute "VER" "1"
					( Origin gFrontEnd )
				)
				( attribute "XY" "(-2100,925)"
					( Origin gFrontEnd )
				)
				( attribute "CHIPS_PART_NAME" "INDUCTOR"
					( Origin gPackager )
				)
				( attribute "CDS_PART_NAME" "INDUCTOR_SM-0.12UH,IND,D92183-A"
					( Origin gPackager )
				)
				( objectStatus "L1D3" )
				( pin "ina"
					( attribute "PN" "1"
						( Origin gPackager )
					)
					( objectStatus "L1D3.1" )
				)
				( pin "inb"
					( attribute "PN" "2"
						( Origin gPackager )
					)
					( objectStatus "L1D3.2" )
				)
			)
			( gate "@baseboard_fab2_lib.baseboard_fab2(sch_1):page207_i18"
				( attribute "BOM_COST" "PROC_VRD_VCCIN_CPU0"
					( Origin gFrontEnd )
				)
				( attribute "CDS_LIB" "dev_discrete"
					( Origin gPackager )
				)
				( attribute "CDS_LOCATION" "C1E3"
					( Origin gPackager )
				)
				( attribute "CDS_SEC" "1"
					( Origin gPackager )
				)
				( attribute "LOCATION" "C1E3"
					( Origin gFrontEnd )
				)
				( attribute "MATERIAL" "X6S"
					( Origin gFrontEnd )
				)
				( attribute "PACK_TYPE" "0603V"
					( Origin gFrontEnd )
				)
				( attribute "PART_NUMBER" "E15431-004"
					( Origin gFrontEnd )
				)
				( attribute "PHYS_PAGE" "207"
					( Origin gFrontEnd )
				)
				( attribute "ROOM" "PVCCIN_CPU1_PWR_VR"
					( Origin gFrontEnd )
				)
				( attribute "ROT" "0"
					( Origin gFrontEnd )
				)
				( attribute "SEC" "1"
					( Origin gFrontEnd )
				)
				( attribute "SEC_TYPE" "0603V"
					( Origin gFrontEnd )
				)
				( attribute "TOLERANCE" "20%"
					( Origin gFrontEnd )
				)
				( attribute "VALUE" "22.0UF"
					( Origin gFrontEnd )
				)
				( attribute "VER" "1"
					( Origin gFrontEnd )
				)
				( attribute "VOLTAGE" "4V"
					( Units "uVoltage" "V" 1.000000)
					( Origin gFrontEnd )
				)
				( attribute "XY" "(-1525,775)"
					( Origin gFrontEnd )
				)
				( attribute "CHIPS_PART_NAME" "CAP_A"
					( Origin gPackager )
				)
				( attribute "CDS_PART_NAME" "CAP_A_0603V-22.0UF,4V,20%,X6S,A"
					( Origin gPackager )
				)
				( objectStatus "C1E3" )
				( pin "a"
					( attribute "PN" "1"
						( Origin gPackager )
					)
					( objectStatus "C1E3.1" )
				)
				( pin "b"
					( attribute "PN" "2"
						( Origin gPackager )
					)
					( objectStatus "C1E3.2" )
				)
			)
			( gate "@baseboard_fab2_lib.baseboard_fab2(sch_1):page207_i20"
				( attribute "CDS_LIB" "mstr_discrete"
					( Origin gPackager )
				)
				( attribute "CDS_LOCATION" "EU1E2"
					( Origin gPackager )
				)
				( attribute "CDS_SEC" "1"
					( Origin gPackager )
				)
				( attribute "LOCATION" "EU1E2"
					( Origin gFrontEnd )
				)
				( attribute "MATERIAL" "IC"
					( Origin gFrontEnd )
				)
				( attribute "PACK_TYPE" "SM"
					( Origin gFrontEnd )
				)
				( attribute "PART_NUMBER" "H73688-001"
					( Origin gFrontEnd )
				)
				( attribute "PHYS_PAGE" "207"
					( Origin gFrontEnd )
				)
				( attribute "ROOM" "PVCCIN_CPU1_PWR_VR"
					( Origin gFrontEnd )
				)
				( attribute "ROT" "0"
					( Origin gFrontEnd )
				)
				( attribute "SEC" "1"
					( Origin gFrontEnd )
				)
				( attribute "SEC_TYPE" "SM"
					( Origin gFrontEnd )
				)
				( attribute "VALUE" "IR35411"
					( Origin gFrontEnd )
				)
				( attribute "VER" "1"
					( Origin gFrontEnd )
				)
				( attribute "XY" "(-3450,3825)"
					( Origin gFrontEnd )
				)
				( attribute "CHIPS_PART_NAME" "IR354XX"
					( Origin gPackager )
				)
				( attribute "CDS_PART_NAME" "IR354XX_SM-IR35411,IC,H73688-0A"
					( Origin gPackager )
				)
				( objectStatus "EU1E2" )
				( pin "boost"
					( attribute "PN" "33"
						( Origin gPackager )
					)
					( objectStatus "EU1E2.33" )
				)
				( pin "en"
					( attribute "PN" "35"
						( Origin gPackager )
					)
					( objectStatus "EU1E2.35" )
				)
				( pin "gl(0)"
					( attribute "PN" "6"
						( Origin gPackager )
					)
					( objectStatus "EU1E2.6" )
				)
				( pin "gl(1)"
					( attribute "PN" "41"
						( Origin gPackager )
					)
					( objectStatus "EU1E2.41" )
				)
				( pin "iout"
					( attribute "PN" "38"
						( Origin gPackager )
					)
					( objectStatus "EU1E2.38" )
				)
				( pin "lgnd"
					( attribute "PN" "2"
						( Origin gPackager )
					)
					( objectStatus "EU1E2.2" )
				)
				( pin "nc"
					( attribute "PN" "31"
						( Origin gPackager )
					)
					( objectStatus "EU1E2.31" )
				)
				( pin "ocset"
					( attribute "PN" "37"
						( Origin gPackager )
					)
					( objectStatus "EU1E2.37" )
				)
				( pin "pgnd(0)"
					( attribute "PN" "5"
						( Origin gPackager )
					)
					( objectStatus "EU1E2.5" )
				)
				( pin "pgnd(1)"
					( attribute "PN" "7"
						( Origin gPackager )
					)
					( objectStatus "EU1E2.7" )
				)
				( pin "pgnd(2)"
					( attribute "PN" "40"
						( Origin gPackager )
					)
					( objectStatus "EU1E2.40" )
				)
				( pin "phase"
					( attribute "PN" "32"
						( Origin gPackager )
					)
					( objectStatus "EU1E2.32" )
				)
				( pin "pwm"
					( attribute "PN" "34"
						( Origin gPackager )
					)
					( objectStatus "EU1E2.34" )
				)
				( pin "refin"
					( attribute "PN" "39"
						( Origin gPackager )
					)
					( objectStatus "EU1E2.39" )
				)
				( pin "sw"
					( attribute "PN" "10"
						( Origin gPackager )
					)
					( objectStatus "EU1E2.10" )
				)
				( pin "tout_flt"
					( attribute "PN" "36"
						( Origin gPackager )
					)
					( objectStatus "EU1E2.36" )
				)
				( pin "vcc"
					( attribute "PN" "3"
						( Origin gPackager )
					)
					( objectStatus "EU1E2.3" )
				)
				( pin "vdrv"
					( attribute "PN" "4"
						( Origin gPackager )
					)
					( objectStatus "EU1E2.4" )
				)
				( pin "vin(0)"
					( attribute "PN" "25"
						( Origin gPackager )
					)
					( objectStatus "EU1E2.25" )
				)
				( pin "vin(1)"
					( attribute "PN" "30"
						( Origin gPackager )
					)
					( objectStatus "EU1E2.30" )
				)
				( pin "vos"
					( attribute "PN" "1"
						( Origin gPackager )
					)
					( objectStatus "EU1E2.1" )
				)
			)
			( gate "@baseboard_fab2_lib.baseboard_fab2(sch_1):page207_i24"
				( attribute "CDS_LIB" "mstr_discrete"
					( Origin gPackager )
				)
				( attribute "CDS_LOCATION" "EU1D4"
					( Origin gPackager )
				)
				( attribute "CDS_SEC" "1"
					( Origin gPackager )
				)
				( attribute "LOCATION" "EU1D4"
					( Origin gFrontEnd )
				)
				( attribute "MATERIAL" "IC"
					( Origin gFrontEnd )
				)
				( attribute "PACK_TYPE" "SM"
					( Origin gFrontEnd )
				)
				( attribute "PART_NUMBER" "H73688-001"
					( Origin gFrontEnd )
				)
				( attribute "PHYS_PAGE" "207"
					( Origin gFrontEnd )
				)
				( attribute "ROOM" "PVCCIN_CPU1_PWR_VR"
					( Origin gFrontEnd )
				)
				( attribute "ROT" "0"
					( Origin gFrontEnd )
				)
				( attribute "SEC" "1"
					( Origin gFrontEnd )
				)
				( attribute "SEC_TYPE" "SM"
					( Origin gFrontEnd )
				)
				( attribute "VALUE" "IR35411"
					( Origin gFrontEnd )
				)
				( attribute "VER" "1"
					( Origin gFrontEnd )
				)
				( attribute "XY" "(-3475,1225)"
					( Origin gFrontEnd )
				)
				( attribute "CHIPS_PART_NAME" "IR354XX"
					( Origin gPackager )
				)
				( attribute "CDS_PART_NAME" "IR354XX_SM-IR35411,IC,H73688-0A"
					( Origin gPackager )
				)
				( objectStatus "EU1D4" )
				( pin "boost"
					( attribute "PN" "33"
						( Origin gPackager )
					)
					( objectStatus "EU1D4.33" )
				)
				( pin "en"
					( attribute "PN" "35"
						( Origin gPackager )
					)
					( objectStatus "EU1D4.35" )
				)
				( pin "gl(0)"
					( attribute "PN" "6"
						( Origin gPackager )
					)
					( objectStatus "EU1D4.6" )
				)
				( pin "gl(1)"
					( attribute "PN" "41"
						( Origin gPackager )
					)
					( objectStatus "EU1D4.41" )
				)
				( pin "iout"
					( attribute "PN" "38"
						( Origin gPackager )
					)
					( objectStatus "EU1D4.38" )
				)
				( pin "lgnd"
					( attribute "PN" "2"
						( Origin gPackager )
					)
					( objectStatus "EU1D4.2" )
				)
				( pin "nc"
					( attribute "PN" "31"
						( Origin gPackager )
					)
					( objectStatus "EU1D4.31" )
				)
				( pin "ocset"
					( attribute "PN" "37"
						( Origin gPackager )
					)
					( objectStatus "EU1D4.37" )
				)
				( pin "pgnd(0)"
					( attribute "PN" "5"
						( Origin gPackager )
					)
					( objectStatus "EU1D4.5" )
				)
				( pin "pgnd(1)"
					( attribute "PN" "7"
						( Origin gPackager )
					)
					( objectStatus "EU1D4.7" )
				)
				( pin "pgnd(2)"
					( attribute "PN" "40"
						( Origin gPackager )
					)
					( objectStatus "EU1D4.40" )
				)
				( pin "phase"
					( attribute "PN" "32"
						( Origin gPackager )
					)
					( objectStatus "EU1D4.32" )
				)
				( pin "pwm"
					( attribute "PN" "34"
						( Origin gPackager )
					)
					( objectStatus "EU1D4.34" )
				)
				( pin "refin"
					( attribute "PN" "39"
						( Origin gPackager )
					)
					( objectStatus "EU1D4.39" )
				)
				( pin "sw"
					( attribute "PN" "10"
						( Origin gPackager )
					)
					( objectStatus "EU1D4.10" )
				)
				( pin "tout_flt"
					( attribute "PN" "36"
						( Origin gPackager )
					)
					( objectStatus "EU1D4.36" )
				)
				( pin "vcc"
					( attribute "PN" "3"
						( Origin gPackager )
					)
					( objectStatus "EU1D4.3" )
				)
				( pin "vdrv"
					( attribute "PN" "4"
						( Origin gPackager )
					)
					( objectStatus "EU1D4.4" )
				)
				( pin "vin(0)"
					( attribute "PN" "25"
						( Origin gPackager )
					)
					( objectStatus "EU1D4.25" )
				)
				( pin "vin(1)"
					( attribute "PN" "30"
						( Origin gPackager )
					)
					( objectStatus "EU1D4.30" )
				)
				( pin "vos"
					( attribute "PN" "1"
						( Origin gPackager )
					)
					( objectStatus "EU1D4.1" )
				)
			)
			( gate "@baseboard_fab2_lib.baseboard_fab2(sch_1):page207_i26"
				( attribute "CDS_LIB" "mstr_discrete"
					( Origin gPackager )
				)
				( attribute "CDS_LOCATION" "R9R2"
					( Origin gPackager )
				)
				( attribute "CDS_SEC" "1"
					( Origin gPackager )
				)
				( attribute "LOCATION" "R9R2"
					( Origin gFrontEnd )
				)
				( attribute "MATERIAL" "CHIP"
					( Origin gFrontEnd )
				)
				( attribute "PACK_TYPE" "0402"
					( Origin gFrontEnd )
				)
				( attribute "PART_NUMBER" "G21796-090"
					( Origin gFrontEnd )
				)
				( attribute "PHYS_PAGE" "207"
					( Origin gFrontEnd )
				)
				( attribute "ROOM" "PVCCIN_CPU1_PWR_VR"
					( Origin gFrontEnd )
				)
				( attribute "ROT" "0"
					( Origin gFrontEnd )
				)
				( attribute "SEC" "1"
					( Origin gFrontEnd )
				)
				( attribute "SEC_TYPE" "0402"
					( Origin gFrontEnd )
				)
				( attribute "TOLERANCE" "1%"
					( Origin gFrontEnd )
				)
				( attribute "VALUE" "1.0"
					( Origin gFrontEnd )
				)
				( attribute "VER" "1"
					( Origin gFrontEnd )
				)
				( attribute "WATTAGE" "1/16W"
					( Origin gFrontEnd )
				)
				( attribute "XY" "(-5700,4625)"
					( Origin gFrontEnd )
				)
				( attribute "CHIPS_PART_NAME" "RES"
					( Origin gPackager )
				)
				( attribute "CDS_PART_NAME" "RES_0402-1.0,1%,1/16W,CHIP,G21A"
					( Origin gPackager )
				)
				( objectStatus "R9R2" )
				( pin "a"
					( attribute "PN" "1"
						( Origin gPackager )
					)
					( objectStatus "R9R2.1" )
				)
				( pin "b"
					( attribute "PN" "2"
						( Origin gPackager )
					)
					( objectStatus "R9R2.2" )
				)
			)
			( gate "@baseboard_fab2_lib.baseboard_fab2(sch_1):page207_i28"
				( attribute "CDS_LIB" "mstr_discrete"
					( Origin gPackager )
				)
				( attribute "CDS_LOCATION" "C1E7"
					( Origin gPackager )
				)
				( attribute "CDS_SEC" "1"
					( Origin gPackager )
				)
				( attribute "LOCATION" "C1E7"
					( Origin gFrontEnd )
				)
				( attribute "MATERIAL" "X7R"
					( Origin gFrontEnd )
				)
				( attribute "PACK_TYPE" "0402"
					( Origin gFrontEnd )
				)
				( attribute "PART_NUMBER" "A36096-155"
					( Origin gFrontEnd )
				)
				( attribute "PHYS_PAGE" "207"
					( Origin gFrontEnd )
				)
				( attribute "ROOM" "PVCCIN_CPU1_PWR_VR"
					( Origin gFrontEnd )
				)
				( attribute "ROT" "0"
					( Origin gFrontEnd )
				)
				( attribute "SEC" "1"
					( Origin gFrontEnd )
				)
				( attribute "SEC_TYPE" "0402"
					( Origin gFrontEnd )
				)
				( attribute "TOLERANCE" "10%"
					( Origin gFrontEnd )
				)
				( attribute "VALUE" "0.22UF"
					( Origin gFrontEnd )
				)
				( attribute "VER" "1"
					( Origin gFrontEnd )
				)
				( attribute "VOLTAGE" "16V"
					( Units "uVoltage" "V" 1.000000)
					( Origin gFrontEnd )
				)
				( attribute "XY" "(-5250,4100)"
					( Origin gFrontEnd )
				)
				( attribute "CHIPS_PART_NAME" "CAP"
					( Origin gPackager )
				)
				( attribute "CDS_PART_NAME" "CAP_0402-0.22UF,16V,10%,X7R,A3A"
					( Origin gPackager )
				)
				( objectStatus "C1E7" )
				( pin "a"
					( attribute "PN" "1"
						( Origin gPackager )
					)
					( objectStatus "C1E7.1" )
				)
				( pin "b"
					( attribute "PN" "2"
						( Origin gPackager )
					)
					( objectStatus "C1E7.2" )
				)
			)
			( gate "@baseboard_fab2_lib.baseboard_fab2(sch_1):page207_i29"
				( attribute "CDS_LIB" "dev_discrete"
					( Origin gPackager )
				)
				( attribute "CDS_LOCATION" "C1E6"
					( Origin gPackager )
				)
				( attribute "CDS_SEC" "1"
					( Origin gPackager )
				)
				( attribute "LOCATION" "C1E6"
					( Origin gFrontEnd )
				)
				( attribute "MATERIAL" "X6S"
					( Origin gFrontEnd )
				)
				( attribute "PACK_TYPE" "0402V"
					( Origin gFrontEnd )
				)
				( attribute "PART_NUMBER" "D97712-004"
					( Origin gFrontEnd )
				)
				( attribute "PHYS_PAGE" "207"
					( Origin gFrontEnd )
				)
				( attribute "ROOM" "PVCCIN_CPU1_PWR_VR"
					( Origin gFrontEnd )
				)
				( attribute "ROT" "2"
					( Origin gFrontEnd )
				)
				( attribute "SEC" "1"
					( Origin gFrontEnd )
				)
				( attribute "SEC_TYPE" "0402V"
					( Origin gFrontEnd )
				)
				( attribute "TOLERANCE" "10%"
					( Origin gFrontEnd )
				)
				( attribute "VALUE" "1.0UF"
					( Origin gFrontEnd )
				)
				( attribute "VER" "1"
					( Origin gFrontEnd )
				)
				( attribute "VOLTAGE" "6.3V"
					( Units "uVoltage" "V" 1.000000)
					( Origin gFrontEnd )
				)
				( attribute "XY" "(-5375,4100)"
					( Origin gFrontEnd )
				)
				( attribute "CHIPS_PART_NAME" "CAP_A"
					( Origin gPackager )
				)
				( attribute "CDS_PART_NAME" "CAP_A_0402V-1.0UF,6.3V,10%,X6SA"
					( Origin gPackager )
				)
				( objectStatus "C1E6" )
				( pin "a"
					( attribute "PN" "1"
						( Origin gPackager )
					)
					( objectStatus "C1E6.1" )
				)
				( pin "b"
					( attribute "PN" "2"
						( Origin gPackager )
					)
					( objectStatus "C1E6.2" )
				)
			)
			( gate "@baseboard_fab2_lib.baseboard_fab2(sch_1):page207_i30"
				( attribute "CDS_LIB" "mstr_discrete"
					( Origin gPackager )
				)
				( attribute "CDS_LOCATION" "C1E11"
					( Origin gPackager )
				)
				( attribute "CDS_SEC" "1"
					( Origin gPackager )
				)
				( attribute "LOCATION" "C1E11"
					( Origin gFrontEnd )
				)
				( attribute "MATERIAL" "X7R"
					( Origin gFrontEnd )
				)
				( attribute "NO_XNET_CONNECTION" "1"
					( Origin gFrontEnd )
				)
				( attribute "PACK_TYPE" "0402"
					( Origin gFrontEnd )
				)
				( attribute "PART_NUMBER" "A36096-104"
					( Origin gFrontEnd )
				)
				( attribute "PHYS_PAGE" "207"
					( Origin gFrontEnd )
				)
				( attribute "ROOM" "PVCCIN_CPU1_PWR_VR"
					( Origin gFrontEnd )
				)
				( attribute "ROT" "2"
					( Origin gFrontEnd )
				)
				( attribute "SEC" "1"
					( Origin gFrontEnd )
				)
				( attribute "SEC_TYPE" "0402"
					( Origin gFrontEnd )
				)
				( attribute "SPOF" "TRUE"
					( Origin gFrontEnd )
				)
				( attribute "TOLERANCE" "10%"
					( Origin gFrontEnd )
				)
				( attribute "VALUE" "0.220UF"
					( Origin gFrontEnd )
				)
				( attribute "VER" "1"
					( Origin gFrontEnd )
				)
				( attribute "VOLTAGE" "16V"
					( Units "uVoltage" "V" 1.000000)
					( Origin gFrontEnd )
				)
				( attribute "XY" "(-6000,3475)"
					( Origin gFrontEnd )
				)
				( attribute "CHIPS_PART_NAME" "CAP"
					( Origin gPackager )
				)
				( attribute "CDS_PART_NAME" "CAP_0402-0.220UF,16V,10%,X7R,AA"
					( Origin gPackager )
				)
				( objectStatus "C1E11" )
				( pin "a"
					( attribute "PN" "1"
						( Origin gPackager )
					)
					( objectStatus "C1E11.1" )
				)
				( pin "b"
					( attribute "PN" "2"
						( Origin gPackager )
					)
					( objectStatus "C1E11.2" )
				)
			)
			( gate "@baseboard_fab2_lib.baseboard_fab2(sch_1):page207_i32"
				( attribute "CDS_LIB" "mstr_discrete"
					( Origin gPackager )
				)
				( attribute "CDS_LOCATION" "C1E8"
					( Origin gPackager )
				)
				( attribute "CDS_SEC" "1"
					( Origin gPackager )
				)
				( attribute "LOCATION" "C1E8"
					( Origin gFrontEnd )
				)
				( attribute "MATERIAL" "X6S"
					( Origin gFrontEnd )
				)
				( attribute "PACK_TYPE" "0402"
					( Origin gFrontEnd )
				)
				( attribute "PART_NUMBER" "D97712-011"
					( Origin gFrontEnd )
				)
				( attribute "PHYS_PAGE" "207"
					( Origin gFrontEnd )
				)
				( attribute "ROOM" "PVCCIN_CPU1_PWR_VR"
					( Origin gFrontEnd )
				)
				( attribute "ROT" "0"
					( Origin gFrontEnd )
				)
				( attribute "SEC" "1"
					( Origin gFrontEnd )
				)
				( attribute "SEC_TYPE" "0402"
					( Origin gFrontEnd )
				)
				( attribute "TOLERANCE" "10%"
					( Origin gFrontEnd )
				)
				( attribute "VALUE" "1.0UF"
					( Origin gFrontEnd )
				)
				( attribute "VER" "1"
					( Origin gFrontEnd )
				)
				( attribute "VOLTAGE" "16V"
					( Units "uVoltage" "V" 1.000000)
					( Origin gFrontEnd )
				)
				( attribute "XY" "(-5950,4075)"
					( Origin gFrontEnd )
				)
				( attribute "CHIPS_PART_NAME" "CAP"
					( Origin gPackager )
				)
				( attribute "CDS_PART_NAME" "CAP_0402-1.0UF,16V,10%,X6S,D97A"
					( Origin gPackager )
				)
				( objectStatus "C1E8" )
				( pin "a"
					( attribute "PN" "1"
						( Origin gPackager )
					)
					( objectStatus "C1E8.1" )
				)
				( pin "b"
					( attribute "PN" "2"
						( Origin gPackager )
					)
					( objectStatus "C1E8.2" )
				)
			)
			( gate "@baseboard_fab2_lib.baseboard_fab2(sch_1):page207_i33"
				( attribute "CDS_LIB" "dev_discrete"
					( Origin gPackager )
				)
				( attribute "CDS_LOCATION" "C1E14"
					( Origin gPackager )
				)
				( attribute "CDS_SEC" "1"
					( Origin gPackager )
				)
				( attribute "LOCATION" "C1E14"
					( Origin gFrontEnd )
				)
				( attribute "MATERIAL" "X7R"
					( Origin gFrontEnd )
				)
				( attribute "PACK_TYPE" "0402V"
					( Origin gFrontEnd )
				)
				( attribute "PART_NUMBER" "A36096-030"
					( Origin gFrontEnd )
				)
				( attribute "PHYS_PAGE" "207"
					( Origin gFrontEnd )
				)
				( attribute "ROOM" "PVCCIN_CPU1_PWR_VR"
					( Origin gFrontEnd )
				)
				( attribute "ROT" "0"
					( Origin gFrontEnd )
				)
				( attribute "SEC" "1"
					( Origin gFrontEnd )
				)
				( attribute "SEC_TYPE" "0402V"
					( Origin gFrontEnd )
				)
				( attribute "TOLERANCE" "10%"
					( Origin gFrontEnd )
				)
				( attribute "VALUE" "0.1UF"
					( Origin gFrontEnd )
				)
				( attribute "VER" "1"
					( Origin gFrontEnd )
				)
				( attribute "VOLTAGE" "16V"
					( Units "uVoltage" "V" 1.000000)
					( Origin gFrontEnd )
				)
				( attribute "XY" "(-6250,4100)"
					( Origin gFrontEnd )
				)
				( attribute "CHIPS_PART_NAME" "CAP_A"
					( Origin gPackager )
				)
				( attribute "CDS_PART_NAME" "CAP_A_0402V-0.1UF,16V,10%,X7R,A"
					( Origin gPackager )
				)
				( objectStatus "C1E14" )
				( pin "a"
					( attribute "PN" "1"
						( Origin gPackager )
					)
					( objectStatus "C1E14.1" )
				)
				( pin "b"
					( attribute "PN" "2"
						( Origin gPackager )
					)
					( objectStatus "C1E14.2" )
				)
			)
			( gate "@baseboard_fab2_lib.baseboard_fab2(sch_1):page207_i34"
				( attribute "CDS_LIB" "mstr_discrete"
					( Origin gPackager )
				)
				( attribute "CDS_LOCATION" "C1E13"
					( Origin gPackager )
				)
				( attribute "CDS_SEC" "1"
					( Origin gPackager )
				)
				( attribute "LOCATION" "C1E13"
					( Origin gFrontEnd )
				)
				( attribute "MATERIAL" "X6S"
					( Origin gFrontEnd )
				)
				( attribute "PACK_TYPE" "0402"
					( Origin gFrontEnd )
				)
				( attribute "PART_NUMBER" "D97712-011"
					( Origin gFrontEnd )
				)
				( attribute "PHYS_PAGE" "207"
					( Origin gFrontEnd )
				)
				( attribute "ROOM" "PVCCIN_CPU1_PWR_VR"
					( Origin gFrontEnd )
				)
				( attribute "ROT" "0"
					( Origin gFrontEnd )
				)
				( attribute "SEC" "1"
					( Origin gFrontEnd )
				)
				( attribute "SEC_TYPE" "0402"
					( Origin gFrontEnd )
				)
				( attribute "TOLERANCE" "10%"
					( Origin gFrontEnd )
				)
				( attribute "VALUE" "1.0UF"
					( Origin gFrontEnd )
				)
				( attribute "VER" "1"
					( Origin gFrontEnd )
				)
				( attribute "VOLTAGE" "16V"
					( Units "uVoltage" "V" 1.000000)
					( Origin gFrontEnd )
				)
				( attribute "XY" "(-6575,4100)"
					( Origin gFrontEnd )
				)
				( attribute "CHIPS_PART_NAME" "CAP"
					( Origin gPackager )
				)
				( attribute "CDS_PART_NAME" "CAP_0402-1.0UF,16V,10%,X6S,D97A"
					( Origin gPackager )
				)
				( objectStatus "C1E13" )
				( pin "a"
					( attribute "PN" "1"
						( Origin gPackager )
					)
					( objectStatus "C1E13.1" )
				)
				( pin "b"
					( attribute "PN" "2"
						( Origin gPackager )
					)
					( objectStatus "C1E13.2" )
				)
			)
			( gate "@baseboard_fab2_lib.baseboard_fab2(sch_1):page207_i36"
				( attribute "CDS_LIB" "mstr_discrete"
					( Origin gPackager )
				)
				( attribute "CDS_LOCATION" "C1E25"
					( Origin gPackager )
				)
				( attribute "CDS_SEC" "1"
					( Origin gPackager )
				)
				( attribute "LOCATION" "C1E25"
					( Origin gFrontEnd )
				)
				( attribute "MATERIAL" "X7R"
					( Origin gFrontEnd )
				)
				( attribute "PACK_TYPE" "0402"
					( Origin gFrontEnd )
				)
				( attribute "PART_NUMBER" "A36096-155"
					( Origin gFrontEnd )
				)
				( attribute "PHYS_PAGE" "207"
					( Origin gFrontEnd )
				)
				( attribute "ROOM" "PVCCIN_CPU1_PWR_VR"
					( Origin gFrontEnd )
				)
				( attribute "ROT" "0"
					( Origin gFrontEnd )
				)
				( attribute "SEC" "1"
					( Origin gFrontEnd )
				)
				( attribute "SEC_TYPE" "0402"
					( Origin gFrontEnd )
				)
				( attribute "TOLERANCE" "10%"
					( Origin gFrontEnd )
				)
				( attribute "VALUE" "0.22UF"
					( Origin gFrontEnd )
				)
				( attribute "VER" "1"
					( Origin gFrontEnd )
				)
				( attribute "VOLTAGE" "16V"
					( Units "uVoltage" "V" 1.000000)
					( Origin gFrontEnd )
				)
				( attribute "XY" "(-5075,1550)"
					( Origin gFrontEnd )
				)
				( attribute "CHIPS_PART_NAME" "CAP"
					( Origin gPackager )
				)
				( attribute "CDS_PART_NAME" "CAP_0402-0.22UF,16V,10%,X7R,A3A"
					( Origin gPackager )
				)
				( objectStatus "C1E25" )
				( pin "a"
					( attribute "PN" "1"
						( Origin gPackager )
					)
					( objectStatus "C1E25.1" )
				)
				( pin "b"
					( attribute "PN" "2"
						( Origin gPackager )
					)
					( objectStatus "C1E25.2" )
				)
			)
			( gate "@baseboard_fab2_lib.baseboard_fab2(sch_1):page207_i37"
				( attribute "CDS_LIB" "dev_discrete"
					( Origin gPackager )
				)
				( attribute "CDS_LOCATION" "C1E23"
					( Origin gPackager )
				)
				( attribute "CDS_SEC" "1"
					( Origin gPackager )
				)
				( attribute "LOCATION" "C1E23"
					( Origin gFrontEnd )
				)
				( attribute "MATERIAL" "X6S"
					( Origin gFrontEnd )
				)
				( attribute "PACK_TYPE" "0402V"
					( Origin gFrontEnd )
				)
				( attribute "PART_NUMBER" "D97712-004"
					( Origin gFrontEnd )
				)
				( attribute "PHYS_PAGE" "207"
					( Origin gFrontEnd )
				)
				( attribute "ROOM" "PVCCIN_CPU1_PWR_VR"
					( Origin gFrontEnd )
				)
				( attribute "ROT" "2"
					( Origin gFrontEnd )
				)
				( attribute "SEC" "1"
					( Origin gFrontEnd )
				)
				( attribute "SEC_TYPE" "0402V"
					( Origin gFrontEnd )
				)
				( attribute "TOLERANCE" "10%"
					( Origin gFrontEnd )
				)
				( attribute "VALUE" "1.0UF"
					( Origin gFrontEnd )
				)
				( attribute "VER" "1"
					( Origin gFrontEnd )
				)
				( attribute "VOLTAGE" "6.3V"
					( Units "uVoltage" "V" 1.000000)
					( Origin gFrontEnd )
				)
				( attribute "XY" "(-5250,1550)"
					( Origin gFrontEnd )
				)
				( attribute "CHIPS_PART_NAME" "CAP_A"
					( Origin gPackager )
				)
				( attribute "CDS_PART_NAME" "CAP_A_0402V-1.0UF,6.3V,10%,X6SA"
					( Origin gPackager )
				)
				( objectStatus "C1E23" )
				( pin "a"
					( attribute "PN" "1"
						( Origin gPackager )
					)
					( objectStatus "C1E23.1" )
				)
				( pin "b"
					( attribute "PN" "2"
						( Origin gPackager )
					)
					( objectStatus "C1E23.2" )
				)
			)
			( gate "@baseboard_fab2_lib.baseboard_fab2(sch_1):page207_i38"
				( attribute "CDS_LIB" "mstr_discrete"
					( Origin gPackager )
				)
				( attribute "CDS_LOCATION" "C1D36"
					( Origin gPackager )
				)
				( attribute "CDS_SEC" "1"
					( Origin gPackager )
				)
				( attribute "LOCATION" "C1D36"
					( Origin gFrontEnd )
				)
				( attribute "MATERIAL" "X7R"
					( Origin gFrontEnd )
				)
				( attribute "NO_XNET_CONNECTION" "1"
					( Origin gFrontEnd )
				)
				( attribute "PACK_TYPE" "0402"
					( Origin gFrontEnd )
				)
				( attribute "PART_NUMBER" "A36096-104"
					( Origin gFrontEnd )
				)
				( attribute "PHYS_PAGE" "207"
					( Origin gFrontEnd )
				)
				( attribute "ROOM" "PVCCIN_CPU1_PWR_VR"
					( Origin gFrontEnd )
				)
				( attribute "ROT" "2"
					( Origin gFrontEnd )
				)
				( attribute "SEC" "1"
					( Origin gFrontEnd )
				)
				( attribute "SEC_TYPE" "0402"
					( Origin gFrontEnd )
				)
				( attribute "SPOF" "TRUE"
					( Origin gFrontEnd )
				)
				( attribute "TOLERANCE" "10%"
					( Origin gFrontEnd )
				)
				( attribute "VALUE" "0.220UF"
					( Origin gFrontEnd )
				)
				( attribute "VER" "1"
					( Origin gFrontEnd )
				)
				( attribute "VOLTAGE" "16V"
					( Units "uVoltage" "V" 1.000000)
					( Origin gFrontEnd )
				)
				( attribute "XY" "(-5875,850)"
					( Origin gFrontEnd )
				)
				( attribute "CHIPS_PART_NAME" "CAP"
					( Origin gPackager )
				)
				( attribute "CDS_PART_NAME" "CAP_0402-0.220UF,16V,10%,X7R,AA"
					( Origin gPackager )
				)
				( objectStatus "C1D36" )
				( pin "a"
					( attribute "PN" "1"
						( Origin gPackager )
					)
					( objectStatus "C1D36.1" )
				)
				( pin "b"
					( attribute "PN" "2"
						( Origin gPackager )
					)
					( objectStatus "C1D36.2" )
				)
			)
			( gate "@baseboard_fab2_lib.baseboard_fab2(sch_1):page207_i39"
				( attribute "CDS_LIB" "mstr_discrete"
					( Origin gPackager )
				)
				( attribute "CDS_LOCATION" "R9R11"
					( Origin gPackager )
				)
				( attribute "CDS_SEC" "1"
					( Origin gPackager )
				)
				( attribute "LOCATION" "R9R11"
					( Origin gFrontEnd )
				)
				( attribute "MATERIAL" "CHIP"
					( Origin gFrontEnd )
				)
				( attribute "PACK_TYPE" "0402"
					( Origin gFrontEnd )
				)
				( attribute "PART_NUMBER" "G21796-090"
					( Origin gFrontEnd )
				)
				( attribute "PHYS_PAGE" "207"
					( Origin gFrontEnd )
				)
				( attribute "ROOM" "PVCCIN_CPU1_PWR_VR"
					( Origin gFrontEnd )
				)
				( attribute "ROT" "0"
					( Origin gFrontEnd )
				)
				( attribute "SEC" "1"
					( Origin gFrontEnd )
				)
				( attribute "SEC_TYPE" "0402"
					( Origin gFrontEnd )
				)
				( attribute "TOLERANCE" "1%"
					( Origin gFrontEnd )
				)
				( attribute "VALUE" "1.0"
					( Origin gFrontEnd )
				)
				( attribute "VER" "1"
					( Origin gFrontEnd )
				)
				( attribute "WATTAGE" "1/16W"
					( Origin gFrontEnd )
				)
				( attribute "XY" "(-5625,2000)"
					( Origin gFrontEnd )
				)
				( attribute "CHIPS_PART_NAME" "RES"
					( Origin gPackager )
				)
				( attribute "CDS_PART_NAME" "RES_0402-1.0,1%,1/16W,CHIP,G21A"
					( Origin gPackager )
				)
				( objectStatus "R9R11" )
				( pin "a"
					( attribute "PN" "1"
						( Origin gPackager )
					)
					( objectStatus "R9R11.1" )
				)
				( pin "b"
					( attribute "PN" "2"
						( Origin gPackager )
					)
					( objectStatus "R9R11.2" )
				)
			)
			( gate "@baseboard_fab2_lib.baseboard_fab2(sch_1):page207_i40"
				( attribute "CDS_LIB" "mstr_discrete"
					( Origin gPackager )
				)
				( attribute "CDS_LOCATION" "C1E24"
					( Origin gPackager )
				)
				( attribute "CDS_SEC" "1"
					( Origin gPackager )
				)
				( attribute "LOCATION" "C1E24"
					( Origin gFrontEnd )
				)
				( attribute "MATERIAL" "X6S"
					( Origin gFrontEnd )
				)
				( attribute "PACK_TYPE" "0402"
					( Origin gFrontEnd )
				)
				( attribute "PART_NUMBER" "D97712-011"
					( Origin gFrontEnd )
				)
				( attribute "PHYS_PAGE" "207"
					( Origin gFrontEnd )
				)
				( attribute "ROOM" "PVCCIN_CPU1_PWR_VR"
					( Origin gFrontEnd )
				)
				( attribute "ROT" "0"
					( Origin gFrontEnd )
				)
				( attribute "SEC" "1"
					( Origin gFrontEnd )
				)
				( attribute "SEC_TYPE" "0402"
					( Origin gFrontEnd )
				)
				( attribute "TOLERANCE" "10%"
					( Origin gFrontEnd )
				)
				( attribute "VALUE" "1.0UF"
					( Origin gFrontEnd )
				)
				( attribute "VER" "1"
					( Origin gFrontEnd )
				)
				( attribute "VOLTAGE" "16V"
					( Units "uVoltage" "V" 1.000000)
					( Origin gFrontEnd )
				)
				( attribute "XY" "(-5850,1500)"
					( Origin gFrontEnd )
				)
				( attribute "CHIPS_PART_NAME" "CAP"
					( Origin gPackager )
				)
				( attribute "CDS_PART_NAME" "CAP_0402-1.0UF,16V,10%,X6S,D97A"
					( Origin gPackager )
				)
				( objectStatus "C1E24" )
				( pin "a"
					( attribute "PN" "1"
						( Origin gPackager )
					)
					( objectStatus "C1E24.1" )
				)
				( pin "b"
					( attribute "PN" "2"
						( Origin gPackager )
					)
					( objectStatus "C1E24.2" )
				)
			)
			( gate "@baseboard_fab2_lib.baseboard_fab2(sch_1):page207_i41"
				( attribute "CDS_LIB" "dev_discrete"
					( Origin gPackager )
				)
				( attribute "CDS_LOCATION" "C1D34"
					( Origin gPackager )
				)
				( attribute "CDS_SEC" "1"
					( Origin gPackager )
				)
				( attribute "LOCATION" "C1D34"
					( Origin gFrontEnd )
				)
				( attribute "MATERIAL" "X7R"
					( Origin gFrontEnd )
				)
				( attribute "PACK_TYPE" "0402V"
					( Origin gFrontEnd )
				)
				( attribute "PART_NUMBER" "A36096-030"
					( Origin gFrontEnd )
				)
				( attribute "PHYS_PAGE" "207"
					( Origin gFrontEnd )
				)
				( attribute "ROOM" "PVCCIN_CPU1_PWR_VR"
					( Origin gFrontEnd )
				)
				( attribute "ROT" "0"
					( Origin gFrontEnd )
				)
				( attribute "SEC" "1"
					( Origin gFrontEnd )
				)
				( attribute "SEC_TYPE" "0402V"
					( Origin gFrontEnd )
				)
				( attribute "TOLERANCE" "10%"
					( Origin gFrontEnd )
				)
				( attribute "VALUE" "0.1UF"
					( Origin gFrontEnd )
				)
				( attribute "VER" "1"
					( Origin gFrontEnd )
				)
				( attribute "VOLTAGE" "16V"
					( Units "uVoltage" "V" 1.000000)
					( Origin gFrontEnd )
				)
				( attribute "XY" "(-6175,1500)"
					( Origin gFrontEnd )
				)
				( attribute "CHIPS_PART_NAME" "CAP_A"
					( Origin gPackager )
				)
				( attribute "CDS_PART_NAME" "CAP_A_0402V-0.1UF,16V,10%,X7R,A"
					( Origin gPackager )
				)
				( objectStatus "C1D34" )
				( pin "a"
					( attribute "PN" "1"
						( Origin gPackager )
					)
					( objectStatus "C1D34.1" )
				)
				( pin "b"
					( attribute "PN" "2"
						( Origin gPackager )
					)
					( objectStatus "C1D34.2" )
				)
			)
			( gate "@baseboard_fab2_lib.baseboard_fab2(sch_1):page207_i42"
				( attribute "CDS_LIB" "mstr_discrete"
					( Origin gPackager )
				)
				( attribute "CDS_LOCATION" "C1D35"
					( Origin gPackager )
				)
				( attribute "CDS_SEC" "1"
					( Origin gPackager )
				)
				( attribute "LOCATION" "C1D35"
					( Origin gFrontEnd )
				)
				( attribute "MATERIAL" "X6S"
					( Origin gFrontEnd )
				)
				( attribute "PACK_TYPE" "0402"
					( Origin gFrontEnd )
				)
				( attribute "PART_NUMBER" "D97712-011"
					( Origin gFrontEnd )
				)
				( attribute "PHYS_PAGE" "207"
					( Origin gFrontEnd )
				)
				( attribute "ROOM" "PVCCIN_CPU1_PWR_VR"
					( Origin gFrontEnd )
				)
				( attribute "ROT" "0"
					( Origin gFrontEnd )
				)
				( attribute "SEC" "1"
					( Origin gFrontEnd )
				)
				( attribute "SEC_TYPE" "0402"
					( Origin gFrontEnd )
				)
				( attribute "TOLERANCE" "10%"
					( Origin gFrontEnd )
				)
				( attribute "VALUE" "1.0UF"
					( Origin gFrontEnd )
				)
				( attribute "VER" "1"
					( Origin gFrontEnd )
				)
				( attribute "VOLTAGE" "16V"
					( Units "uVoltage" "V" 1.000000)
					( Origin gFrontEnd )
				)
				( attribute "XY" "(-6450,1525)"
					( Origin gFrontEnd )
				)
				( attribute "CHIPS_PART_NAME" "CAP"
					( Origin gPackager )
				)
				( attribute "CDS_PART_NAME" "CAP_0402-1.0UF,16V,10%,X6S,D97A"
					( Origin gPackager )
				)
				( objectStatus "C1D35" )
				( pin "a"
					( attribute "PN" "1"
						( Origin gPackager )
					)
					( objectStatus "C1D35.1" )
				)
				( pin "b"
					( attribute "PN" "2"
						( Origin gPackager )
					)
					( objectStatus "C1D35.2" )
				)
			)
			( gate "@baseboard_fab2_lib.baseboard_fab2(sch_1):page207_i43"
				( attribute "CDS_LIB" "mstr_discrete"
					( Origin gPackager )
				)
				( attribute "CDS_LOCATION" "C9R7"
					( Origin gPackager )
				)
				( attribute "CDS_SEC" "1"
					( Origin gPackager )
				)
				( attribute "LOCATION" "C9R7"
					( Origin gFrontEnd )
				)
				( attribute "MATERIAL" "X6S"
					( Origin gFrontEnd )
				)
				( attribute "PACK_TYPE" "0805"
					( Origin gFrontEnd )
				)
				( attribute "PART_NUMBER" "C95333-007"
					( Origin gFrontEnd )
				)
				( attribute "PHYS_PAGE" "207"
					( Origin gFrontEnd )
				)
				( attribute "ROOM" "PVCCIN_CPU1_PWR_VR"
					( Origin gFrontEnd )
				)
				( attribute "ROT" "0"
					( Origin gFrontEnd )
				)
				( attribute "SEC" "1"
					( Origin gFrontEnd )
				)
				( attribute "SEC_TYPE" "0805"
					( Origin gFrontEnd )
				)
				( attribute "TOLERANCE" "10%"
					( Origin gFrontEnd )
				)
				( attribute "VALUE" "10UF"
					( Origin gFrontEnd )
				)
				( attribute "VER" "1"
					( Origin gFrontEnd )
				)
				( attribute "VOLTAGE" "16V"
					( Units "uVoltage" "V" 1.000000)
					( Origin gFrontEnd )
				)
				( attribute "XY" "(-6875,4100)"
					( Origin gFrontEnd )
				)
				( attribute "CHIPS_PART_NAME" "CAP"
					( Origin gPackager )
				)
				( attribute "CDS_PART_NAME" "CAP_0805-10UF,16V,10%,X6S,C953A"
					( Origin gPackager )
				)
				( objectStatus "C9R7" )
				( pin "a"
					( attribute "PN" "1"
						( Origin gPackager )
					)
					( objectStatus "C9R7.1" )
				)
				( pin "b"
					( attribute "PN" "2"
						( Origin gPackager )
					)
					( objectStatus "C9R7.2" )
				)
			)
			( gate "@baseboard_fab2_lib.baseboard_fab2(sch_1):page207_i44"
				( attribute "CDS_LIB" "mstr_discrete"
					( Origin gPackager )
				)
				( attribute "CDS_LOCATION" "C9R10"
					( Origin gPackager )
				)
				( attribute "CDS_SEC" "1"
					( Origin gPackager )
				)
				( attribute "LOCATION" "C9R10"
					( Origin gFrontEnd )
				)
				( attribute "MATERIAL" "X6S"
					( Origin gFrontEnd )
				)
				( attribute "PACK_TYPE" "0805"
					( Origin gFrontEnd )
				)
				( attribute "PART_NUMBER" "C95333-007"
					( Origin gFrontEnd )
				)
				( attribute "PHYS_PAGE" "207"
					( Origin gFrontEnd )
				)
				( attribute "ROOM" "PVCCIN_CPU1_PWR_VR"
					( Origin gFrontEnd )
				)
				( attribute "ROT" "0"
					( Origin gFrontEnd )
				)
				( attribute "SEC" "1"
					( Origin gFrontEnd )
				)
				( attribute "SEC_TYPE" "0805"
					( Origin gFrontEnd )
				)
				( attribute "TOLERANCE" "10%"
					( Origin gFrontEnd )
				)
				( attribute "VALUE" "10UF"
					( Origin gFrontEnd )
				)
				( attribute "VER" "1"
					( Origin gFrontEnd )
				)
				( attribute "VOLTAGE" "16V"
					( Units "uVoltage" "V" 1.000000)
					( Origin gFrontEnd )
				)
				( attribute "XY" "(-7175,4100)"
					( Origin gFrontEnd )
				)
				( attribute "CHIPS_PART_NAME" "CAP"
					( Origin gPackager )
				)
				( attribute "CDS_PART_NAME" "CAP_0805-10UF,16V,10%,X6S,C953A"
					( Origin gPackager )
				)
				( objectStatus "C9R10" )
				( pin "a"
					( attribute "PN" "1"
						( Origin gPackager )
					)
					( objectStatus "C9R10.1" )
				)
				( pin "b"
					( attribute "PN" "2"
						( Origin gPackager )
					)
					( objectStatus "C9R10.2" )
				)
			)
			( gate "@baseboard_fab2_lib.baseboard_fab2(sch_1):page207_i48"
				( attribute "CDS_LIB" "mstr_discrete"
					( Origin gPackager )
				)
				( attribute "CDS_LOCATION" "C9R11"
					( Origin gPackager )
				)
				( attribute "CDS_SEC" "1"
					( Origin gPackager )
				)
				( attribute "LOCATION" "C9R11"
					( Origin gFrontEnd )
				)
				( attribute "MATERIAL" "X6S"
					( Origin gFrontEnd )
				)
				( attribute "PACK_TYPE" "0805"
					( Origin gFrontEnd )
				)
				( attribute "PART_NUMBER" "C95333-007"
					( Origin gFrontEnd )
				)
				( attribute "PHYS_PAGE" "207"
					( Origin gFrontEnd )
				)
				( attribute "ROOM" "PVCCIN_CPU1_PWR_VR"
					( Origin gFrontEnd )
				)
				( attribute "ROT" "0"
					( Origin gFrontEnd )
				)
				( attribute "SEC" "1"
					( Origin gFrontEnd )
				)
				( attribute "SEC_TYPE" "0805"
					( Origin gFrontEnd )
				)
				( attribute "TOLERANCE" "10%"
					( Origin gFrontEnd )
				)
				( attribute "VALUE" "10UF"
					( Origin gFrontEnd )
				)
				( attribute "VER" "1"
					( Origin gFrontEnd )
				)
				( attribute "VOLTAGE" "16V"
					( Units "uVoltage" "V" 1.000000)
					( Origin gFrontEnd )
				)
				( attribute "XY" "(-7425,4100)"
					( Origin gFrontEnd )
				)
				( attribute "CHIPS_PART_NAME" "CAP"
					( Origin gPackager )
				)
				( attribute "CDS_PART_NAME" "CAP_0805-10UF,16V,10%,X6S,C953A"
					( Origin gPackager )
				)
				( objectStatus "C9R11" )
				( pin "a"
					( attribute "PN" "1"
						( Origin gPackager )
					)
					( objectStatus "C9R11.1" )
				)
				( pin "b"
					( attribute "PN" "2"
						( Origin gPackager )
					)
					( objectStatus "C9R11.2" )
				)
			)
			( gate "@baseboard_fab2_lib.baseboard_fab2(sch_1):page207_i50"
				( attribute "CDS_LIB" "mstr_discrete"
					( Origin gPackager )
				)
				( attribute "CDS_LOCATION" "C9P22"
					( Origin gPackager )
				)
				( attribute "CDS_SEC" "1"
					( Origin gPackager )
				)
				( attribute "LOCATION" "C9P22"
					( Origin gFrontEnd )
				)
				( attribute "MATERIAL" "X6S"
					( Origin gFrontEnd )
				)
				( attribute "PACK_TYPE" "0805"
					( Origin gFrontEnd )
				)
				( attribute "PART_NUMBER" "C95333-007"
					( Origin gFrontEnd )
				)
				( attribute "PHYS_PAGE" "207"
					( Origin gFrontEnd )
				)
				( attribute "ROOM" "PVCCIN_CPU1_PWR_VR"
					( Origin gFrontEnd )
				)
				( attribute "ROT" "0"
					( Origin gFrontEnd )
				)
				( attribute "SEC" "1"
					( Origin gFrontEnd )
				)
				( attribute "SEC_TYPE" "0805"
					( Origin gFrontEnd )
				)
				( attribute "TOLERANCE" "10%"
					( Origin gFrontEnd )
				)
				( attribute "VALUE" "10UF"
					( Origin gFrontEnd )
				)
				( attribute "VER" "1"
					( Origin gFrontEnd )
				)
				( attribute "VOLTAGE" "16V"
					( Units "uVoltage" "V" 1.000000)
					( Origin gFrontEnd )
				)
				( attribute "XY" "(-6800,1525)"
					( Origin gFrontEnd )
				)
				( attribute "CHIPS_PART_NAME" "CAP"
					( Origin gPackager )
				)
				( attribute "CDS_PART_NAME" "CAP_0805-10UF,16V,10%,X6S,C953A"
					( Origin gPackager )
				)
				( objectStatus "C9P22" )
				( pin "a"
					( attribute "PN" "1"
						( Origin gPackager )
					)
					( objectStatus "C9P22.1" )
				)
				( pin "b"
					( attribute "PN" "2"
						( Origin gPackager )
					)
					( objectStatus "C9P22.2" )
				)
			)
			( gate "@baseboard_fab2_lib.baseboard_fab2(sch_1):page207_i51"
				( attribute "CDS_LIB" "mstr_discrete"
					( Origin gPackager )
				)
				( attribute "CDS_LOCATION" "C9P25"
					( Origin gPackager )
				)
				( attribute "CDS_SEC" "1"
					( Origin gPackager )
				)
				( attribute "LOCATION" "C9P25"
					( Origin gFrontEnd )
				)
				( attribute "MATERIAL" "X6S"
					( Origin gFrontEnd )
				)
				( attribute "PACK_TYPE" "0805"
					( Origin gFrontEnd )
				)
				( attribute "PART_NUMBER" "C95333-007"
					( Origin gFrontEnd )
				)
				( attribute "PHYS_PAGE" "207"
					( Origin gFrontEnd )
				)
				( attribute "ROOM" "PVCCIN_CPU1_PWR_VR"
					( Origin gFrontEnd )
				)
				( attribute "ROT" "0"
					( Origin gFrontEnd )
				)
				( attribute "SEC" "1"
					( Origin gFrontEnd )
				)
				( attribute "SEC_TYPE" "0805"
					( Origin gFrontEnd )
				)
				( attribute "TOLERANCE" "10%"
					( Origin gFrontEnd )
				)
				( attribute "VALUE" "10UF"
					( Origin gFrontEnd )
				)
				( attribute "VER" "1"
					( Origin gFrontEnd )
				)
				( attribute "VOLTAGE" "16V"
					( Units "uVoltage" "V" 1.000000)
					( Origin gFrontEnd )
				)
				( attribute "XY" "(-7125,1525)"
					( Origin gFrontEnd )
				)
				( attribute "CHIPS_PART_NAME" "CAP"
					( Origin gPackager )
				)
				( attribute "CDS_PART_NAME" "CAP_0805-10UF,16V,10%,X6S,C953A"
					( Origin gPackager )
				)
				( objectStatus "C9P25" )
				( pin "a"
					( attribute "PN" "1"
						( Origin gPackager )
					)
					( objectStatus "C9P25.1" )
				)
				( pin "b"
					( attribute "PN" "2"
						( Origin gPackager )
					)
					( objectStatus "C9P25.2" )
				)
			)
			( gate "@baseboard_fab2_lib.baseboard_fab2(sch_1):page207_i54"
				( attribute "CDS_LIB" "mstr_discrete"
					( Origin gPackager )
				)
				( attribute "CDS_LOCATION" "C9P26"
					( Origin gPackager )
				)
				( attribute "CDS_SEC" "1"
					( Origin gPackager )
				)
				( attribute "LOCATION" "C9P26"
					( Origin gFrontEnd )
				)
				( attribute "MATERIAL" "X6S"
					( Origin gFrontEnd )
				)
				( attribute "PACK_TYPE" "0805"
					( Origin gFrontEnd )
				)
				( attribute "PART_NUMBER" "C95333-007"
					( Origin gFrontEnd )
				)
				( attribute "PHYS_PAGE" "207"
					( Origin gFrontEnd )
				)
				( attribute "ROOM" "PVCCIN_CPU1_PWR_VR"
					( Origin gFrontEnd )
				)
				( attribute "ROT" "0"
					( Origin gFrontEnd )
				)
				( attribute "SEC" "1"
					( Origin gFrontEnd )
				)
				( attribute "SEC_TYPE" "0805"
					( Origin gFrontEnd )
				)
				( attribute "TOLERANCE" "10%"
					( Origin gFrontEnd )
				)
				( attribute "VALUE" "10UF"
					( Origin gFrontEnd )
				)
				( attribute "VER" "1"
					( Origin gFrontEnd )
				)
				( attribute "VOLTAGE" "16V"
					( Units "uVoltage" "V" 1.000000)
					( Origin gFrontEnd )
				)
				( attribute "XY" "(-7450,1525)"
					( Origin gFrontEnd )
				)
				( attribute "CHIPS_PART_NAME" "CAP"
					( Origin gPackager )
				)
				( attribute "CDS_PART_NAME" "CAP_0805-10UF,16V,10%,X6S,C953A"
					( Origin gPackager )
				)
				( objectStatus "C9P26" )
				( pin "a"
					( attribute "PN" "1"
						( Origin gPackager )
					)
					( objectStatus "C9P26.1" )
				)
				( pin "b"
					( attribute "PN" "2"
						( Origin gPackager )
					)
					( objectStatus "C9P26.2" )
				)
			)
			( gate "@baseboard_fab2_lib.baseboard_fab2(sch_1):page207_i58"
				( attribute "CDS_LIB" "dev_discrete"
					( Origin gPackager )
				)
				( attribute "CDS_LOCATION" "C1E9"
					( Origin gPackager )
				)
				( attribute "CDS_SEC" "1"
					( Origin gPackager )
				)
				( attribute "LOCATION" "C1E9"
					( Origin gFrontEnd )
				)
				( attribute "MATERIAL" "X6S"
					( Origin gFrontEnd )
				)
				( attribute "PACK_TYPE" "0603V"
					( Origin gFrontEnd )
				)
				( attribute "PART_NUMBER" "E15431-004"
					( Origin gFrontEnd )
				)
				( attribute "PHYS_PAGE" "207"
					( Origin gFrontEnd )
				)
				( attribute "ROT" "0"
					( Origin gFrontEnd )
				)
				( attribute "SEC" "1"
					( Origin gFrontEnd )
				)
				( attribute "SEC_TYPE" "0603V"
					( Origin gFrontEnd )
				)
				( attribute "TOLERANCE" "20%"
					( Origin gFrontEnd )
				)
				( attribute "VALUE" "22.0UF"
					( Origin gFrontEnd )
				)
				( attribute "VER" "1"
					( Origin gFrontEnd )
				)
				( attribute "VOLTAGE" "4V"
					( Units "uVoltage" "V" 1.000000)
					( Origin gFrontEnd )
				)
				( attribute "XY" "(-975,3350)"
					( Origin gFrontEnd )
				)
				( attribute "CHIPS_PART_NAME" "CAP_A"
					( Origin gPackager )
				)
				( attribute "CDS_PART_NAME" "CAP_A_0603V-22.0UF,4V,20%,X6S,A"
					( Origin gPackager )
				)
				( objectStatus "C1E9" )
				( pin "a"
					( attribute "PN" "1"
						( Origin gPackager )
					)
					( objectStatus "C1E9.1" )
				)
				( pin "b"
					( attribute "PN" "2"
						( Origin gPackager )
					)
					( objectStatus "C1E9.2" )
				)
			)
			( gate "@baseboard_fab2_lib.baseboard_fab2(sch_1):page207_i59"
				( attribute "CDS_LIB" "dev_discrete"
					( Origin gPackager )
				)
				( attribute "CDS_LOCATION" "C9P3"
					( Origin gPackager )
				)
				( attribute "CDS_SEC" "1"
					( Origin gPackager )
				)
				( attribute "LOCATION" "C9P3"
					( Origin gFrontEnd )
				)
				( attribute "MATERIAL" "X6S"
					( Origin gFrontEnd )
				)
				( attribute "PACK_TYPE" "0603V"
					( Origin gFrontEnd )
				)
				( attribute "PART_NUMBER" "E15431-004"
					( Origin gFrontEnd )
				)
				( attribute "PHYS_PAGE" "207"
					( Origin gFrontEnd )
				)
				( attribute "ROT" "0"
					( Origin gFrontEnd )
				)
				( attribute "SEC" "1"
					( Origin gFrontEnd )
				)
				( attribute "SEC_TYPE" "0603V"
					( Origin gFrontEnd )
				)
				( attribute "TOLERANCE" "20%"
					( Origin gFrontEnd )
				)
				( attribute "VALUE" "22.0UF"
					( Origin gFrontEnd )
				)
				( attribute "VER" "1"
					( Origin gFrontEnd )
				)
				( attribute "VOLTAGE" "4V"
					( Units "uVoltage" "V" 1.000000)
					( Origin gFrontEnd )
				)
				( attribute "XY" "(-1075,775)"
					( Origin gFrontEnd )
				)
				( attribute "CHIPS_PART_NAME" "CAP_A"
					( Origin gPackager )
				)
				( attribute "CDS_PART_NAME" "CAP_A_0603V-22.0UF,4V,20%,X6S,A"
					( Origin gPackager )
				)
				( objectStatus "C9P3" )
				( pin "a"
					( attribute "PN" "1"
						( Origin gPackager )
					)
					( objectStatus "C9P3.1" )
				)
				( pin "b"
					( attribute "PN" "2"
						( Origin gPackager )
					)
					( objectStatus "C9P3.2" )
				)
			)
			( gate "@baseboard_fab2_lib.baseboard_fab2(sch_1):page207_i67"
				( attribute "CDS_LIB" "mstr_discrete"
					( Origin gPackager )
				)
				( attribute "CDS_LOCATION" "R1E13"
					( Origin gPackager )
				)
				( attribute "CDS_SEC" "1"
					( Origin gPackager )
				)
				( attribute "LOCATION" "R1E13"
					( Origin gFrontEnd )
				)
				( attribute "MATERIAL" "EMPTY"
					( Origin gFrontEnd )
				)
				( attribute "PACK_TYPE" "0402"
					( Origin gFrontEnd )
				)
				( attribute "PART_NUMBER" "G21796-187"
					( Origin gFrontEnd )
				)
				( attribute "PHYS_PAGE" "207"
					( Origin gFrontEnd )
				)
				( attribute "ROT" "0"
					( Origin gFrontEnd )
				)
				( attribute "SEC" "1"
					( Origin gPackager )
				)
				( attribute "TOLERANCE" "1%"
					( Origin gFrontEnd )
				)
				( attribute "VALUE" "68.1K"
					( Origin gFrontEnd )
				)
				( attribute "VER" "2"
					( Origin gFrontEnd )
				)
				( attribute "WATTAGE" "1/16W"
					( Origin gFrontEnd )
				)
				( attribute "XY" "(-1025,1400)"
					( Origin gFrontEnd )
				)
				( attribute "CHIPS_PART_NAME" "RES"
					( Origin gPackager )
				)
				( attribute "CDS_PART_NAME" "RES_0402-68.1K,1%,1/16W,EMPTY,A"
					( Origin gPackager )
				)
				( objectStatus "R1E13" )
				( pin "a"
					( attribute "PN" "1"
						( Origin gPackager )
					)
					( objectStatus "R1E13.1" )
				)
				( pin "b"
					( attribute "PN" "2"
						( Origin gPackager )
					)
					( objectStatus "R1E13.2" )
				)
			)
			( gate "@baseboard_fab2_lib.baseboard_fab2(sch_1):page207_i68"
				( attribute "CDS_LIB" "mstr_discrete"
					( Origin gPackager )
				)
				( attribute "CDS_LOCATION" "R1E14"
					( Origin gPackager )
				)
				( attribute "CDS_SEC" "1"
					( Origin gPackager )
				)
				( attribute "LOCATION" "R1E14"
					( Origin gFrontEnd )
				)
				( attribute "MATERIAL" "EMPTY"
					( Origin gFrontEnd )
				)
				( attribute "PACK_TYPE" "0402"
					( Origin gFrontEnd )
				)
				( attribute "PART_NUMBER" "G21796-187"
					( Origin gFrontEnd )
				)
				( attribute "PHYS_PAGE" "207"
					( Origin gFrontEnd )
				)
				( attribute "ROT" "0"
					( Origin gFrontEnd )
				)
				( attribute "SEC" "1"
					( Origin gPackager )
				)
				( attribute "TOLERANCE" "1%"
					( Origin gFrontEnd )
				)
				( attribute "VALUE" "68.1K"
					( Origin gFrontEnd )
				)
				( attribute "VER" "2"
					( Origin gFrontEnd )
				)
				( attribute "WATTAGE" "1/16W"
					( Origin gFrontEnd )
				)
				( attribute "XY" "(-550,4025)"
					( Origin gFrontEnd )
				)
				( attribute "CHIPS_PART_NAME" "RES"
					( Origin gPackager )
				)
				( attribute "CDS_PART_NAME" "RES_0402-68.1K,1%,1/16W,EMPTY,A"
					( Origin gPackager )
				)
				( objectStatus "R1E14" )
				( pin "a"
					( attribute "PN" "1"
						( Origin gPackager )
					)
					( objectStatus "R1E14.1" )
				)
				( pin "b"
					( attribute "PN" "2"
						( Origin gPackager )
					)
					( objectStatus "R1E14.2" )
				)
			)
			( gate "@baseboard_fab2_lib.baseboard_fab2(sch_1):page208_i7"
				( attribute "BOM_COST" "PROC_VRD_VCCIN_CPU0"
					( Origin gFrontEnd )
				)
				( attribute "CDS_LIB" "mstr_discrete"
					( Origin gPackager )
				)
				( attribute "CDS_LOCATION" "R1E3"
					( Origin gPackager )
				)
				( attribute "CDS_SEC" "1"
					( Origin gPackager )
				)
				( attribute "LOCATION" "R1E3"
					( Origin gFrontEnd )
				)
				( attribute "MATERIAL" "CHIP"
					( Origin gFrontEnd )
				)
				( attribute "PACK_TYPE" "0603"
					( Origin gFrontEnd )
				)
				( attribute "PART_NUMBER" "G22026-038"
					( Origin gFrontEnd )
				)
				( attribute "PHYS_PAGE" "208"
					( Origin gFrontEnd )
				)
				( attribute "ROOM" "PVCCIN_CPU1_DECAP_VR"
					( Origin gFrontEnd )
				)
				( attribute "ROT" "0"
					( Origin gFrontEnd )
				)
				( attribute "SEC" "1"
					( Origin gFrontEnd )
				)
				( attribute "SEC_TYPE" "0603"
					( Origin gFrontEnd )
				)
				( attribute "TOLERANCE" "1%"
					( Origin gFrontEnd )
				)
				( attribute "VALUE" "100.0"
					( Origin gFrontEnd )
				)
				( attribute "VER" "2"
					( Origin gFrontEnd )
				)
				( attribute "WATTAGE" "1/10W"
					( Origin gFrontEnd )
				)
				( attribute "XY" "(-1000,2575)"
					( Origin gFrontEnd )
				)
				( attribute "CHIPS_PART_NAME" "RES"
					( Origin gPackager )
				)
				( attribute "CDS_PART_NAME" "RES_0603-100.0,1%,1/10W,CHIP,GA"
					( Origin gPackager )
				)
				( objectStatus "R1E3" )
				( pin "a"
					( attribute "PN" "1"
						( Origin gPackager )
					)
					( objectStatus "R1E3.1" )
				)
				( pin "b"
					( attribute "PN" "2"
						( Origin gPackager )
					)
					( objectStatus "R1E3.2" )
				)
			)
			( gate "@baseboard_fab2_lib.baseboard_fab2(sch_1):page208_i9"
				( attribute "BOM_COST" "PROC_VRD_VCCIN_CPU0"
					( Origin gFrontEnd )
				)
				( attribute "CDS_LIB" "dev_discrete"
					( Origin gPackager )
				)
				( attribute "CDS_LOCATION" "C1D14"
					( Origin gPackager )
				)
				( attribute "CDS_SEC" "1"
					( Origin gPackager )
				)
				( attribute "LOCATION" "C1D14"
					( Origin gFrontEnd )
				)
				( attribute "MATERIAL" "X6S"
					( Origin gFrontEnd )
				)
				( attribute "PACK_TYPE" "0603V"
					( Origin gFrontEnd )
				)
				( attribute "PART_NUMBER" "E15431-004"
					( Origin gFrontEnd )
				)
				( attribute "PHYS_PAGE" "208"
					( Origin gFrontEnd )
				)
				( attribute "ROOM" "PVCCIN_CPU1_PWR_VR"
					( Origin gFrontEnd )
				)
				( attribute "ROT" "0"
					( Origin gFrontEnd )
				)
				( attribute "SEC" "1"
					( Origin gFrontEnd )
				)
				( attribute "SEC_TYPE" "0603V"
					( Origin gFrontEnd )
				)
				( attribute "TOLERANCE" "20%"
					( Origin gFrontEnd )
				)
				( attribute "VALUE" "22.0UF"
					( Origin gFrontEnd )
				)
				( attribute "VER" "1"
					( Origin gFrontEnd )
				)
				( attribute "VOLTAGE" "4V"
					( Units "uVoltage" "V" 1.000000)
					( Origin gFrontEnd )
				)
				( attribute "XY" "(-825,3425)"
					( Origin gFrontEnd )
				)
				( attribute "CHIPS_PART_NAME" "CAP_A"
					( Origin gPackager )
				)
				( attribute "CDS_PART_NAME" "CAP_A_0603V-22.0UF,4V,20%,X6S,A"
					( Origin gPackager )
				)
				( objectStatus "C1D14" )
				( pin "a"
					( attribute "PN" "1"
						( Origin gPackager )
					)
					( objectStatus "C1D14.1" )
				)
				( pin "b"
					( attribute "PN" "2"
						( Origin gPackager )
					)
					( objectStatus "C1D14.2" )
				)
			)
			( gate "@baseboard_fab2_lib.baseboard_fab2(sch_1):page208_i11"
				( attribute "CDS_LIB" "mstr_discrete"
					( Origin gPackager )
				)
				( attribute "CDS_LOCATION" "L1D2"
					( Origin gPackager )
				)
				( attribute "CDS_SEC" "1"
					( Origin gPackager )
				)
				( attribute "LOCATION" "L1D2"
					( Origin gFrontEnd )
				)
				( attribute "MATERIAL" "IND"
					( Origin gFrontEnd )
				)
				( attribute "PACK_TYPE" "SM"
					( Origin gFrontEnd )
				)
				( attribute "PART_NUMBER" "D92183-034"
					( Origin gFrontEnd )
				)
				( attribute "PHYS_PAGE" "208"
					( Origin gFrontEnd )
				)
				( attribute "ROOM" "PVCCIN_CPU1_PWR_VR"
					( Origin gFrontEnd )
				)
				( attribute "ROT" "0"
					( Origin gFrontEnd )
				)
				( attribute "SEC" "1"
					( Origin gPackager )
				)
				( attribute "VALUE" "0.12UH"
					( Origin gFrontEnd )
				)
				( attribute "VER" "1"
					( Origin gFrontEnd )
				)
				( attribute "XY" "(-1475,3625)"
					( Origin gFrontEnd )
				)
				( attribute "CHIPS_PART_NAME" "INDUCTOR"
					( Origin gPackager )
				)
				( attribute "CDS_PART_NAME" "INDUCTOR_SM-0.12UH,IND,D92183-A"
					( Origin gPackager )
				)
				( objectStatus "L1D2" )
				( pin "ina"
					( attribute "PN" "1"
						( Origin gPackager )
					)
					( objectStatus "L1D2.1" )
				)
				( pin "inb"
					( attribute "PN" "2"
						( Origin gPackager )
					)
					( objectStatus "L1D2.2" )
				)
			)
			( gate "@baseboard_fab2_lib.baseboard_fab2(sch_1):page208_i12"
				( attribute "BOM_COST" "PROC_VRD_VCCIN_CPU0"
					( Origin gFrontEnd )
				)
				( attribute "CDS_LIB" "mstr_discrete"
					( Origin gPackager )
				)
				( attribute "CDS_LOCATION" "C9P8"
					( Origin gPackager )
				)
				( attribute "CDS_SEC" "1"
					( Origin gPackager )
				)
				( attribute "LOCATION" "C9P8"
					( Origin gFrontEnd )
				)
				( attribute "MATERIAL" "ALUM"
					( Origin gFrontEnd )
				)
				( attribute "PACK_TYPE" "3018"
					( Origin gFrontEnd )
				)
				( attribute "PART_NUMBER" "699013-049"
					( Origin gFrontEnd )
				)
				( attribute "PHYS_PAGE" "208"
					( Origin gFrontEnd )
				)
				( attribute "ROOM" "PVCCIN_CPU1_DECAP_VR"
					( Origin gFrontEnd )
				)
				( attribute "ROT" "0"
					( Origin gFrontEnd )
				)
				( attribute "SEC" "1"
					( Origin gFrontEnd )
				)
				( attribute "SEC_TYPE" "3018"
					( Origin gFrontEnd )
				)
				( attribute "TOLERANCE" "20%"
					( Origin gFrontEnd )
				)
				( attribute "VALUE" "470UF"
					( Origin gFrontEnd )
				)
				( attribute "VER" "1"
					( Origin gFrontEnd )
				)
				( attribute "VOLTAGE" "2.5V"
					( Units "uVoltage" "V" 1.000000)
					( Origin gFrontEnd )
				)
				( attribute "XY" "(-1450,2625)"
					( Origin gFrontEnd )
				)
				( attribute "CHIPS_PART_NAME" "CAPP"
					( Origin gPackager )
				)
				( attribute "CDS_PART_NAME" "CAPP_3018-470UF,2.5V,20%,ALUM,A"
					( Origin gPackager )
				)
				( objectStatus "C9P8" )
				( pin "a"
					( attribute "PN" "1"
						( Origin gPackager )
					)
					( objectStatus "C9P8.1" )
				)
				( pin "b"
					( attribute "PN" "2"
						( Origin gPackager )
					)
					( objectStatus "C9P8.2" )
				)
			)
			( gate "@baseboard_fab2_lib.baseboard_fab2(sch_1):page208_i14"
				( attribute "BOM_COST" "PROC_VRD_VCCIN_CPU0"
					( Origin gFrontEnd )
				)
				( attribute "CDS_LIB" "mstr_discrete"
					( Origin gPackager )
				)
				( attribute "CDS_LOCATION" "C9P5"
					( Origin gPackager )
				)
				( attribute "CDS_SEC" "1"
					( Origin gPackager )
				)
				( attribute "LOCATION" "C9P5"
					( Origin gFrontEnd )
				)
				( attribute "MATERIAL" "ALUM"
					( Origin gFrontEnd )
				)
				( attribute "PACK_TYPE" "3018"
					( Origin gFrontEnd )
				)
				( attribute "PART_NUMBER" "699013-049"
					( Origin gFrontEnd )
				)
				( attribute "PHYS_PAGE" "208"
					( Origin gFrontEnd )
				)
				( attribute "ROOM" "PVCCIN_CPU1_DECAP_VR"
					( Origin gFrontEnd )
				)
				( attribute "ROT" "0"
					( Origin gFrontEnd )
				)
				( attribute "SEC" "1"
					( Origin gFrontEnd )
				)
				( attribute "SEC_TYPE" "3018"
					( Origin gFrontEnd )
				)
				( attribute "TOLERANCE" "20%"
					( Origin gFrontEnd )
				)
				( attribute "VALUE" "470UF"
					( Origin gFrontEnd )
				)
				( attribute "VER" "1"
					( Origin gFrontEnd )
				)
				( attribute "VOLTAGE" "2.5V"
					( Units "uVoltage" "V" 1.000000)
					( Origin gFrontEnd )
				)
				( attribute "XY" "(-1925,2625)"
					( Origin gFrontEnd )
				)
				( attribute "CHIPS_PART_NAME" "CAPP"
					( Origin gPackager )
				)
				( attribute "CDS_PART_NAME" "CAPP_3018-470UF,2.5V,20%,ALUM,A"
					( Origin gPackager )
				)
				( objectStatus "C9P5" )
				( pin "a"
					( attribute "PN" "1"
						( Origin gPackager )
					)
					( objectStatus "C9P5.1" )
				)
				( pin "b"
					( attribute "PN" "2"
						( Origin gPackager )
					)
					( objectStatus "C9P5.2" )
				)
			)
			( gate "@baseboard_fab2_lib.baseboard_fab2(sch_1):page208_i20"
				( attribute "CDS_LIB" "mstr_discrete"
					( Origin gPackager )
				)
				( attribute "CDS_LOCATION" "L1D1"
					( Origin gPackager )
				)
				( attribute "CDS_SEC" "1"
					( Origin gPackager )
				)
				( attribute "LOCATION" "L1D1"
					( Origin gFrontEnd )
				)
				( attribute "MATERIAL" "IND"
					( Origin gFrontEnd )
				)
				( attribute "PACK_TYPE" "SM"
					( Origin gFrontEnd )
				)
				( attribute "PART_NUMBER" "D92183-034"
					( Origin gFrontEnd )
				)
				( attribute "PHYS_PAGE" "208"
					( Origin gFrontEnd )
				)
				( attribute "ROOM" "PVCCIN_CPU1_PWR_VR"
					( Origin gFrontEnd )
				)
				( attribute "ROT" "0"
					( Origin gFrontEnd )
				)
				( attribute "SEC" "1"
					( Origin gPackager )
				)
				( attribute "VALUE" "0.12UH"
					( Origin gFrontEnd )
				)
				( attribute "VER" "1"
					( Origin gFrontEnd )
				)
				( attribute "XY" "(-1325,1025)"
					( Origin gFrontEnd )
				)
				( attribute "CHIPS_PART_NAME" "INDUCTOR"
					( Origin gPackager )
				)
				( attribute "CDS_PART_NAME" "INDUCTOR_SM-0.12UH,IND,D92183-A"
					( Origin gPackager )
				)
				( objectStatus "L1D1" )
				( pin "ina"
					( attribute "PN" "1"
						( Origin gPackager )
					)
					( objectStatus "L1D1.1" )
				)
				( pin "inb"
					( attribute "PN" "2"
						( Origin gPackager )
					)
					( objectStatus "L1D1.2" )
				)
			)
			( gate "@baseboard_fab2_lib.baseboard_fab2(sch_1):page208_i22"
				( attribute "BOM_COST" "PROC_VRD_VCCIN_CPU0"
					( Origin gFrontEnd )
				)
				( attribute "CDS_LIB" "dev_discrete"
					( Origin gPackager )
				)
				( attribute "CDS_LOCATION" "C1D3"
					( Origin gPackager )
				)
				( attribute "CDS_SEC" "1"
					( Origin gPackager )
				)
				( attribute "LOCATION" "C1D3"
					( Origin gFrontEnd )
				)
				( attribute "MATERIAL" "X6S"
					( Origin gFrontEnd )
				)
				( attribute "PACK_TYPE" "0603V"
					( Origin gFrontEnd )
				)
				( attribute "PART_NUMBER" "E15431-004"
					( Origin gFrontEnd )
				)
				( attribute "PHYS_PAGE" "208"
					( Origin gFrontEnd )
				)
				( attribute "ROOM" "PVCCIN_CPU1_PWR_VR"
					( Origin gFrontEnd )
				)
				( attribute "ROT" "0"
					( Origin gFrontEnd )
				)
				( attribute "SEC" "1"
					( Origin gFrontEnd )
				)
				( attribute "SEC_TYPE" "0603V"
					( Origin gFrontEnd )
				)
				( attribute "TOLERANCE" "20%"
					( Origin gFrontEnd )
				)
				( attribute "VALUE" "22.0UF"
					( Origin gFrontEnd )
				)
				( attribute "VER" "1"
					( Origin gFrontEnd )
				)
				( attribute "VOLTAGE" "4V"
					( Units "uVoltage" "V" 1.000000)
					( Origin gFrontEnd )
				)
				( attribute "XY" "(-700,800)"
					( Origin gFrontEnd )
				)
				( attribute "CHIPS_PART_NAME" "CAP_A"
					( Origin gPackager )
				)
				( attribute "CDS_PART_NAME" "CAP_A_0603V-22.0UF,4V,20%,X6S,A"
					( Origin gPackager )
				)
				( objectStatus "C1D3" )
				( pin "a"
					( attribute "PN" "1"
						( Origin gPackager )
					)
					( objectStatus "C1D3.1" )
				)
				( pin "b"
					( attribute "PN" "2"
						( Origin gPackager )
					)
					( objectStatus "C1D3.2" )
				)
			)
			( gate "@baseboard_fab2_lib.baseboard_fab2(sch_1):page208_i24"
				( attribute "BOM_COST" "PROC_VRD_VCCIN_CPU0"
					( Origin gFrontEnd )
				)
				( attribute "CDS_LIB" "mstr_discrete"
					( Origin gPackager )
				)
				( attribute "CDS_LOCATION" "C9N24"
					( Origin gPackager )
				)
				( attribute "CDS_SEC" "1"
					( Origin gPackager )
				)
				( attribute "LOCATION" "C9N24"
					( Origin gFrontEnd )
				)
				( attribute "MATERIAL" "ALUM"
					( Origin gFrontEnd )
				)
				( attribute "PACK_TYPE" "3018"
					( Origin gFrontEnd )
				)
				( attribute "PART_NUMBER" "699013-049"
					( Origin gFrontEnd )
				)
				( attribute "PHYS_PAGE" "208"
					( Origin gFrontEnd )
				)
				( attribute "ROOM" "PVCCIN_CPU1_DECAP_VR"
					( Origin gFrontEnd )
				)
				( attribute "ROT" "0"
					( Origin gFrontEnd )
				)
				( attribute "SEC" "1"
					( Origin gFrontEnd )
				)
				( attribute "SEC_TYPE" "3018"
					( Origin gFrontEnd )
				)
				( attribute "TOLERANCE" "20%"
					( Origin gFrontEnd )
				)
				( attribute "VALUE" "470UF"
					( Origin gFrontEnd )
				)
				( attribute "VER" "1"
					( Origin gFrontEnd )
				)
				( attribute "VOLTAGE" "2.5V"
					( Units "uVoltage" "V" 1.000000)
					( Origin gFrontEnd )
				)
				( attribute "XY" "(-2375,2600)"
					( Origin gFrontEnd )
				)
				( attribute "CHIPS_PART_NAME" "CAPP"
					( Origin gPackager )
				)
				( attribute "CDS_PART_NAME" "CAPP_3018-470UF,2.5V,20%,ALUM,A"
					( Origin gPackager )
				)
				( objectStatus "C9N24" )
				( pin "a"
					( attribute "PN" "1"
						( Origin gPackager )
					)
					( objectStatus "C9N24.1" )
				)
				( pin "b"
					( attribute "PN" "2"
						( Origin gPackager )
					)
					( objectStatus "C9N24.2" )
				)
			)
			( gate "@baseboard_fab2_lib.baseboard_fab2(sch_1):page208_i25"
				( attribute "BOM_COST" "PROC_VRD_VCCIN_CPU0"
					( Origin gFrontEnd )
				)
				( attribute "CDS_LIB" "mstr_discrete"
					( Origin gPackager )
				)
				( attribute "CDS_LOCATION" "C9R9"
					( Origin gPackager )
				)
				( attribute "CDS_SEC" "1"
					( Origin gPackager )
				)
				( attribute "LOCATION" "C9R9"
					( Origin gFrontEnd )
				)
				( attribute "MATERIAL" "ALUM"
					( Origin gFrontEnd )
				)
				( attribute "PACK_TYPE" "3018"
					( Origin gFrontEnd )
				)
				( attribute "PART_NUMBER" "699013-049"
					( Origin gFrontEnd )
				)
				( attribute "PHYS_PAGE" "208"
					( Origin gFrontEnd )
				)
				( attribute "ROOM" "PVCCIN_CPU1_DECAP_VR"
					( Origin gFrontEnd )
				)
				( attribute "ROT" "0"
					( Origin gFrontEnd )
				)
				( attribute "SEC" "1"
					( Origin gFrontEnd )
				)
				( attribute "SEC_TYPE" "3018"
					( Origin gFrontEnd )
				)
				( attribute "TOLERANCE" "20%"
					( Origin gFrontEnd )
				)
				( attribute "VALUE" "470UF"
					( Origin gFrontEnd )
				)
				( attribute "VER" "1"
					( Origin gFrontEnd )
				)
				( attribute "VOLTAGE" "2.5V"
					( Units "uVoltage" "V" 1.000000)
					( Origin gFrontEnd )
				)
				( attribute "XY" "(-2825,2625)"
					( Origin gFrontEnd )
				)
				( attribute "CHIPS_PART_NAME" "CAPP"
					( Origin gPackager )
				)
				( attribute "CDS_PART_NAME" "CAPP_3018-470UF,2.5V,20%,ALUM,A"
					( Origin gPackager )
				)
				( objectStatus "C9R9" )
				( pin "a"
					( attribute "PN" "1"
						( Origin gPackager )
					)
					( objectStatus "C9R9.1" )
				)
				( pin "b"
					( attribute "PN" "2"
						( Origin gPackager )
					)
					( objectStatus "C9R9.2" )
				)
			)
			( gate "@baseboard_fab2_lib.baseboard_fab2(sch_1):page208_i26"
				( attribute "BOM_COST" "PROC_VRD_VCCIN_CPU0"
					( Origin gFrontEnd )
				)
				( attribute "CDS_LIB" "mstr_discrete"
					( Origin gPackager )
				)
				( attribute "CDS_LOCATION" "C9R3"
					( Origin gPackager )
				)
				( attribute "CDS_SEC" "1"
					( Origin gPackager )
				)
				( attribute "LOCATION" "C9R3"
					( Origin gFrontEnd )
				)
				( attribute "MATERIAL" "ALUM"
					( Origin gFrontEnd )
				)
				( attribute "PACK_TYPE" "3018"
					( Origin gFrontEnd )
				)
				( attribute "PART_NUMBER" "699013-049"
					( Origin gFrontEnd )
				)
				( attribute "PHYS_PAGE" "208"
					( Origin gFrontEnd )
				)
				( attribute "ROOM" "PVCCIN_CPU1_DECAP_VR"
					( Origin gFrontEnd )
				)
				( attribute "ROT" "0"
					( Origin gFrontEnd )
				)
				( attribute "SEC" "1"
					( Origin gFrontEnd )
				)
				( attribute "SEC_TYPE" "3018"
					( Origin gFrontEnd )
				)
				( attribute "TOLERANCE" "20%"
					( Origin gFrontEnd )
				)
				( attribute "VALUE" "470UF"
					( Origin gFrontEnd )
				)
				( attribute "VER" "1"
					( Origin gFrontEnd )
				)
				( attribute "VOLTAGE" "2.5V"
					( Units "uVoltage" "V" 1.000000)
					( Origin gFrontEnd )
				)
				( attribute "XY" "(-3275,2625)"
					( Origin gFrontEnd )
				)
				( attribute "CHIPS_PART_NAME" "CAPP"
					( Origin gPackager )
				)
				( attribute "CDS_PART_NAME" "CAPP_3018-470UF,2.5V,20%,ALUM,A"
					( Origin gPackager )
				)
				( objectStatus "C9R3" )
				( pin "a"
					( attribute "PN" "1"
						( Origin gPackager )
					)
					( objectStatus "C9R3.1" )
				)
				( pin "b"
					( attribute "PN" "2"
						( Origin gPackager )
					)
					( objectStatus "C9R3.2" )
				)
			)
			( gate "@baseboard_fab2_lib.baseboard_fab2(sch_1):page208_i27"
				( attribute "CDS_LIB" "mstr_discrete"
					( Origin gPackager )
				)
				( attribute "CDS_LOCATION" "EU1D3"
					( Origin gPackager )
				)
				( attribute "CDS_SEC" "1"
					( Origin gPackager )
				)
				( attribute "LOCATION" "EU1D3"
					( Origin gFrontEnd )
				)
				( attribute "MATERIAL" "IC"
					( Origin gFrontEnd )
				)
				( attribute "PACK_TYPE" "SM"
					( Origin gFrontEnd )
				)
				( attribute "PART_NUMBER" "H73688-001"
					( Origin gFrontEnd )
				)
				( attribute "PHYS_PAGE" "208"
					( Origin gFrontEnd )
				)
				( attribute "ROOM" "PVCCIN_CPU1_PWR_VR"
					( Origin gFrontEnd )
				)
				( attribute "ROT" "0"
					( Origin gFrontEnd )
				)
				( attribute "SEC" "1"
					( Origin gFrontEnd )
				)
				( attribute "SEC_TYPE" "SM"
					( Origin gFrontEnd )
				)
				( attribute "VALUE" "IR35411"
					( Origin gFrontEnd )
				)
				( attribute "VER" "1"
					( Origin gFrontEnd )
				)
				( attribute "XY" "(-3300,3875)"
					( Origin gFrontEnd )
				)
				( attribute "CHIPS_PART_NAME" "IR354XX"
					( Origin gPackager )
				)
				( attribute "CDS_PART_NAME" "IR354XX_SM-IR35411,IC,H73688-0A"
					( Origin gPackager )
				)
				( objectStatus "EU1D3" )
				( pin "boost"
					( attribute "PN" "33"
						( Origin gPackager )
					)
					( objectStatus "EU1D3.33" )
				)
				( pin "en"
					( attribute "PN" "35"
						( Origin gPackager )
					)
					( objectStatus "EU1D3.35" )
				)
				( pin "gl(0)"
					( attribute "PN" "6"
						( Origin gPackager )
					)
					( objectStatus "EU1D3.6" )
				)
				( pin "gl(1)"
					( attribute "PN" "41"
						( Origin gPackager )
					)
					( objectStatus "EU1D3.41" )
				)
				( pin "iout"
					( attribute "PN" "38"
						( Origin gPackager )
					)
					( objectStatus "EU1D3.38" )
				)
				( pin "lgnd"
					( attribute "PN" "2"
						( Origin gPackager )
					)
					( objectStatus "EU1D3.2" )
				)
				( pin "nc"
					( attribute "PN" "31"
						( Origin gPackager )
					)
					( objectStatus "EU1D3.31" )
				)
				( pin "ocset"
					( attribute "PN" "37"
						( Origin gPackager )
					)
					( objectStatus "EU1D3.37" )
				)
				( pin "pgnd(0)"
					( attribute "PN" "5"
						( Origin gPackager )
					)
					( objectStatus "EU1D3.5" )
				)
				( pin "pgnd(1)"
					( attribute "PN" "7"
						( Origin gPackager )
					)
					( objectStatus "EU1D3.7" )
				)
				( pin "pgnd(2)"
					( attribute "PN" "40"
						( Origin gPackager )
					)
					( objectStatus "EU1D3.40" )
				)
				( pin "phase"
					( attribute "PN" "32"
						( Origin gPackager )
					)
					( objectStatus "EU1D3.32" )
				)
				( pin "pwm"
					( attribute "PN" "34"
						( Origin gPackager )
					)
					( objectStatus "EU1D3.34" )
				)
				( pin "refin"
					( attribute "PN" "39"
						( Origin gPackager )
					)
					( objectStatus "EU1D3.39" )
				)
				( pin "sw"
					( attribute "PN" "10"
						( Origin gPackager )
					)
					( objectStatus "EU1D3.10" )
				)
				( pin "tout_flt"
					( attribute "PN" "36"
						( Origin gPackager )
					)
					( objectStatus "EU1D3.36" )
				)
				( pin "vcc"
					( attribute "PN" "3"
						( Origin gPackager )
					)
					( objectStatus "EU1D3.3" )
				)
				( pin "vdrv"
					( attribute "PN" "4"
						( Origin gPackager )
					)
					( objectStatus "EU1D3.4" )
				)
				( pin "vin(0)"
					( attribute "PN" "25"
						( Origin gPackager )
					)
					( objectStatus "EU1D3.25" )
				)
				( pin "vin(1)"
					( attribute "PN" "30"
						( Origin gPackager )
					)
					( objectStatus "EU1D3.30" )
				)
				( pin "vos"
					( attribute "PN" "1"
						( Origin gPackager )
					)
					( objectStatus "EU1D3.1" )
				)
			)
			( gate "@baseboard_fab2_lib.baseboard_fab2(sch_1):page208_i28"
				( attribute "BOM_COST" "PROC_VRD_VCCIN_CPU0"
					( Origin gFrontEnd )
				)
				( attribute "CDS_LIB" "mstr_discrete"
					( Origin gPackager )
				)
				( attribute "CDS_LOCATION" "C9P23"
					( Origin gPackager )
				)
				( attribute "CDS_SEC" "1"
					( Origin gPackager )
				)
				( attribute "LOCATION" "C9P23"
					( Origin gFrontEnd )
				)
				( attribute "MATERIAL" "ALUM"
					( Origin gFrontEnd )
				)
				( attribute "PACK_TYPE" "3018"
					( Origin gFrontEnd )
				)
				( attribute "PART_NUMBER" "699013-049"
					( Origin gFrontEnd )
				)
				( attribute "PHYS_PAGE" "208"
					( Origin gFrontEnd )
				)
				( attribute "ROOM" "PVCCIN_CPU1_DECAP_VR"
					( Origin gFrontEnd )
				)
				( attribute "ROT" "0"
					( Origin gFrontEnd )
				)
				( attribute "SEC" "1"
					( Origin gFrontEnd )
				)
				( attribute "SEC_TYPE" "3018"
					( Origin gFrontEnd )
				)
				( attribute "TOLERANCE" "20%"
					( Origin gFrontEnd )
				)
				( attribute "VALUE" "470UF"
					( Origin gFrontEnd )
				)
				( attribute "VER" "1"
					( Origin gFrontEnd )
				)
				( attribute "VOLTAGE" "2.5V"
					( Units "uVoltage" "V" 1.000000)
					( Origin gFrontEnd )
				)
				( attribute "XY" "(-3725,2625)"
					( Origin gFrontEnd )
				)
				( attribute "CHIPS_PART_NAME" "CAPP"
					( Origin gPackager )
				)
				( attribute "CDS_PART_NAME" "CAPP_3018-470UF,2.5V,20%,ALUM,A"
					( Origin gPackager )
				)
				( objectStatus "C9P23" )
				( pin "a"
					( attribute "PN" "1"
						( Origin gPackager )
					)
					( objectStatus "C9P23.1" )
				)
				( pin "b"
					( attribute "PN" "2"
						( Origin gPackager )
					)
					( objectStatus "C9P23.2" )
				)
			)
			( gate "@baseboard_fab2_lib.baseboard_fab2(sch_1):page208_i30"
				( attribute "BOM_COST" "PROC_VRD_VCCIN_CPU0"
					( Origin gFrontEnd )
				)
				( attribute "CDS_LIB" "mstr_discrete"
					( Origin gPackager )
				)
				( attribute "CDS_LOCATION" "C9P18"
					( Origin gPackager )
				)
				( attribute "CDS_SEC" "1"
					( Origin gPackager )
				)
				( attribute "LOCATION" "C9P18"
					( Origin gFrontEnd )
				)
				( attribute "MATERIAL" "ALUM"
					( Origin gFrontEnd )
				)
				( attribute "PACK_TYPE" "3018"
					( Origin gFrontEnd )
				)
				( attribute "PART_NUMBER" "699013-049"
					( Origin gFrontEnd )
				)
				( attribute "PHYS_PAGE" "208"
					( Origin gFrontEnd )
				)
				( attribute "ROOM" "PVCCIN_CPU1_DECAP_VR"
					( Origin gFrontEnd )
				)
				( attribute "ROT" "0"
					( Origin gFrontEnd )
				)
				( attribute "SEC" "1"
					( Origin gFrontEnd )
				)
				( attribute "SEC_TYPE" "3018"
					( Origin gFrontEnd )
				)
				( attribute "TOLERANCE" "20%"
					( Origin gFrontEnd )
				)
				( attribute "VALUE" "470UF"
					( Origin gFrontEnd )
				)
				( attribute "VER" "1"
					( Origin gFrontEnd )
				)
				( attribute "VOLTAGE" "2.5V"
					( Units "uVoltage" "V" 1.000000)
					( Origin gFrontEnd )
				)
				( attribute "XY" "(-4150,2625)"
					( Origin gFrontEnd )
				)
				( attribute "CHIPS_PART_NAME" "CAPP"
					( Origin gPackager )
				)
				( attribute "CDS_PART_NAME" "CAPP_3018-470UF,2.5V,20%,ALUM,A"
					( Origin gPackager )
				)
				( objectStatus "C9P18" )
				( pin "a"
					( attribute "PN" "1"
						( Origin gPackager )
					)
					( objectStatus "C9P18.1" )
				)
				( pin "b"
					( attribute "PN" "2"
						( Origin gPackager )
					)
					( objectStatus "C9P18.2" )
				)
			)
			( gate "@baseboard_fab2_lib.baseboard_fab2(sch_1):page208_i36"
				( attribute "CDS_LIB" "mstr_discrete"
					( Origin gPackager )
				)
				( attribute "CDS_LOCATION" "R9P22"
					( Origin gPackager )
				)
				( attribute "CDS_SEC" "1"
					( Origin gPackager )
				)
				( attribute "LOCATION" "R9P22"
					( Origin gFrontEnd )
				)
				( attribute "MATERIAL" "CHIP"
					( Origin gFrontEnd )
				)
				( attribute "PACK_TYPE" "0402"
					( Origin gFrontEnd )
				)
				( attribute "PART_NUMBER" "G21796-090"
					( Origin gFrontEnd )
				)
				( attribute "PHYS_PAGE" "208"
					( Origin gFrontEnd )
				)
				( attribute "ROOM" "PVCCIN_CPU1_PWR_VR"
					( Origin gFrontEnd )
				)
				( attribute "ROT" "0"
					( Origin gFrontEnd )
				)
				( attribute "SEC" "1"
					( Origin gFrontEnd )
				)
				( attribute "SEC_TYPE" "0402"
					( Origin gFrontEnd )
				)
				( attribute "TOLERANCE" "1%"
					( Origin gFrontEnd )
				)
				( attribute "VALUE" "1.0"
					( Origin gFrontEnd )
				)
				( attribute "VER" "1"
					( Origin gFrontEnd )
				)
				( attribute "WATTAGE" "1/16W"
					( Origin gFrontEnd )
				)
				( attribute "XY" "(-5275,4700)"
					( Origin gFrontEnd )
				)
				( attribute "CHIPS_PART_NAME" "RES"
					( Origin gPackager )
				)
				( attribute "CDS_PART_NAME" "RES_0402-1.0,1%,1/16W,CHIP,G21A"
					( Origin gPackager )
				)
				( objectStatus "R9P22" )
				( pin "a"
					( attribute "PN" "1"
						( Origin gPackager )
					)
					( objectStatus "R9P22.1" )
				)
				( pin "b"
					( attribute "PN" "2"
						( Origin gPackager )
					)
					( objectStatus "R9P22.2" )
				)
			)
			( gate "@baseboard_fab2_lib.baseboard_fab2(sch_1):page208_i38"
				( attribute "CDS_LIB" "mstr_discrete"
					( Origin gPackager )
				)
				( attribute "CDS_LOCATION" "C1D16"
					( Origin gPackager )
				)
				( attribute "CDS_SEC" "1"
					( Origin gPackager )
				)
				( attribute "LOCATION" "C1D16"
					( Origin gFrontEnd )
				)
				( attribute "MATERIAL" "X7R"
					( Origin gFrontEnd )
				)
				( attribute "PACK_TYPE" "0402"
					( Origin gFrontEnd )
				)
				( attribute "PART_NUMBER" "A36096-155"
					( Origin gFrontEnd )
				)
				( attribute "PHYS_PAGE" "208"
					( Origin gFrontEnd )
				)
				( attribute "ROOM" "PVCCIN_CPU1_PWR_VR"
					( Origin gFrontEnd )
				)
				( attribute "ROT" "0"
					( Origin gFrontEnd )
				)
				( attribute "SEC" "1"
					( Origin gFrontEnd )
				)
				( attribute "SEC_TYPE" "0402"
					( Origin gFrontEnd )
				)
				( attribute "TOLERANCE" "10%"
					( Origin gFrontEnd )
				)
				( attribute "VALUE" "0.22UF"
					( Origin gFrontEnd )
				)
				( attribute "VER" "1"
					( Origin gFrontEnd )
				)
				( attribute "VOLTAGE" "16V"
					( Units "uVoltage" "V" 1.000000)
					( Origin gFrontEnd )
				)
				( attribute "XY" "(-4850,4200)"
					( Origin gFrontEnd )
				)
				( attribute "CHIPS_PART_NAME" "CAP"
					( Origin gPackager )
				)
				( attribute "CDS_PART_NAME" "CAP_0402-0.22UF,16V,10%,X7R,A3A"
					( Origin gPackager )
				)
				( objectStatus "C1D16" )
				( pin "a"
					( attribute "PN" "1"
						( Origin gPackager )
					)
					( objectStatus "C1D16.1" )
				)
				( pin "b"
					( attribute "PN" "2"
						( Origin gPackager )
					)
					( objectStatus "C1D16.2" )
				)
			)
			( gate "@baseboard_fab2_lib.baseboard_fab2(sch_1):page208_i39"
				( attribute "CDS_LIB" "dev_discrete"
					( Origin gPackager )
				)
				( attribute "CDS_LOCATION" "C1D15"
					( Origin gPackager )
				)
				( attribute "CDS_SEC" "1"
					( Origin gPackager )
				)
				( attribute "LOCATION" "C1D15"
					( Origin gFrontEnd )
				)
				( attribute "MATERIAL" "X6S"
					( Origin gFrontEnd )
				)
				( attribute "PACK_TYPE" "0402V"
					( Origin gFrontEnd )
				)
				( attribute "PART_NUMBER" "D97712-004"
					( Origin gFrontEnd )
				)
				( attribute "PHYS_PAGE" "208"
					( Origin gFrontEnd )
				)
				( attribute "ROOM" "PVCCIN_CPU1_PWR_VR"
					( Origin gFrontEnd )
				)
				( attribute "ROT" "2"
					( Origin gFrontEnd )
				)
				( attribute "SEC" "1"
					( Origin gFrontEnd )
				)
				( attribute "SEC_TYPE" "0402V"
					( Origin gFrontEnd )
				)
				( attribute "TOLERANCE" "10%"
					( Origin gFrontEnd )
				)
				( attribute "VALUE" "1.0UF"
					( Origin gFrontEnd )
				)
				( attribute "VER" "1"
					( Origin gFrontEnd )
				)
				( attribute "VOLTAGE" "6.3V"
					( Units "uVoltage" "V" 1.000000)
					( Origin gFrontEnd )
				)
				( attribute "XY" "(-5000,4200)"
					( Origin gFrontEnd )
				)
				( attribute "CHIPS_PART_NAME" "CAP_A"
					( Origin gPackager )
				)
				( attribute "CDS_PART_NAME" "CAP_A_0402V-1.0UF,6.3V,10%,X6SA"
					( Origin gPackager )
				)
				( objectStatus "C1D15" )
				( pin "a"
					( attribute "PN" "1"
						( Origin gPackager )
					)
					( objectStatus "C1D15.1" )
				)
				( pin "b"
					( attribute "PN" "2"
						( Origin gPackager )
					)
					( objectStatus "C1D15.2" )
				)
			)
			( gate "@baseboard_fab2_lib.baseboard_fab2(sch_1):page208_i40"
				( attribute "CDS_LIB" "mstr_discrete"
					( Origin gPackager )
				)
				( attribute "CDS_LOCATION" "C1D20"
					( Origin gPackager )
				)
				( attribute "CDS_SEC" "1"
					( Origin gPackager )
				)
				( attribute "LOCATION" "C1D20"
					( Origin gFrontEnd )
				)
				( attribute "MATERIAL" "X7R"
					( Origin gFrontEnd )
				)
				( attribute "NO_XNET_CONNECTION" "1"
					( Origin gFrontEnd )
				)
				( attribute "PACK_TYPE" "0402"
					( Origin gFrontEnd )
				)
				( attribute "PART_NUMBER" "A36096-104"
					( Origin gFrontEnd )
				)
				( attribute "PHYS_PAGE" "208"
					( Origin gFrontEnd )
				)
				( attribute "ROOM" "PVCCIN_CPU1_PWR_VR"
					( Origin gFrontEnd )
				)
				( attribute "ROT" "2"
					( Origin gFrontEnd )
				)
				( attribute "SEC" "1"
					( Origin gFrontEnd )
				)
				( attribute "SEC_TYPE" "0402"
					( Origin gFrontEnd )
				)
				( attribute "SPOF" "TRUE"
					( Origin gFrontEnd )
				)
				( attribute "TOLERANCE" "10%"
					( Origin gFrontEnd )
				)
				( attribute "VALUE" "0.220UF"
					( Origin gFrontEnd )
				)
				( attribute "VER" "1"
					( Origin gFrontEnd )
				)
				( attribute "VOLTAGE" "16V"
					( Units "uVoltage" "V" 1.000000)
					( Origin gFrontEnd )
				)
				( attribute "XY" "(-5975,3575)"
					( Origin gFrontEnd )
				)
				( attribute "CHIPS_PART_NAME" "CAP"
					( Origin gPackager )
				)
				( attribute "CDS_PART_NAME" "CAP_0402-0.220UF,16V,10%,X7R,AA"
					( Origin gPackager )
				)
				( objectStatus "C1D20" )
				( pin "a"
					( attribute "PN" "1"
						( Origin gPackager )
					)
					( objectStatus "C1D20.1" )
				)
				( pin "b"
					( attribute "PN" "2"
						( Origin gPackager )
					)
					( objectStatus "C1D20.2" )
				)
			)
			( gate "@baseboard_fab2_lib.baseboard_fab2(sch_1):page208_i43"
				( attribute "CDS_LIB" "mstr_discrete"
					( Origin gPackager )
				)
				( attribute "CDS_LOCATION" "C1D17"
					( Origin gPackager )
				)
				( attribute "CDS_SEC" "1"
					( Origin gPackager )
				)
				( attribute "LOCATION" "C1D17"
					( Origin gFrontEnd )
				)
				( attribute "MATERIAL" "X6S"
					( Origin gFrontEnd )
				)
				( attribute "PACK_TYPE" "0402"
					( Origin gFrontEnd )
				)
				( attribute "PART_NUMBER" "D97712-011"
					( Origin gFrontEnd )
				)
				( attribute "PHYS_PAGE" "208"
					( Origin gFrontEnd )
				)
				( attribute "ROOM" "PVCCIN_CPU1_PWR_VR"
					( Origin gFrontEnd )
				)
				( attribute "ROT" "0"
					( Origin gFrontEnd )
				)
				( attribute "SEC" "1"
					( Origin gFrontEnd )
				)
				( attribute "SEC_TYPE" "0402"
					( Origin gFrontEnd )
				)
				( attribute "TOLERANCE" "10%"
					( Origin gFrontEnd )
				)
				( attribute "VALUE" "1.0UF"
					( Origin gFrontEnd )
				)
				( attribute "VER" "1"
					( Origin gFrontEnd )
				)
				( attribute "VOLTAGE" "16V"
					( Units "uVoltage" "V" 1.000000)
					( Origin gFrontEnd )
				)
				( attribute "XY" "(-5575,4150)"
					( Origin gFrontEnd )
				)
				( attribute "CHIPS_PART_NAME" "CAP"
					( Origin gPackager )
				)
				( attribute "CDS_PART_NAME" "CAP_0402-1.0UF,16V,10%,X6S,D97A"
					( Origin gPackager )
				)
				( objectStatus "C1D17" )
				( pin "a"
					( attribute "PN" "1"
						( Origin gPackager )
					)
					( objectStatus "C1D17.1" )
				)
				( pin "b"
					( attribute "PN" "2"
						( Origin gPackager )
					)
					( objectStatus "C1D17.2" )
				)
			)
			( gate "@baseboard_fab2_lib.baseboard_fab2(sch_1):page208_i44"
				( attribute "CDS_LIB" "dev_discrete"
					( Origin gPackager )
				)
				( attribute "CDS_LOCATION" "C1D28"
					( Origin gPackager )
				)
				( attribute "CDS_SEC" "1"
					( Origin gPackager )
				)
				( attribute "LOCATION" "C1D28"
					( Origin gFrontEnd )
				)
				( attribute "MATERIAL" "X7R"
					( Origin gFrontEnd )
				)
				( attribute "PACK_TYPE" "0402V"
					( Origin gFrontEnd )
				)
				( attribute "PART_NUMBER" "A36096-030"
					( Origin gFrontEnd )
				)
				( attribute "PHYS_PAGE" "208"
					( Origin gFrontEnd )
				)
				( attribute "ROOM" "PVCCIN_CPU1_PWR_VR"
					( Origin gFrontEnd )
				)
				( attribute "ROT" "0"
					( Origin gFrontEnd )
				)
				( attribute "SEC" "1"
					( Origin gFrontEnd )
				)
				( attribute "SEC_TYPE" "0402V"
					( Origin gFrontEnd )
				)
				( attribute "TOLERANCE" "10%"
					( Origin gFrontEnd )
				)
				( attribute "VALUE" "0.1UF"
					( Origin gFrontEnd )
				)
				( attribute "VER" "1"
					( Origin gFrontEnd )
				)
				( attribute "VOLTAGE" "16V"
					( Units "uVoltage" "V" 1.000000)
					( Origin gFrontEnd )
				)
				( attribute "XY" "(-5875,4150)"
					( Origin gFrontEnd )
				)
				( attribute "CHIPS_PART_NAME" "CAP_A"
					( Origin gPackager )
				)
				( attribute "CDS_PART_NAME" "CAP_A_0402V-0.1UF,16V,10%,X7R,A"
					( Origin gPackager )
				)
				( objectStatus "C1D28" )
				( pin "a"
					( attribute "PN" "1"
						( Origin gPackager )
					)
					( objectStatus "C1D28.1" )
				)
				( pin "b"
					( attribute "PN" "2"
						( Origin gPackager )
					)
					( objectStatus "C1D28.2" )
				)
			)
			( gate "@baseboard_fab2_lib.baseboard_fab2(sch_1):page208_i45"
				( attribute "CDS_LIB" "mstr_discrete"
					( Origin gPackager )
				)
				( attribute "CDS_LOCATION" "C1D23"
					( Origin gPackager )
				)
				( attribute "CDS_SEC" "1"
					( Origin gPackager )
				)
				( attribute "LOCATION" "C1D23"
					( Origin gFrontEnd )
				)
				( attribute "MATERIAL" "X6S"
					( Origin gFrontEnd )
				)
				( attribute "PACK_TYPE" "0402"
					( Origin gFrontEnd )
				)
				( attribute "PART_NUMBER" "D97712-011"
					( Origin gFrontEnd )
				)
				( attribute "PHYS_PAGE" "208"
					( Origin gFrontEnd )
				)
				( attribute "ROOM" "PVCCIN_CPU1_PWR_VR"
					( Origin gFrontEnd )
				)
				( attribute "ROT" "0"
					( Origin gFrontEnd )
				)
				( attribute "SEC" "1"
					( Origin gFrontEnd )
				)
				( attribute "SEC_TYPE" "0402"
					( Origin gFrontEnd )
				)
				( attribute "TOLERANCE" "10%"
					( Origin gFrontEnd )
				)
				( attribute "VALUE" "1.0UF"
					( Origin gFrontEnd )
				)
				( attribute "VER" "1"
					( Origin gFrontEnd )
				)
				( attribute "VOLTAGE" "16V"
					( Units "uVoltage" "V" 1.000000)
					( Origin gFrontEnd )
				)
				( attribute "XY" "(-6250,4150)"
					( Origin gFrontEnd )
				)
				( attribute "CHIPS_PART_NAME" "CAP"
					( Origin gPackager )
				)
				( attribute "CDS_PART_NAME" "CAP_0402-1.0UF,16V,10%,X6S,D97A"
					( Origin gPackager )
				)
				( objectStatus "C1D23" )
				( pin "a"
					( attribute "PN" "1"
						( Origin gPackager )
					)
					( objectStatus "C1D23.1" )
				)
				( pin "b"
					( attribute "PN" "2"
						( Origin gPackager )
					)
					( objectStatus "C1D23.2" )
				)
			)
			( gate "@baseboard_fab2_lib.baseboard_fab2(sch_1):page208_i46"
				( attribute "CDS_LIB" "mstr_discrete"
					( Origin gPackager )
				)
				( attribute "CDS_LOCATION" "C1D6"
					( Origin gPackager )
				)
				( attribute "CDS_SEC" "1"
					( Origin gPackager )
				)
				( attribute "LOCATION" "C1D6"
					( Origin gFrontEnd )
				)
				( attribute "MATERIAL" "X7R"
					( Origin gFrontEnd )
				)
				( attribute "PACK_TYPE" "0402"
					( Origin gFrontEnd )
				)
				( attribute "PART_NUMBER" "A36096-155"
					( Origin gFrontEnd )
				)
				( attribute "PHYS_PAGE" "208"
					( Origin gFrontEnd )
				)
				( attribute "ROOM" "PVCCIN_CPU1_PWR_VR"
					( Origin gFrontEnd )
				)
				( attribute "ROT" "0"
					( Origin gFrontEnd )
				)
				( attribute "SEC" "1"
					( Origin gFrontEnd )
				)
				( attribute "SEC_TYPE" "0402"
					( Origin gFrontEnd )
				)
				( attribute "TOLERANCE" "10%"
					( Origin gFrontEnd )
				)
				( attribute "VALUE" "0.22UF"
					( Origin gFrontEnd )
				)
				( attribute "VER" "1"
					( Origin gFrontEnd )
				)
				( attribute "VOLTAGE" "16V"
					( Units "uVoltage" "V" 1.000000)
					( Origin gFrontEnd )
				)
				( attribute "XY" "(-4900,1575)"
					( Origin gFrontEnd )
				)
				( attribute "CHIPS_PART_NAME" "CAP"
					( Origin gPackager )
				)
				( attribute "CDS_PART_NAME" "CAP_0402-0.22UF,16V,10%,X7R,A3A"
					( Origin gPackager )
				)
				( objectStatus "C1D6" )
				( pin "a"
					( attribute "PN" "1"
						( Origin gPackager )
					)
					( objectStatus "C1D6.1" )
				)
				( pin "b"
					( attribute "PN" "2"
						( Origin gPackager )
					)
					( objectStatus "C1D6.2" )
				)
			)
			( gate "@baseboard_fab2_lib.baseboard_fab2(sch_1):page208_i47"
				( attribute "CDS_LIB" "dev_discrete"
					( Origin gPackager )
				)
				( attribute "CDS_LOCATION" "C1D5"
					( Origin gPackager )
				)
				( attribute "CDS_SEC" "1"
					( Origin gPackager )
				)
				( attribute "LOCATION" "C1D5"
					( Origin gFrontEnd )
				)
				( attribute "MATERIAL" "X6S"
					( Origin gFrontEnd )
				)
				( attribute "PACK_TYPE" "0402V"
					( Origin gFrontEnd )
				)
				( attribute "PART_NUMBER" "D97712-004"
					( Origin gFrontEnd )
				)
				( attribute "PHYS_PAGE" "208"
					( Origin gFrontEnd )
				)
				( attribute "ROOM" "PVCCIN_CPU1_PWR_VR"
					( Origin gFrontEnd )
				)
				( attribute "ROT" "2"
					( Origin gFrontEnd )
				)
				( attribute "SEC" "1"
					( Origin gFrontEnd )
				)
				( attribute "SEC_TYPE" "0402V"
					( Origin gFrontEnd )
				)
				( attribute "TOLERANCE" "10%"
					( Origin gFrontEnd )
				)
				( attribute "VALUE" "1.0UF"
					( Origin gFrontEnd )
				)
				( attribute "VER" "1"
					( Origin gFrontEnd )
				)
				( attribute "VOLTAGE" "6.3V"
					( Units "uVoltage" "V" 1.000000)
					( Origin gFrontEnd )
				)
				( attribute "XY" "(-5075,1575)"
					( Origin gFrontEnd )
				)
				( attribute "CHIPS_PART_NAME" "CAP_A"
					( Origin gPackager )
				)
				( attribute "CDS_PART_NAME" "CAP_A_0402V-1.0UF,6.3V,10%,X6SA"
					( Origin gPackager )
				)
				( objectStatus "C1D5" )
				( pin "a"
					( attribute "PN" "1"
						( Origin gPackager )
					)
					( objectStatus "C1D5.1" )
				)
				( pin "b"
					( attribute "PN" "2"
						( Origin gPackager )
					)
					( objectStatus "C1D5.2" )
				)
			)
			( gate "@baseboard_fab2_lib.baseboard_fab2(sch_1):page208_i48"
				( attribute "CDS_LIB" "mstr_discrete"
					( Origin gPackager )
				)
				( attribute "CDS_LOCATION" "C1D10"
					( Origin gPackager )
				)
				( attribute "CDS_SEC" "1"
					( Origin gPackager )
				)
				( attribute "LOCATION" "C1D10"
					( Origin gFrontEnd )
				)
				( attribute "MATERIAL" "X7R"
					( Origin gFrontEnd )
				)
				( attribute "NO_XNET_CONNECTION" "1"
					( Origin gFrontEnd )
				)
				( attribute "PACK_TYPE" "0402"
					( Origin gFrontEnd )
				)
				( attribute "PART_NUMBER" "A36096-104"
					( Origin gFrontEnd )
				)
				( attribute "PHYS_PAGE" "208"
					( Origin gFrontEnd )
				)
				( attribute "ROOM" "PVCCIN_CPU1_PWR_VR"
					( Origin gFrontEnd )
				)
				( attribute "ROT" "2"
					( Origin gFrontEnd )
				)
				( attribute "SEC" "1"
					( Origin gFrontEnd )
				)
				( attribute "SEC_TYPE" "0402"
					( Origin gFrontEnd )
				)
				( attribute "SPOF" "TRUE"
					( Origin gFrontEnd )
				)
				( attribute "TOLERANCE" "10%"
					( Origin gFrontEnd )
				)
				( attribute "VALUE" "0.220UF"
					( Origin gFrontEnd )
				)
				( attribute "VER" "1"
					( Origin gFrontEnd )
				)
				( attribute "VOLTAGE" "16V"
					( Units "uVoltage" "V" 1.000000)
					( Origin gFrontEnd )
				)
				( attribute "XY" "(-5975,900)"
					( Origin gFrontEnd )
				)
				( attribute "CHIPS_PART_NAME" "CAP"
					( Origin gPackager )
				)
				( attribute "CDS_PART_NAME" "CAP_0402-0.220UF,16V,10%,X7R,AA"
					( Origin gPackager )
				)
				( objectStatus "C1D10" )
				( pin "a"
					( attribute "PN" "1"
						( Origin gPackager )
					)
					( objectStatus "C1D10.1" )
				)
				( pin "b"
					( attribute "PN" "2"
						( Origin gPackager )
					)
					( objectStatus "C1D10.2" )
				)
			)
			( gate "@baseboard_fab2_lib.baseboard_fab2(sch_1):page208_i49"
				( attribute "CDS_LIB" "mstr_discrete"
					( Origin gPackager )
				)
				( attribute "CDS_LOCATION" "R9P8"
					( Origin gPackager )
				)
				( attribute "CDS_SEC" "1"
					( Origin gPackager )
				)
				( attribute "LOCATION" "R9P8"
					( Origin gFrontEnd )
				)
				( attribute "MATERIAL" "CHIP"
					( Origin gFrontEnd )
				)
				( attribute "PACK_TYPE" "0402"
					( Origin gFrontEnd )
				)
				( attribute "PART_NUMBER" "G21796-090"
					( Origin gFrontEnd )
				)
				( attribute "PHYS_PAGE" "208"
					( Origin gFrontEnd )
				)
				( attribute "ROOM" "PVCCIN_CPU1_PWR_VR"
					( Origin gFrontEnd )
				)
				( attribute "ROT" "0"
					( Origin gFrontEnd )
				)
				( attribute "SEC" "1"
					( Origin gFrontEnd )
				)
				( attribute "SEC_TYPE" "0402"
					( Origin gFrontEnd )
				)
				( attribute "TOLERANCE" "1%"
					( Origin gFrontEnd )
				)
				( attribute "VALUE" "1.0"
					( Origin gFrontEnd )
				)
				( attribute "VER" "1"
					( Origin gFrontEnd )
				)
				( attribute "WATTAGE" "1/16W"
					( Origin gFrontEnd )
				)
				( attribute "XY" "(-5450,2025)"
					( Origin gFrontEnd )
				)
				( attribute "CHIPS_PART_NAME" "RES"
					( Origin gPackager )
				)
				( attribute "CDS_PART_NAME" "RES_0402-1.0,1%,1/16W,CHIP,G21A"
					( Origin gPackager )
				)
				( objectStatus "R9P8" )
				( pin "a"
					( attribute "PN" "1"
						( Origin gPackager )
					)
					( objectStatus "R9P8.1" )
				)
				( pin "b"
					( attribute "PN" "2"
						( Origin gPackager )
					)
					( objectStatus "R9P8.2" )
				)
			)
			( gate "@baseboard_fab2_lib.baseboard_fab2(sch_1):page208_i50"
				( attribute "CDS_LIB" "mstr_discrete"
					( Origin gPackager )
				)
				( attribute "CDS_LOCATION" "C1D7"
					( Origin gPackager )
				)
				( attribute "CDS_SEC" "1"
					( Origin gPackager )
				)
				( attribute "LOCATION" "C1D7"
					( Origin gFrontEnd )
				)
				( attribute "MATERIAL" "X6S"
					( Origin gFrontEnd )
				)
				( attribute "PACK_TYPE" "0402"
					( Origin gFrontEnd )
				)
				( attribute "PART_NUMBER" "D97712-011"
					( Origin gFrontEnd )
				)
				( attribute "PHYS_PAGE" "208"
					( Origin gFrontEnd )
				)
				( attribute "ROOM" "PVCCIN_CPU1_PWR_VR"
					( Origin gFrontEnd )
				)
				( attribute "ROT" "0"
					( Origin gFrontEnd )
				)
				( attribute "SEC" "1"
					( Origin gFrontEnd )
				)
				( attribute "SEC_TYPE" "0402"
					( Origin gFrontEnd )
				)
				( attribute "TOLERANCE" "10%"
					( Origin gFrontEnd )
				)
				( attribute "VALUE" "1.0UF"
					( Origin gFrontEnd )
				)
				( attribute "VER" "1"
					( Origin gFrontEnd )
				)
				( attribute "VOLTAGE" "16V"
					( Units "uVoltage" "V" 1.000000)
					( Origin gFrontEnd )
				)
				( attribute "XY" "(-5700,1575)"
					( Origin gFrontEnd )
				)
				( attribute "CHIPS_PART_NAME" "CAP"
					( Origin gPackager )
				)
				( attribute "CDS_PART_NAME" "CAP_0402-1.0UF,16V,10%,X6S,D97A"
					( Origin gPackager )
				)
				( objectStatus "C1D7" )
				( pin "a"
					( attribute "PN" "1"
						( Origin gPackager )
					)
					( objectStatus "C1D7.1" )
				)
				( pin "b"
					( attribute "PN" "2"
						( Origin gPackager )
					)
					( objectStatus "C1D7.2" )
				)
			)
			( gate "@baseboard_fab2_lib.baseboard_fab2(sch_1):page208_i51"
				( attribute "CDS_LIB" "dev_discrete"
					( Origin gPackager )
				)
				( attribute "CDS_LOCATION" "C1D13"
					( Origin gPackager )
				)
				( attribute "CDS_SEC" "1"
					( Origin gPackager )
				)
				( attribute "LOCATION" "C1D13"
					( Origin gFrontEnd )
				)
				( attribute "MATERIAL" "X7R"
					( Origin gFrontEnd )
				)
				( attribute "PACK_TYPE" "0402V"
					( Origin gFrontEnd )
				)
				( attribute "PART_NUMBER" "A36096-030"
					( Origin gFrontEnd )
				)
				( attribute "PHYS_PAGE" "208"
					( Origin gFrontEnd )
				)
				( attribute "ROOM" "PVCCIN_CPU1_PWR_VR"
					( Origin gFrontEnd )
				)
				( attribute "ROT" "0"
					( Origin gFrontEnd )
				)
				( attribute "SEC" "1"
					( Origin gFrontEnd )
				)
				( attribute "SEC_TYPE" "0402V"
					( Origin gFrontEnd )
				)
				( attribute "TOLERANCE" "10%"
					( Origin gFrontEnd )
				)
				( attribute "VALUE" "0.1UF"
					( Origin gFrontEnd )
				)
				( attribute "VER" "1"
					( Origin gFrontEnd )
				)
				( attribute "VOLTAGE" "16V"
					( Units "uVoltage" "V" 1.000000)
					( Origin gFrontEnd )
				)
				( attribute "XY" "(-6025,1450)"
					( Origin gFrontEnd )
				)
				( attribute "CHIPS_PART_NAME" "CAP_A"
					( Origin gPackager )
				)
				( attribute "CDS_PART_NAME" "CAP_A_0402V-0.1UF,16V,10%,X7R,A"
					( Origin gPackager )
				)
				( objectStatus "C1D13" )
				( pin "a"
					( attribute "PN" "1"
						( Origin gPackager )
					)
					( objectStatus "C1D13.1" )
				)
				( pin "b"
					( attribute "PN" "2"
						( Origin gPackager )
					)
					( objectStatus "C1D13.2" )
				)
			)
			( gate "@baseboard_fab2_lib.baseboard_fab2(sch_1):page208_i52"
				( attribute "CDS_LIB" "mstr_discrete"
					( Origin gPackager )
				)
				( attribute "CDS_LOCATION" "C1D12"
					( Origin gPackager )
				)
				( attribute "CDS_SEC" "1"
					( Origin gPackager )
				)
				( attribute "LOCATION" "C1D12"
					( Origin gFrontEnd )
				)
				( attribute "MATERIAL" "X6S"
					( Origin gFrontEnd )
				)
				( attribute "PACK_TYPE" "0402"
					( Origin gFrontEnd )
				)
				( attribute "PART_NUMBER" "D97712-011"
					( Origin gFrontEnd )
				)
				( attribute "PHYS_PAGE" "208"
					( Origin gFrontEnd )
				)
				( attribute "ROOM" "PVCCIN_CPU1_PWR_VR"
					( Origin gFrontEnd )
				)
				( attribute "ROT" "0"
					( Origin gFrontEnd )
				)
				( attribute "SEC" "1"
					( Origin gFrontEnd )
				)
				( attribute "SEC_TYPE" "0402"
					( Origin gFrontEnd )
				)
				( attribute "TOLERANCE" "10%"
					( Origin gFrontEnd )
				)
				( attribute "VALUE" "1.0UF"
					( Origin gFrontEnd )
				)
				( attribute "VER" "1"
					( Origin gFrontEnd )
				)
				( attribute "VOLTAGE" "16V"
					( Units "uVoltage" "V" 1.000000)
					( Origin gFrontEnd )
				)
				( attribute "XY" "(-6350,1500)"
					( Origin gFrontEnd )
				)
				( attribute "CHIPS_PART_NAME" "CAP"
					( Origin gPackager )
				)
				( attribute "CDS_PART_NAME" "CAP_0402-1.0UF,16V,10%,X6S,D97A"
					( Origin gPackager )
				)
				( objectStatus "C1D12" )
				( pin "a"
					( attribute "PN" "1"
						( Origin gPackager )
					)
					( objectStatus "C1D12.1" )
				)
				( pin "b"
					( attribute "PN" "2"
						( Origin gPackager )
					)
					( objectStatus "C1D12.2" )
				)
			)
			( gate "@baseboard_fab2_lib.baseboard_fab2(sch_1):page208_i53"
				( attribute "CDS_LIB" "mstr_discrete"
					( Origin gPackager )
				)
				( attribute "CDS_LOCATION" "C9P4"
					( Origin gPackager )
				)
				( attribute "CDS_SEC" "1"
					( Origin gPackager )
				)
				( attribute "LOCATION" "C9P4"
					( Origin gFrontEnd )
				)
				( attribute "MATERIAL" "X6S"
					( Origin gFrontEnd )
				)
				( attribute "PACK_TYPE" "0805"
					( Origin gFrontEnd )
				)
				( attribute "PART_NUMBER" "C95333-007"
					( Origin gFrontEnd )
				)
				( attribute "PHYS_PAGE" "208"
					( Origin gFrontEnd )
				)
				( attribute "ROOM" "PVCCIN_CPU1_PWR_VR"
					( Origin gFrontEnd )
				)
				( attribute "ROT" "0"
					( Origin gFrontEnd )
				)
				( attribute "SEC" "1"
					( Origin gFrontEnd )
				)
				( attribute "SEC_TYPE" "0805"
					( Origin gFrontEnd )
				)
				( attribute "TOLERANCE" "10%"
					( Origin gFrontEnd )
				)
				( attribute "VALUE" "10UF"
					( Origin gFrontEnd )
				)
				( attribute "VER" "1"
					( Origin gFrontEnd )
				)
				( attribute "VOLTAGE" "16V"
					( Units "uVoltage" "V" 1.000000)
					( Origin gFrontEnd )
				)
				( attribute "XY" "(-6625,4150)"
					( Origin gFrontEnd )
				)
				( attribute "CHIPS_PART_NAME" "CAP"
					( Origin gPackager )
				)
				( attribute "CDS_PART_NAME" "CAP_0805-10UF,16V,10%,X6S,C953A"
					( Origin gPackager )
				)
				( objectStatus "C9P4" )
				( pin "a"
					( attribute "PN" "1"
						( Origin gPackager )
					)
					( objectStatus "C9P4.1" )
				)
				( pin "b"
					( attribute "PN" "2"
						( Origin gPackager )
					)
					( objectStatus "C9P4.2" )
				)
			)
			( gate "@baseboard_fab2_lib.baseboard_fab2(sch_1):page208_i54"
				( attribute "CDS_LIB" "mstr_discrete"
					( Origin gPackager )
				)
				( attribute "CDS_LOCATION" "C9P7"
					( Origin gPackager )
				)
				( attribute "CDS_SEC" "1"
					( Origin gPackager )
				)
				( attribute "LOCATION" "C9P7"
					( Origin gFrontEnd )
				)
				( attribute "MATERIAL" "X6S"
					( Origin gFrontEnd )
				)
				( attribute "PACK_TYPE" "0805"
					( Origin gFrontEnd )
				)
				( attribute "PART_NUMBER" "C95333-007"
					( Origin gFrontEnd )
				)
				( attribute "PHYS_PAGE" "208"
					( Origin gFrontEnd )
				)
				( attribute "ROOM" "PVCCIN_CPU1_PWR_VR"
					( Origin gFrontEnd )
				)
				( attribute "ROT" "0"
					( Origin gFrontEnd )
				)
				( attribute "SEC" "1"
					( Origin gFrontEnd )
				)
				( attribute "SEC_TYPE" "0805"
					( Origin gFrontEnd )
				)
				( attribute "TOLERANCE" "10%"
					( Origin gFrontEnd )
				)
				( attribute "VALUE" "10UF"
					( Origin gFrontEnd )
				)
				( attribute "VER" "1"
					( Origin gFrontEnd )
				)
				( attribute "VOLTAGE" "16V"
					( Units "uVoltage" "V" 1.000000)
					( Origin gFrontEnd )
				)
				( attribute "XY" "(-7000,4150)"
					( Origin gFrontEnd )
				)
				( attribute "CHIPS_PART_NAME" "CAP"
					( Origin gPackager )
				)
				( attribute "CDS_PART_NAME" "CAP_0805-10UF,16V,10%,X6S,C953A"
					( Origin gPackager )
				)
				( objectStatus "C9P7" )
				( pin "a"
					( attribute "PN" "1"
						( Origin gPackager )
					)
					( objectStatus "C9P7.1" )
				)
				( pin "b"
					( attribute "PN" "2"
						( Origin gPackager )
					)
					( objectStatus "C9P7.2" )
				)
			)
			( gate "@baseboard_fab2_lib.baseboard_fab2(sch_1):page208_i55"
				( attribute "CDS_LIB" "mstr_discrete"
					( Origin gPackager )
				)
				( attribute "CDS_LOCATION" "C9P9"
					( Origin gPackager )
				)
				( attribute "CDS_SEC" "1"
					( Origin gPackager )
				)
				( attribute "LOCATION" "C9P9"
					( Origin gFrontEnd )
				)
				( attribute "MATERIAL" "X6S"
					( Origin gFrontEnd )
				)
				( attribute "PACK_TYPE" "0805"
					( Origin gFrontEnd )
				)
				( attribute "PART_NUMBER" "C95333-007"
					( Origin gFrontEnd )
				)
				( attribute "PHYS_PAGE" "208"
					( Origin gFrontEnd )
				)
				( attribute "ROOM" "PVCCIN_CPU1_PWR_VR"
					( Origin gFrontEnd )
				)
				( attribute "ROT" "0"
					( Origin gFrontEnd )
				)
				( attribute "SEC" "1"
					( Origin gFrontEnd )
				)
				( attribute "SEC_TYPE" "0805"
					( Origin gFrontEnd )
				)
				( attribute "TOLERANCE" "10%"
					( Origin gFrontEnd )
				)
				( attribute "VALUE" "10UF"
					( Origin gFrontEnd )
				)
				( attribute "VER" "1"
					( Origin gFrontEnd )
				)
				( attribute "VOLTAGE" "16V"
					( Units "uVoltage" "V" 1.000000)
					( Origin gFrontEnd )
				)
				( attribute "XY" "(-7375,4150)"
					( Origin gFrontEnd )
				)
				( attribute "CHIPS_PART_NAME" "CAP"
					( Origin gPackager )
				)
				( attribute "CDS_PART_NAME" "CAP_0805-10UF,16V,10%,X6S,C953A"
					( Origin gPackager )
				)
				( objectStatus "C9P9" )
				( pin "a"
					( attribute "PN" "1"
						( Origin gPackager )
					)
					( objectStatus "C9P9.1" )
				)
				( pin "b"
					( attribute "PN" "2"
						( Origin gPackager )
					)
					( objectStatus "C9P9.2" )
				)
			)
			( gate "@baseboard_fab2_lib.baseboard_fab2(sch_1):page208_i58"
				( attribute "CDS_LIB" "mstr_discrete"
					( Origin gPackager )
				)
				( attribute "CDS_LOCATION" "C9P24"
					( Origin gPackager )
				)
				( attribute "CDS_SEC" "1"
					( Origin gPackager )
				)
				( attribute "LOCATION" "C9P24"
					( Origin gFrontEnd )
				)
				( attribute "MATERIAL" "X6S"
					( Origin gFrontEnd )
				)
				( attribute "PACK_TYPE" "0805"
					( Origin gFrontEnd )
				)
				( attribute "PART_NUMBER" "C95333-007"
					( Origin gFrontEnd )
				)
				( attribute "PHYS_PAGE" "208"
					( Origin gFrontEnd )
				)
				( attribute "ROOM" "PVCCIN_CPU1_PWR_VR"
					( Origin gFrontEnd )
				)
				( attribute "ROT" "0"
					( Origin gFrontEnd )
				)
				( attribute "SEC" "1"
					( Origin gFrontEnd )
				)
				( attribute "SEC_TYPE" "0805"
					( Origin gFrontEnd )
				)
				( attribute "TOLERANCE" "10%"
					( Origin gFrontEnd )
				)
				( attribute "VALUE" "10UF"
					( Origin gFrontEnd )
				)
				( attribute "VER" "1"
					( Origin gFrontEnd )
				)
				( attribute "VOLTAGE" "16V"
					( Units "uVoltage" "V" 1.000000)
					( Origin gFrontEnd )
				)
				( attribute "XY" "(-6725,1475)"
					( Origin gFrontEnd )
				)
				( attribute "CHIPS_PART_NAME" "CAP"
					( Origin gPackager )
				)
				( attribute "CDS_PART_NAME" "CAP_0805-10UF,16V,10%,X6S,C953A"
					( Origin gPackager )
				)
				( objectStatus "C9P24" )
				( pin "a"
					( attribute "PN" "1"
						( Origin gPackager )
					)
					( objectStatus "C9P24.1" )
				)
				( pin "b"
					( attribute "PN" "2"
						( Origin gPackager )
					)
					( objectStatus "C9P24.2" )
				)
			)
			( gate "@baseboard_fab2_lib.baseboard_fab2(sch_1):page208_i59"
				( attribute "CDS_LIB" "mstr_discrete"
					( Origin gPackager )
				)
				( attribute "CDS_LOCATION" "C9P1"
					( Origin gPackager )
				)
				( attribute "CDS_SEC" "1"
					( Origin gPackager )
				)
				( attribute "LOCATION" "C9P1"
					( Origin gFrontEnd )
				)
				( attribute "MATERIAL" "X6S"
					( Origin gFrontEnd )
				)
				( attribute "PACK_TYPE" "0805"
					( Origin gFrontEnd )
				)
				( attribute "PART_NUMBER" "C95333-007"
					( Origin gFrontEnd )
				)
				( attribute "PHYS_PAGE" "208"
					( Origin gFrontEnd )
				)
				( attribute "ROOM" "PVCCIN_CPU1_PWR_VR"
					( Origin gFrontEnd )
				)
				( attribute "ROT" "0"
					( Origin gFrontEnd )
				)
				( attribute "SEC" "1"
					( Origin gFrontEnd )
				)
				( attribute "SEC_TYPE" "0805"
					( Origin gFrontEnd )
				)
				( attribute "TOLERANCE" "10%"
					( Origin gFrontEnd )
				)
				( attribute "VALUE" "10UF"
					( Origin gFrontEnd )
				)
				( attribute "VER" "1"
					( Origin gFrontEnd )
				)
				( attribute "VOLTAGE" "16V"
					( Units "uVoltage" "V" 1.000000)
					( Origin gFrontEnd )
				)
				( attribute "XY" "(-7075,1475)"
					( Origin gFrontEnd )
				)
				( attribute "CHIPS_PART_NAME" "CAP"
					( Origin gPackager )
				)
				( attribute "CDS_PART_NAME" "CAP_0805-10UF,16V,10%,X6S,C953A"
					( Origin gPackager )
				)
				( objectStatus "C9P1" )
				( pin "a"
					( attribute "PN" "1"
						( Origin gPackager )
					)
					( objectStatus "C9P1.1" )
				)
				( pin "b"
					( attribute "PN" "2"
						( Origin gPackager )
					)
					( objectStatus "C9P1.2" )
				)
			)
			( gate "@baseboard_fab2_lib.baseboard_fab2(sch_1):page208_i60"
				( attribute "CDS_LIB" "mstr_discrete"
					( Origin gPackager )
				)
				( attribute "CDS_LOCATION" "C9P2"
					( Origin gPackager )
				)
				( attribute "CDS_SEC" "1"
					( Origin gPackager )
				)
				( attribute "LOCATION" "C9P2"
					( Origin gFrontEnd )
				)
				( attribute "MATERIAL" "X6S"
					( Origin gFrontEnd )
				)
				( attribute "PACK_TYPE" "0805"
					( Origin gFrontEnd )
				)
				( attribute "PART_NUMBER" "C95333-007"
					( Origin gFrontEnd )
				)
				( attribute "PHYS_PAGE" "208"
					( Origin gFrontEnd )
				)
				( attribute "ROOM" "PVCCIN_CPU1_PWR_VR"
					( Origin gFrontEnd )
				)
				( attribute "ROT" "0"
					( Origin gFrontEnd )
				)
				( attribute "SEC" "1"
					( Origin gFrontEnd )
				)
				( attribute "SEC_TYPE" "0805"
					( Origin gFrontEnd )
				)
				( attribute "TOLERANCE" "10%"
					( Origin gFrontEnd )
				)
				( attribute "VALUE" "10UF"
					( Origin gFrontEnd )
				)
				( attribute "VER" "1"
					( Origin gFrontEnd )
				)
				( attribute "VOLTAGE" "16V"
					( Units "uVoltage" "V" 1.000000)
					( Origin gFrontEnd )
				)
				( attribute "XY" "(-7375,1500)"
					( Origin gFrontEnd )
				)
				( attribute "CHIPS_PART_NAME" "CAP"
					( Origin gPackager )
				)
				( attribute "CDS_PART_NAME" "CAP_0805-10UF,16V,10%,X6S,C953A"
					( Origin gPackager )
				)
				( objectStatus "C9P2" )
				( pin "a"
					( attribute "PN" "1"
						( Origin gPackager )
					)
					( objectStatus "C9P2.1" )
				)
				( pin "b"
					( attribute "PN" "2"
						( Origin gPackager )
					)
					( objectStatus "C9P2.2" )
				)
			)
			( gate "@baseboard_fab2_lib.baseboard_fab2(sch_1):page208_i66"
				( attribute "CDS_LIB" "dev_discrete"
					( Origin gPackager )
				)
				( attribute "CDS_LOCATION" "C9P10"
					( Origin gPackager )
				)
				( attribute "CDS_SEC" "1"
					( Origin gPackager )
				)
				( attribute "LOCATION" "C9P10"
					( Origin gFrontEnd )
				)
				( attribute "MATERIAL" "X6S"
					( Origin gFrontEnd )
				)
				( attribute "PACK_TYPE" "0603V"
					( Origin gFrontEnd )
				)
				( attribute "PART_NUMBER" "E15431-004"
					( Origin gFrontEnd )
				)
				( attribute "PHYS_PAGE" "208"
					( Origin gFrontEnd )
				)
				( attribute "ROT" "0"
					( Origin gFrontEnd )
				)
				( attribute "SEC" "1"
					( Origin gFrontEnd )
				)
				( attribute "SEC_TYPE" "0603V"
					( Origin gFrontEnd )
				)
				( attribute "TOLERANCE" "20%"
					( Origin gFrontEnd )
				)
				( attribute "VALUE" "22.0UF"
					( Origin gFrontEnd )
				)
				( attribute "VER" "1"
					( Origin gFrontEnd )
				)
				( attribute "VOLTAGE" "4V"
					( Units "uVoltage" "V" 1.000000)
					( Origin gFrontEnd )
				)
				( attribute "XY" "(-400,3400)"
					( Origin gFrontEnd )
				)
				( attribute "CHIPS_PART_NAME" "CAP_A"
					( Origin gPackager )
				)
				( attribute "CDS_PART_NAME" "CAP_A_0603V-22.0UF,4V,20%,X6S,A"
					( Origin gPackager )
				)
				( objectStatus "C9P10" )
				( pin "a"
					( attribute "PN" "1"
						( Origin gPackager )
					)
					( objectStatus "C9P10.1" )
				)
				( pin "b"
					( attribute "PN" "2"
						( Origin gPackager )
					)
					( objectStatus "C9P10.2" )
				)
			)
			( gate "@baseboard_fab2_lib.baseboard_fab2(sch_1):page208_i67"
				( attribute "CDS_LIB" "dev_discrete"
					( Origin gPackager )
				)
				( attribute "CDS_LOCATION" "C9R2"
					( Origin gPackager )
				)
				( attribute "CDS_SEC" "1"
					( Origin gPackager )
				)
				( attribute "LOCATION" "C9R2"
					( Origin gFrontEnd )
				)
				( attribute "MATERIAL" "X6S"
					( Origin gFrontEnd )
				)
				( attribute "PACK_TYPE" "0603V"
					( Origin gFrontEnd )
				)
				( attribute "PART_NUMBER" "E15431-004"
					( Origin gFrontEnd )
				)
				( attribute "PHYS_PAGE" "208"
					( Origin gFrontEnd )
				)
				( attribute "ROT" "0"
					( Origin gFrontEnd )
				)
				( attribute "SEC" "1"
					( Origin gFrontEnd )
				)
				( attribute "SEC_TYPE" "0603V"
					( Origin gFrontEnd )
				)
				( attribute "TOLERANCE" "20%"
					( Origin gFrontEnd )
				)
				( attribute "VALUE" "22.0UF"
					( Origin gFrontEnd )
				)
				( attribute "VER" "1"
					( Origin gFrontEnd )
				)
				( attribute "VOLTAGE" "4V"
					( Units "uVoltage" "V" 1.000000)
					( Origin gFrontEnd )
				)
				( attribute "XY" "(-350,800)"
					( Origin gFrontEnd )
				)
				( attribute "CHIPS_PART_NAME" "CAP_A"
					( Origin gPackager )
				)
				( attribute "CDS_PART_NAME" "CAP_A_0603V-22.0UF,4V,20%,X6S,A"
					( Origin gPackager )
				)
				( objectStatus "C9R2" )
				( pin "a"
					( attribute "PN" "1"
						( Origin gPackager )
					)
					( objectStatus "C9R2.1" )
				)
				( pin "b"
					( attribute "PN" "2"
						( Origin gPackager )
					)
					( objectStatus "C9R2.2" )
				)
			)
			( gate "@baseboard_fab2_lib.baseboard_fab2(sch_1):page208_i71"
				( attribute "CDS_LIB" "mstr_discrete"
					( Origin gPackager )
				)
				( attribute "CDS_LOCATION" "EU1D1"
					( Origin gPackager )
				)
				( attribute "LOCATION" "EU1D1"
					( Origin gFrontEnd )
				)
				( attribute "MATERIAL" "IC"
					( Origin gFrontEnd )
				)
				( attribute "PACK_TYPE" "SM"
					( Origin gFrontEnd )
				)
				( attribute "PART_NUMBER" "H73688-001"
					( Origin gFrontEnd )
				)
				( attribute "PHYS_PAGE" "208"
					( Origin gFrontEnd )
				)
				( attribute "ROOM" "PVCCIN_CPU1_PWR_VR"
					( Origin gFrontEnd )
				)
				( attribute "ROT" "0"
					( Origin gFrontEnd )
				)
				( attribute "SEC" "1"
					( Origin gFrontEnd )
				)
				( attribute "SEC_TYPE" "SM"
					( Origin gFrontEnd )
				)
				( attribute "VALUE" "IR35411"
					( Origin gFrontEnd )
				)
				( attribute "VER" "1"
					( Origin gFrontEnd )
				)
				( attribute "XY" "(-3250,1275)"
					( Origin gFrontEnd )
				)
				( attribute "CHIPS_PART_NAME" "IR354XX"
					( Origin gPackager )
				)
				( attribute "CDS_PART_NAME" "IR354XX_SM-IR35411,IC,H73688-0A"
					( Origin gPackager )
				)
				( attribute "CDS_SEC" "1"
					( Origin gPackager )
				)
				( objectStatus "EU1D1" )
				( pin "boost"
					( attribute "PN" "33"
						( Origin gPackager )
					)
					( objectStatus "EU1D1.33" )
				)
				( pin "en"
					( attribute "PN" "35"
						( Origin gPackager )
					)
					( objectStatus "EU1D1.35" )
				)
				( pin "gl(0)"
					( attribute "PN" "6"
						( Origin gPackager )
					)
					( objectStatus "EU1D1.6" )
				)
				( pin "gl(1)"
					( attribute "PN" "41"
						( Origin gPackager )
					)
					( objectStatus "EU1D1.41" )
				)
				( pin "iout"
					( attribute "PN" "38"
						( Origin gPackager )
					)
					( objectStatus "EU1D1.38" )
				)
				( pin "lgnd"
					( attribute "PN" "2"
						( Origin gPackager )
					)
					( objectStatus "EU1D1.2" )
				)
				( pin "nc"
					( attribute "PN" "31"
						( Origin gPackager )
					)
					( objectStatus "EU1D1.31" )
				)
				( pin "ocset"
					( attribute "PN" "37"
						( Origin gPackager )
					)
					( objectStatus "EU1D1.37" )
				)
				( pin "pgnd(0)"
					( attribute "PN" "5"
						( Origin gPackager )
					)
					( objectStatus "EU1D1.5" )
				)
				( pin "pgnd(1)"
					( attribute "PN" "7"
						( Origin gPackager )
					)
					( objectStatus "EU1D1.7" )
				)
				( pin "pgnd(2)"
					( attribute "PN" "40"
						( Origin gPackager )
					)
					( objectStatus "EU1D1.40" )
				)
				( pin "phase"
					( attribute "PN" "32"
						( Origin gPackager )
					)
					( objectStatus "EU1D1.32" )
				)
				( pin "pwm"
					( attribute "PN" "34"
						( Origin gPackager )
					)
					( objectStatus "EU1D1.34" )
				)
				( pin "refin"
					( attribute "PN" "39"
						( Origin gPackager )
					)
					( objectStatus "EU1D1.39" )
				)
				( pin "sw"
					( attribute "PN" "10"
						( Origin gPackager )
					)
					( objectStatus "EU1D1.10" )
				)
				( pin "tout_flt"
					( attribute "PN" "36"
						( Origin gPackager )
					)
					( objectStatus "EU1D1.36" )
				)
				( pin "vcc"
					( attribute "PN" "3"
						( Origin gPackager )
					)
					( objectStatus "EU1D1.3" )
				)
				( pin "vdrv"
					( attribute "PN" "4"
						( Origin gPackager )
					)
					( objectStatus "EU1D1.4" )
				)
				( pin "vin(0)"
					( attribute "PN" "25"
						( Origin gPackager )
					)
					( objectStatus "EU1D1.25" )
				)
				( pin "vin(1)"
					( attribute "PN" "30"
						( Origin gPackager )
					)
					( objectStatus "EU1D1.30" )
				)
				( pin "vos"
					( attribute "PN" "1"
						( Origin gPackager )
					)
					( objectStatus "EU1D1.1" )
				)
			)
			( gate "@baseboard_fab2_lib.baseboard_fab2(sch_1):page208_i75"
				( attribute "CDS_LIB" "mstr_discrete"
					( Origin gPackager )
				)
				( attribute "CDS_LOCATION" "R1D54"
					( Origin gPackager )
				)
				( attribute "CDS_SEC" "1"
					( Origin gPackager )
				)
				( attribute "LOCATION" "R1D54"
					( Origin gFrontEnd )
				)
				( attribute "MATERIAL" "EMPTY"
					( Origin gFrontEnd )
				)
				( attribute "PACK_TYPE" "0402"
					( Origin gFrontEnd )
				)
				( attribute "PART_NUMBER" "G21796-187"
					( Origin gFrontEnd )
				)
				( attribute "PHYS_PAGE" "208"
					( Origin gFrontEnd )
				)
				( attribute "ROT" "0"
					( Origin gFrontEnd )
				)
				( attribute "SEC" "1"
					( Origin gPackager )
				)
				( attribute "TOLERANCE" "1%"
					( Origin gFrontEnd )
				)
				( attribute "VALUE" "68.1K"
					( Origin gFrontEnd )
				)
				( attribute "VER" "2"
					( Origin gFrontEnd )
				)
				( attribute "WATTAGE" "1/16W"
					( Origin gFrontEnd )
				)
				( attribute "XY" "(-625,1450)"
					( Origin gFrontEnd )
				)
				( attribute "CHIPS_PART_NAME" "RES"
					( Origin gPackager )
				)
				( attribute "CDS_PART_NAME" "RES_0402-68.1K,1%,1/16W,EMPTY,A"
					( Origin gPackager )
				)
				( objectStatus "R1D54" )
				( pin "a"
					( attribute "PN" "1"
						( Origin gPackager )
					)
					( objectStatus "R1D54.1" )
				)
				( pin "b"
					( attribute "PN" "2"
						( Origin gPackager )
					)
					( objectStatus "R1D54.2" )
				)
			)
			( gate "@baseboard_fab2_lib.baseboard_fab2(sch_1):page208_i76"
				( attribute "CDS_LIB" "mstr_discrete"
					( Origin gPackager )
				)
				( attribute "CDS_LOCATION" "R1D55"
					( Origin gPackager )
				)
				( attribute "CDS_SEC" "1"
					( Origin gPackager )
				)
				( attribute "LOCATION" "R1D55"
					( Origin gFrontEnd )
				)
				( attribute "MATERIAL" "EMPTY"
					( Origin gFrontEnd )
				)
				( attribute "PACK_TYPE" "0402"
					( Origin gFrontEnd )
				)
				( attribute "PART_NUMBER" "G21796-187"
					( Origin gFrontEnd )
				)
				( attribute "PHYS_PAGE" "208"
					( Origin gFrontEnd )
				)
				( attribute "ROT" "0"
					( Origin gFrontEnd )
				)
				( attribute "SEC" "1"
					( Origin gPackager )
				)
				( attribute "TOLERANCE" "1%"
					( Origin gFrontEnd )
				)
				( attribute "VALUE" "68.1K"
					( Origin gFrontEnd )
				)
				( attribute "VER" "2"
					( Origin gFrontEnd )
				)
				( attribute "WATTAGE" "1/16W"
					( Origin gFrontEnd )
				)
				( attribute "XY" "(-700,4075)"
					( Origin gFrontEnd )
				)
				( attribute "CHIPS_PART_NAME" "RES"
					( Origin gPackager )
				)
				( attribute "CDS_PART_NAME" "RES_0402-68.1K,1%,1/16W,EMPTY,A"
					( Origin gPackager )
				)
				( objectStatus "R1D55" )
				( pin "a"
					( attribute "PN" "1"
						( Origin gPackager )
					)
					( objectStatus "R1D55.1" )
				)
				( pin "b"
					( attribute "PN" "2"
						( Origin gPackager )
					)
					( objectStatus "R1D55.2" )
				)
			)
			( gate "@baseboard_fab2_lib.baseboard_fab2(sch_1):page209_i3"
				( attribute "BOM_COST" "PROC_VRD_VCCIN_CPU0"
					( Origin gFrontEnd )
				)
				( attribute "CDS_LIB" "mstr_discrete"
					( Origin gPackager )
				)
				( attribute "CDS_LOCATION" "R1E5"
					( Origin gPackager )
				)
				( attribute "CDS_SEC" "1"
					( Origin gPackager )
				)
				( attribute "LOCATION" "R1E5"
					( Origin gFrontEnd )
				)
				( attribute "MATERIAL" "EMPTY"
					( Origin gFrontEnd )
				)
				( attribute "PACK_TYPE" "0402"
					( Origin gFrontEnd )
				)
				( attribute "PART_NUMBER" "G21796-026"
					( Origin gFrontEnd )
				)
				( attribute "PHYS_PAGE" "209"
					( Origin gFrontEnd )
				)
				( attribute "ROOM" "PVCCIN_CPU1_VSENSE_VR"
					( Origin gFrontEnd )
				)
				( attribute "ROT" "0"
					( Origin gFrontEnd )
				)
				( attribute "SEC" "1"
					( Origin gPackager )
				)
				( attribute "TOLERANCE" "1%"
					( Origin gFrontEnd )
				)
				( attribute "VALUE" "1.00K"
					( Origin gFrontEnd )
				)
				( attribute "VER" "2"
					( Origin gFrontEnd )
				)
				( attribute "WATTAGE" "1/16W"
					( Origin gFrontEnd )
				)
				( attribute "XY" "(-6300,1700)"
					( Origin gFrontEnd )
				)
				( attribute "CHIPS_PART_NAME" "RES"
					( Origin gPackager )
				)
				( attribute "CDS_PART_NAME" "RES_0402-1.00K,1%,1/16W,EMPTY,A"
					( Origin gPackager )
				)
				( objectStatus "R1E5" )
				( pin "a"
					( attribute "PN" "1"
						( Origin gPackager )
					)
					( objectStatus "R1E5.1" )
				)
				( pin "b"
					( attribute "PN" "2"
						( Origin gPackager )
					)
					( objectStatus "R1E5.2" )
				)
			)
			( gate "@baseboard_fab2_lib.baseboard_fab2(sch_1):page209_i5"
				( attribute "CDS_LIB" "mstr_discrete"
					( Origin gPackager )
				)
				( attribute "CDS_LOCATION" "C9N27"
					( Origin gPackager )
				)
				( attribute "CDS_SEC" "1"
					( Origin gPackager )
				)
				( attribute "LOCATION" "C9N27"
					( Origin gFrontEnd )
				)
				( attribute "MATERIAL" "X6S"
					( Origin gFrontEnd )
				)
				( attribute "PACK_TYPE" "0805"
					( Origin gFrontEnd )
				)
				( attribute "PART_NUMBER" "C95333-007"
					( Origin gFrontEnd )
				)
				( attribute "PHYS_PAGE" "209"
					( Origin gFrontEnd )
				)
				( attribute "ROOM" "PVCCIN_CPU1_PWR_VR"
					( Origin gFrontEnd )
				)
				( attribute "ROT" "0"
					( Origin gFrontEnd )
				)
				( attribute "SEC" "1"
					( Origin gFrontEnd )
				)
				( attribute "SEC_TYPE" "0805"
					( Origin gFrontEnd )
				)
				( attribute "TOLERANCE" "10%"
					( Origin gFrontEnd )
				)
				( attribute "VALUE" "10UF"
					( Origin gFrontEnd )
				)
				( attribute "VER" "1"
					( Origin gFrontEnd )
				)
				( attribute "VOLTAGE" "16V"
					( Units "uVoltage" "V" 1.000000)
					( Origin gFrontEnd )
				)
				( attribute "XY" "(-7175,4025)"
					( Origin gFrontEnd )
				)
				( attribute "CHIPS_PART_NAME" "CAP"
					( Origin gPackager )
				)
				( attribute "CDS_PART_NAME" "CAP_0805-10UF,16V,10%,X6S,C953A"
					( Origin gPackager )
				)
				( objectStatus "C9N27" )
				( pin "a"
					( attribute "PN" "1"
						( Origin gPackager )
					)
					( objectStatus "C9N27.1" )
				)
				( pin "b"
					( attribute "PN" "2"
						( Origin gPackager )
					)
					( objectStatus "C9N27.2" )
				)
			)
			( gate "@baseboard_fab2_lib.baseboard_fab2(sch_1):page209_i7"
				( attribute "CDS_LIB" "mstr_discrete"
					( Origin gPackager )
				)
				( attribute "CDS_LOCATION" "C9N26"
					( Origin gPackager )
				)
				( attribute "CDS_SEC" "1"
					( Origin gPackager )
				)
				( attribute "LOCATION" "C9N26"
					( Origin gFrontEnd )
				)
				( attribute "MATERIAL" "X6S"
					( Origin gFrontEnd )
				)
				( attribute "PACK_TYPE" "0805"
					( Origin gFrontEnd )
				)
				( attribute "PART_NUMBER" "C95333-007"
					( Origin gFrontEnd )
				)
				( attribute "PHYS_PAGE" "209"
					( Origin gFrontEnd )
				)
				( attribute "ROOM" "PVCCIN_CPU1_PWR_VR"
					( Origin gFrontEnd )
				)
				( attribute "ROT" "0"
					( Origin gFrontEnd )
				)
				( attribute "SEC" "1"
					( Origin gFrontEnd )
				)
				( attribute "SEC_TYPE" "0805"
					( Origin gFrontEnd )
				)
				( attribute "TOLERANCE" "10%"
					( Origin gFrontEnd )
				)
				( attribute "VALUE" "10UF"
					( Origin gFrontEnd )
				)
				( attribute "VER" "1"
					( Origin gFrontEnd )
				)
				( attribute "VOLTAGE" "16V"
					( Units "uVoltage" "V" 1.000000)
					( Origin gFrontEnd )
				)
				( attribute "XY" "(-6900,4025)"
					( Origin gFrontEnd )
				)
				( attribute "CHIPS_PART_NAME" "CAP"
					( Origin gPackager )
				)
				( attribute "CDS_PART_NAME" "CAP_0805-10UF,16V,10%,X6S,C953A"
					( Origin gPackager )
				)
				( objectStatus "C9N26" )
				( pin "a"
					( attribute "PN" "1"
						( Origin gPackager )
					)
					( objectStatus "C9N26.1" )
				)
				( pin "b"
					( attribute "PN" "2"
						( Origin gPackager )
					)
					( objectStatus "C9N26.2" )
				)
			)
			( gate "@baseboard_fab2_lib.baseboard_fab2(sch_1):page209_i8"
				( attribute "CDS_LIB" "mstr_discrete"
					( Origin gPackager )
				)
				( attribute "CDS_LOCATION" "C9N25"
					( Origin gPackager )
				)
				( attribute "CDS_SEC" "1"
					( Origin gPackager )
				)
				( attribute "LOCATION" "C9N25"
					( Origin gFrontEnd )
				)
				( attribute "MATERIAL" "X6S"
					( Origin gFrontEnd )
				)
				( attribute "PACK_TYPE" "0805"
					( Origin gFrontEnd )
				)
				( attribute "PART_NUMBER" "C95333-007"
					( Origin gFrontEnd )
				)
				( attribute "PHYS_PAGE" "209"
					( Origin gFrontEnd )
				)
				( attribute "ROOM" "PVCCIN_CPU1_PWR_VR"
					( Origin gFrontEnd )
				)
				( attribute "ROT" "0"
					( Origin gFrontEnd )
				)
				( attribute "SEC" "1"
					( Origin gFrontEnd )
				)
				( attribute "SEC_TYPE" "0805"
					( Origin gFrontEnd )
				)
				( attribute "TOLERANCE" "10%"
					( Origin gFrontEnd )
				)
				( attribute "VALUE" "10UF"
					( Origin gFrontEnd )
				)
				( attribute "VER" "1"
					( Origin gFrontEnd )
				)
				( attribute "VOLTAGE" "16V"
					( Units "uVoltage" "V" 1.000000)
					( Origin gFrontEnd )
				)
				( attribute "XY" "(-6625,3975)"
					( Origin gFrontEnd )
				)
				( attribute "CHIPS_PART_NAME" "CAP"
					( Origin gPackager )
				)
				( attribute "CDS_PART_NAME" "CAP_0805-10UF,16V,10%,X6S,C953A"
					( Origin gPackager )
				)
				( objectStatus "C9N25" )
				( pin "a"
					( attribute "PN" "1"
						( Origin gPackager )
					)
					( objectStatus "C9N25.1" )
				)
				( pin "b"
					( attribute "PN" "2"
						( Origin gPackager )
					)
					( objectStatus "C9N25.2" )
				)
			)
			( gate "@baseboard_fab2_lib.baseboard_fab2(sch_1):page209_i9"
				( attribute "BOM_COST" "PROC_VRD_VCCIN_CPU0"
					( Origin gFrontEnd )
				)
				( attribute "CDS_LIB" "mstr_discrete"
					( Origin gPackager )
				)
				( attribute "CDS_LOCATION" "R1E8"
					( Origin gPackager )
				)
				( attribute "CDS_SEC" "1"
					( Origin gPackager )
				)
				( attribute "LOCATION" "R1E8"
					( Origin gFrontEnd )
				)
				( attribute "MATERIAL" "CHIP"
					( Origin gFrontEnd )
				)
				( attribute "PACK_TYPE" "0402"
					( Origin gFrontEnd )
				)
				( attribute "PART_NUMBER" "G21796-017"
					( Origin gFrontEnd )
				)
				( attribute "PHYS_PAGE" "209"
					( Origin gFrontEnd )
				)
				( attribute "ROOM" "PVCCIN_CPU1_VSENSE_VR"
					( Origin gFrontEnd )
				)
				( attribute "ROT" "0"
					( Origin gFrontEnd )
				)
				( attribute "SEC" "1"
					( Origin gPackager )
				)
				( attribute "TOLERANCE" "1%"
					( Origin gFrontEnd )
				)
				( attribute "VALUE" "100.0"
					( Origin gFrontEnd )
				)
				( attribute "VER" "1"
					( Origin gFrontEnd )
				)
				( attribute "WATTAGE" "1/16W"
					( Origin gFrontEnd )
				)
				( attribute "XY" "(-5475,1050)"
					( Origin gFrontEnd )
				)
				( attribute "CHIPS_PART_NAME" "RES"
					( Origin gPackager )
				)
				( attribute "CDS_PART_NAME" "RES_0402-100.0,1%,1/16W,CHIP,GA"
					( Origin gPackager )
				)
				( objectStatus "R1E8" )
				( pin "a"
					( attribute "PN" "1"
						( Origin gPackager )
					)
					( objectStatus "R1E8.1" )
				)
				( pin "b"
					( attribute "PN" "2"
						( Origin gPackager )
					)
					( objectStatus "R1E8.2" )
				)
			)
			( gate "@baseboard_fab2_lib.baseboard_fab2(sch_1):page209_i10"
				( attribute "BOM_COST" "PROC_VRD_VCCIN_CPU0"
					( Origin gFrontEnd )
				)
				( attribute "CDS_LIB" "mstr_discrete"
					( Origin gPackager )
				)
				( attribute "CDS_LOCATION" "R1E7"
					( Origin gPackager )
				)
				( attribute "CDS_SEC" "1"
					( Origin gPackager )
				)
				( attribute "LOCATION" "R1E7"
					( Origin gFrontEnd )
				)
				( attribute "MATERIAL" "CHIP"
					( Origin gFrontEnd )
				)
				( attribute "PACK_TYPE" "0402"
					( Origin gFrontEnd )
				)
				( attribute "PART_NUMBER" "G21497-005"
					( Origin gFrontEnd )
				)
				( attribute "PHYS_PAGE" "209"
					( Origin gFrontEnd )
				)
				( attribute "ROOM" "PVCCIN_CPU1_VSENSE_VR"
					( Origin gFrontEnd )
				)
				( attribute "ROT" "0"
					( Origin gFrontEnd )
				)
				( attribute "SEC" "1"
					( Origin gPackager )
				)
				( attribute "TOLERANCE" "5%"
					( Origin gFrontEnd )
				)
				( attribute "VALUE" "0.0"
					( Origin gFrontEnd )
				)
				( attribute "VER" "1"
					( Origin gFrontEnd )
				)
				( attribute "WATTAGE" "1/16W"
					( Origin gFrontEnd )
				)
				( attribute "XY" "(-5475,1450)"
					( Origin gFrontEnd )
				)
				( attribute "CHIPS_PART_NAME" "RES"
					( Origin gPackager )
				)
				( attribute "CDS_PART_NAME" "RES_0402-0.0,5%,1/16W,CHIP,G21A"
					( Origin gPackager )
				)
				( objectStatus "R1E7" )
				( pin "a"
					( attribute "PN" "1"
						( Origin gPackager )
					)
					( objectStatus "R1E7.1" )
				)
				( pin "b"
					( attribute "PN" "2"
						( Origin gPackager )
					)
					( objectStatus "R1E7.2" )
				)
			)
			( gate "@baseboard_fab2_lib.baseboard_fab2(sch_1):page209_i11"
				( attribute "BOM_COST" "PROC_VRD_VCCIN_CPU0"
					( Origin gFrontEnd )
				)
				( attribute "CDS_LIB" "mstr_discrete"
					( Origin gPackager )
				)
				( attribute "CDS_LOCATION" "R1E6"
					( Origin gPackager )
				)
				( attribute "CDS_SEC" "1"
					( Origin gPackager )
				)
				( attribute "LOCATION" "R1E6"
					( Origin gFrontEnd )
				)
				( attribute "MATERIAL" "CHIP"
					( Origin gFrontEnd )
				)
				( attribute "PACK_TYPE" "0402"
					( Origin gFrontEnd )
				)
				( attribute "PART_NUMBER" "G21497-005"
					( Origin gFrontEnd )
				)
				( attribute "PHYS_PAGE" "209"
					( Origin gFrontEnd )
				)
				( attribute "ROOM" "PVCCIN_CPU1_VSENSE_VR"
					( Origin gFrontEnd )
				)
				( attribute "ROT" "0"
					( Origin gFrontEnd )
				)
				( attribute "SEC" "1"
					( Origin gPackager )
				)
				( attribute "TOLERANCE" "5%"
					( Origin gFrontEnd )
				)
				( attribute "VALUE" "0.0"
					( Origin gFrontEnd )
				)
				( attribute "VER" "1"
					( Origin gFrontEnd )
				)
				( attribute "WATTAGE" "1/16W"
					( Origin gFrontEnd )
				)
				( attribute "XY" "(-5500,1900)"
					( Origin gFrontEnd )
				)
				( attribute "CHIPS_PART_NAME" "RES"
					( Origin gPackager )
				)
				( attribute "CDS_PART_NAME" "RES_0402-0.0,5%,1/16W,CHIP,G21A"
					( Origin gPackager )
				)
				( objectStatus "R1E6" )
				( pin "a"
					( attribute "PN" "1"
						( Origin gPackager )
					)
					( objectStatus "R1E6.1" )
				)
				( pin "b"
					( attribute "PN" "2"
						( Origin gPackager )
					)
					( objectStatus "R1E6.2" )
				)
			)
			( gate "@baseboard_fab2_lib.baseboard_fab2(sch_1):page209_i15"
				( attribute "BOM_COST" "PROC_VRD_VCCIN_CPU0"
					( Origin gFrontEnd )
				)
				( attribute "CDS_LIB" "mstr_discrete"
					( Origin gPackager )
				)
				( attribute "CDS_LOCATION" "R1E4"
					( Origin gPackager )
				)
				( attribute "CDS_SEC" "1"
					( Origin gPackager )
				)
				( attribute "LOCATION" "R1E4"
					( Origin gFrontEnd )
				)
				( attribute "MATERIAL" "CHIP"
					( Origin gFrontEnd )
				)
				( attribute "PACK_TYPE" "0402"
					( Origin gFrontEnd )
				)
				( attribute "PART_NUMBER" "G21796-017"
					( Origin gFrontEnd )
				)
				( attribute "PHYS_PAGE" "209"
					( Origin gFrontEnd )
				)
				( attribute "ROOM" "PVCCIN_CPU1_VSENSE_VR"
					( Origin gFrontEnd )
				)
				( attribute "ROT" "0"
					( Origin gFrontEnd )
				)
				( attribute "SEC" "1"
					( Origin gPackager )
				)
				( attribute "TOLERANCE" "1%"
					( Origin gFrontEnd )
				)
				( attribute "VALUE" "100.0"
					( Origin gFrontEnd )
				)
				( attribute "VER" "1"
					( Origin gFrontEnd )
				)
				( attribute "WATTAGE" "1/16W"
					( Origin gFrontEnd )
				)
				( attribute "XY" "(-5500,2300)"
					( Origin gFrontEnd )
				)
				( attribute "CHIPS_PART_NAME" "RES"
					( Origin gPackager )
				)
				( attribute "CDS_PART_NAME" "RES_0402-100.0,1%,1/16W,CHIP,GA"
					( Origin gPackager )
				)
				( objectStatus "R1E4" )
				( pin "a"
					( attribute "PN" "1"
						( Origin gPackager )
					)
					( objectStatus "R1E4.1" )
				)
				( pin "b"
					( attribute "PN" "2"
						( Origin gPackager )
					)
					( objectStatus "R1E4.2" )
				)
			)
			( gate "@baseboard_fab2_lib.baseboard_fab2(sch_1):page209_i16"
				( attribute "CDS_LIB" "mstr_discrete"
					( Origin gPackager )
				)
				( attribute "CDS_LOCATION" "C1C26"
					( Origin gPackager )
				)
				( attribute "CDS_SEC" "1"
					( Origin gPackager )
				)
				( attribute "LOCATION" "C1C26"
					( Origin gFrontEnd )
				)
				( attribute "MATERIAL" "X6S"
					( Origin gFrontEnd )
				)
				( attribute "PACK_TYPE" "0402"
					( Origin gFrontEnd )
				)
				( attribute "PART_NUMBER" "D97712-011"
					( Origin gFrontEnd )
				)
				( attribute "PHYS_PAGE" "209"
					( Origin gFrontEnd )
				)
				( attribute "ROOM" "PVCCIN_CPU1_PWR_VR"
					( Origin gFrontEnd )
				)
				( attribute "ROT" "0"
					( Origin gFrontEnd )
				)
				( attribute "SEC" "1"
					( Origin gFrontEnd )
				)
				( attribute "SEC_TYPE" "0402"
					( Origin gFrontEnd )
				)
				( attribute "TOLERANCE" "10%"
					( Origin gFrontEnd )
				)
				( attribute "VALUE" "1.0UF"
					( Origin gFrontEnd )
				)
				( attribute "VER" "1"
					( Origin gFrontEnd )
				)
				( attribute "VOLTAGE" "16V"
					( Units "uVoltage" "V" 1.000000)
					( Origin gFrontEnd )
				)
				( attribute "XY" "(-6350,4025)"
					( Origin gFrontEnd )
				)
				( attribute "CHIPS_PART_NAME" "CAP"
					( Origin gPackager )
				)
				( attribute "CDS_PART_NAME" "CAP_0402-1.0UF,16V,10%,X6S,D97A"
					( Origin gPackager )
				)
				( objectStatus "C1C26" )
				( pin "a"
					( attribute "PN" "1"
						( Origin gPackager )
					)
					( objectStatus "C1C26.1" )
				)
				( pin "b"
					( attribute "PN" "2"
						( Origin gPackager )
					)
					( objectStatus "C1C26.2" )
				)
			)
			( gate "@baseboard_fab2_lib.baseboard_fab2(sch_1):page209_i17"
				( attribute "CDS_LIB" "dev_discrete"
					( Origin gPackager )
				)
				( attribute "CDS_LOCATION" "C1C25"
					( Origin gPackager )
				)
				( attribute "CDS_SEC" "1"
					( Origin gPackager )
				)
				( attribute "LOCATION" "C1C25"
					( Origin gFrontEnd )
				)
				( attribute "MATERIAL" "X7R"
					( Origin gFrontEnd )
				)
				( attribute "PACK_TYPE" "0402V"
					( Origin gFrontEnd )
				)
				( attribute "PART_NUMBER" "A36096-030"
					( Origin gFrontEnd )
				)
				( attribute "PHYS_PAGE" "209"
					( Origin gFrontEnd )
				)
				( attribute "ROOM" "PVCCIN_CPU1_PWR_VR"
					( Origin gFrontEnd )
				)
				( attribute "ROT" "0"
					( Origin gFrontEnd )
				)
				( attribute "SEC" "1"
					( Origin gFrontEnd )
				)
				( attribute "SEC_TYPE" "0402V"
					( Origin gFrontEnd )
				)
				( attribute "TOLERANCE" "10%"
					( Origin gFrontEnd )
				)
				( attribute "VALUE" "0.1UF"
					( Origin gFrontEnd )
				)
				( attribute "VER" "1"
					( Origin gFrontEnd )
				)
				( attribute "VOLTAGE" "16V"
					( Units "uVoltage" "V" 1.000000)
					( Origin gFrontEnd )
				)
				( attribute "XY" "(-6000,4050)"
					( Origin gFrontEnd )
				)
				( attribute "CHIPS_PART_NAME" "CAP_A"
					( Origin gPackager )
				)
				( attribute "CDS_PART_NAME" "CAP_A_0402V-0.1UF,16V,10%,X7R,A"
					( Origin gPackager )
				)
				( objectStatus "C1C25" )
				( pin "a"
					( attribute "PN" "1"
						( Origin gPackager )
					)
					( objectStatus "C1C25.1" )
				)
				( pin "b"
					( attribute "PN" "2"
						( Origin gPackager )
					)
					( objectStatus "C1C25.2" )
				)
			)
			( gate "@baseboard_fab2_lib.baseboard_fab2(sch_1):page209_i18"
				( attribute "CDS_LIB" "mstr_discrete"
					( Origin gPackager )
				)
				( attribute "CDS_LOCATION" "C1D32"
					( Origin gPackager )
				)
				( attribute "CDS_SEC" "1"
					( Origin gPackager )
				)
				( attribute "LOCATION" "C1D32"
					( Origin gFrontEnd )
				)
				( attribute "MATERIAL" "X6S"
					( Origin gFrontEnd )
				)
				( attribute "PACK_TYPE" "0402"
					( Origin gFrontEnd )
				)
				( attribute "PART_NUMBER" "D97712-011"
					( Origin gFrontEnd )
				)
				( attribute "PHYS_PAGE" "209"
					( Origin gFrontEnd )
				)
				( attribute "ROOM" "PVCCIN_CPU1_PWR_VR"
					( Origin gFrontEnd )
				)
				( attribute "ROT" "0"
					( Origin gFrontEnd )
				)
				( attribute "SEC" "1"
					( Origin gFrontEnd )
				)
				( attribute "SEC_TYPE" "0402"
					( Origin gFrontEnd )
				)
				( attribute "TOLERANCE" "10%"
					( Origin gFrontEnd )
				)
				( attribute "VALUE" "1.0UF"
					( Origin gFrontEnd )
				)
				( attribute "VER" "1"
					( Origin gFrontEnd )
				)
				( attribute "VOLTAGE" "16V"
					( Units "uVoltage" "V" 1.000000)
					( Origin gFrontEnd )
				)
				( attribute "XY" "(-5625,4025)"
					( Origin gFrontEnd )
				)
				( attribute "CHIPS_PART_NAME" "CAP"
					( Origin gPackager )
				)
				( attribute "CDS_PART_NAME" "CAP_0402-1.0UF,16V,10%,X6S,D97A"
					( Origin gPackager )
				)
				( objectStatus "C1D32" )
				( pin "a"
					( attribute "PN" "1"
						( Origin gPackager )
					)
					( objectStatus "C1D32.1" )
				)
				( pin "b"
					( attribute "PN" "2"
						( Origin gPackager )
					)
					( objectStatus "C1D32.2" )
				)
			)
			( gate "@baseboard_fab2_lib.baseboard_fab2(sch_1):page209_i20"
				( attribute "CDS_LIB" "mstr_discrete"
					( Origin gPackager )
				)
				( attribute "CDS_LOCATION" "C1C24"
					( Origin gPackager )
				)
				( attribute "CDS_SEC" "1"
					( Origin gPackager )
				)
				( attribute "LOCATION" "C1C24"
					( Origin gFrontEnd )
				)
				( attribute "MATERIAL" "X7R"
					( Origin gFrontEnd )
				)
				( attribute "NO_XNET_CONNECTION" "1"
					( Origin gFrontEnd )
				)
				( attribute "PACK_TYPE" "0402"
					( Origin gFrontEnd )
				)
				( attribute "PART_NUMBER" "A36096-104"
					( Origin gFrontEnd )
				)
				( attribute "PHYS_PAGE" "209"
					( Origin gFrontEnd )
				)
				( attribute "ROOM" "PVCCIN_CPU1_PWR_VR"
					( Origin gFrontEnd )
				)
				( attribute "ROT" "2"
					( Origin gFrontEnd )
				)
				( attribute "SEC" "1"
					( Origin gFrontEnd )
				)
				( attribute "SEC_TYPE" "0402"
					( Origin gFrontEnd )
				)
				( attribute "SPOF" "TRUE"
					( Origin gFrontEnd )
				)
				( attribute "TOLERANCE" "10%"
					( Origin gFrontEnd )
				)
				( attribute "VALUE" "0.220UF"
					( Origin gFrontEnd )
				)
				( attribute "VER" "1"
					( Origin gFrontEnd )
				)
				( attribute "VOLTAGE" "16V"
					( Units "uVoltage" "V" 1.000000)
					( Origin gFrontEnd )
				)
				( attribute "XY" "(-5575,3450)"
					( Origin gFrontEnd )
				)
				( attribute "CHIPS_PART_NAME" "CAP"
					( Origin gPackager )
				)
				( attribute "CDS_PART_NAME" "CAP_0402-0.220UF,16V,10%,X7R,AA"
					( Origin gPackager )
				)
				( objectStatus "C1C24" )
				( pin "a"
					( attribute "PN" "1"
						( Origin gPackager )
					)
					( objectStatus "C1C24.1" )
				)
				( pin "b"
					( attribute "PN" "2"
						( Origin gPackager )
					)
					( objectStatus "C1C24.2" )
				)
			)
			( gate "@baseboard_fab2_lib.baseboard_fab2(sch_1):page209_i21"
				( attribute "CDS_LIB" "dev_discrete"
					( Origin gPackager )
				)
				( attribute "CDS_LOCATION" "C1C18"
					( Origin gPackager )
				)
				( attribute "CDS_SEC" "1"
					( Origin gPackager )
				)
				( attribute "LOCATION" "C1C18"
					( Origin gFrontEnd )
				)
				( attribute "MATERIAL" "X6S"
					( Origin gFrontEnd )
				)
				( attribute "PACK_TYPE" "0402V"
					( Origin gFrontEnd )
				)
				( attribute "PART_NUMBER" "D97712-004"
					( Origin gFrontEnd )
				)
				( attribute "PHYS_PAGE" "209"
					( Origin gFrontEnd )
				)
				( attribute "ROOM" "PVCCIN_CPU1_PWR_VR"
					( Origin gFrontEnd )
				)
				( attribute "ROT" "2"
					( Origin gFrontEnd )
				)
				( attribute "SEC" "1"
					( Origin gFrontEnd )
				)
				( attribute "SEC_TYPE" "0402V"
					( Origin gFrontEnd )
				)
				( attribute "TOLERANCE" "10%"
					( Origin gFrontEnd )
				)
				( attribute "VALUE" "1.0UF"
					( Origin gFrontEnd )
				)
				( attribute "VER" "1"
					( Origin gFrontEnd )
				)
				( attribute "VOLTAGE" "6.3V"
					( Units "uVoltage" "V" 1.000000)
					( Origin gFrontEnd )
				)
				( attribute "XY" "(-4975,4050)"
					( Origin gFrontEnd )
				)
				( attribute "CHIPS_PART_NAME" "CAP_A"
					( Origin gPackager )
				)
				( attribute "CDS_PART_NAME" "CAP_A_0402V-1.0UF,6.3V,10%,X6SA"
					( Origin gPackager )
				)
				( objectStatus "C1C18" )
				( pin "a"
					( attribute "PN" "1"
						( Origin gPackager )
					)
					( objectStatus "C1C18.1" )
				)
				( pin "b"
					( attribute "PN" "2"
						( Origin gPackager )
					)
					( objectStatus "C1C18.2" )
				)
			)
			( gate "@baseboard_fab2_lib.baseboard_fab2(sch_1):page209_i22"
				( attribute "CDS_LIB" "mstr_discrete"
					( Origin gPackager )
				)
				( attribute "CDS_LOCATION" "C1D33"
					( Origin gPackager )
				)
				( attribute "CDS_SEC" "1"
					( Origin gPackager )
				)
				( attribute "LOCATION" "C1D33"
					( Origin gFrontEnd )
				)
				( attribute "MATERIAL" "X7R"
					( Origin gFrontEnd )
				)
				( attribute "PACK_TYPE" "0402"
					( Origin gFrontEnd )
				)
				( attribute "PART_NUMBER" "A36096-155"
					( Origin gFrontEnd )
				)
				( attribute "PHYS_PAGE" "209"
					( Origin gFrontEnd )
				)
				( attribute "ROOM" "PVCCIN_CPU1_PWR_VR"
					( Origin gFrontEnd )
				)
				( attribute "ROT" "0"
					( Origin gFrontEnd )
				)
				( attribute "SEC" "1"
					( Origin gFrontEnd )
				)
				( attribute "SEC_TYPE" "0402"
					( Origin gFrontEnd )
				)
				( attribute "TOLERANCE" "10%"
					( Origin gFrontEnd )
				)
				( attribute "VALUE" "0.22UF"
					( Origin gFrontEnd )
				)
				( attribute "VER" "1"
					( Origin gFrontEnd )
				)
				( attribute "VOLTAGE" "16V"
					( Units "uVoltage" "V" 1.000000)
					( Origin gFrontEnd )
				)
				( attribute "XY" "(-4875,4050)"
					( Origin gFrontEnd )
				)
				( attribute "CHIPS_PART_NAME" "CAP"
					( Origin gPackager )
				)
				( attribute "CDS_PART_NAME" "CAP_0402-0.22UF,16V,10%,X7R,A3A"
					( Origin gPackager )
				)
				( objectStatus "C1D33" )
				( pin "a"
					( attribute "PN" "1"
						( Origin gPackager )
					)
					( objectStatus "C1D33.1" )
				)
				( pin "b"
					( attribute "PN" "2"
						( Origin gPackager )
					)
					( objectStatus "C1D33.2" )
				)
			)
			( gate "@baseboard_fab2_lib.baseboard_fab2(sch_1):page209_i24"
				( attribute "CDS_LIB" "mstr_discrete"
					( Origin gPackager )
				)
				( attribute "CDS_LOCATION" "R9P32"
					( Origin gPackager )
				)
				( attribute "CDS_SEC" "1"
					( Origin gPackager )
				)
				( attribute "LOCATION" "R9P32"
					( Origin gFrontEnd )
				)
				( attribute "MATERIAL" "CHIP"
					( Origin gFrontEnd )
				)
				( attribute "PACK_TYPE" "0402"
					( Origin gFrontEnd )
				)
				( attribute "PART_NUMBER" "G21796-090"
					( Origin gFrontEnd )
				)
				( attribute "PHYS_PAGE" "209"
					( Origin gFrontEnd )
				)
				( attribute "ROOM" "PVCCIN_CPU1_PWR_VR"
					( Origin gFrontEnd )
				)
				( attribute "ROT" "0"
					( Origin gFrontEnd )
				)
				( attribute "SEC" "1"
					( Origin gFrontEnd )
				)
				( attribute "SEC_TYPE" "0402"
					( Origin gFrontEnd )
				)
				( attribute "TOLERANCE" "1%"
					( Origin gFrontEnd )
				)
				( attribute "VALUE" "1.0"
					( Origin gFrontEnd )
				)
				( attribute "VER" "1"
					( Origin gFrontEnd )
				)
				( attribute "WATTAGE" "1/16W"
					( Origin gFrontEnd )
				)
				( attribute "XY" "(-5300,4650)"
					( Origin gFrontEnd )
				)
				( attribute "CHIPS_PART_NAME" "RES"
					( Origin gPackager )
				)
				( attribute "CDS_PART_NAME" "RES_0402-1.0,1%,1/16W,CHIP,G21A"
					( Origin gPackager )
				)
				( objectStatus "R9P32" )
				( pin "a"
					( attribute "PN" "1"
						( Origin gPackager )
					)
					( objectStatus "R9P32.1" )
				)
				( pin "b"
					( attribute "PN" "2"
						( Origin gPackager )
					)
					( objectStatus "R9P32.2" )
				)
			)
			( gate "@baseboard_fab2_lib.baseboard_fab2(sch_1):page209_i30"
				( attribute "CDS_LIB" "dev_discrete"
					( Origin gPackager )
				)
				( attribute "CDS_LOCATION" "C1B16"
					( Origin gPackager )
				)
				( attribute "CDS_SEC" "1"
					( Origin gPackager )
				)
				( attribute "LOCATION" "C1B16"
					( Origin gFrontEnd )
				)
				( attribute "MATERIAL" "EMPTY"
					( Origin gFrontEnd )
				)
				( attribute "PACK_TYPE" "0402V"
					( Origin gFrontEnd )
				)
				( attribute "PART_NUMBER" "A36096-030"
					( Origin gFrontEnd )
				)
				( attribute "PHYS_PAGE" "209"
					( Origin gFrontEnd )
				)
				( attribute "ROOM" "PVCCIN_CPU1_FILTER_VR"
					( Origin gFrontEnd )
				)
				( attribute "ROT" "0"
					( Origin gFrontEnd )
				)
				( attribute "SEC" "1"
					( Origin gPackager )
				)
				( attribute "TOLERANCE" "10%"
					( Origin gFrontEnd )
				)
				( attribute "VALUE" "0.1UF"
					( Origin gFrontEnd )
				)
				( attribute "VER" "1"
					( Origin gFrontEnd )
				)
				( attribute "VOLTAGE" "16V"
					( Units "uVoltage" "V" 1.000000)
					( Origin gFrontEnd )
				)
				( attribute "XY" "(-2250,1125)"
					( Origin gFrontEnd )
				)
				( attribute "CHIPS_PART_NAME" "CAP_A"
					( Origin gPackager )
				)
				( attribute "CDS_PART_NAME" "CAP_A_0402V-0.1UF,16V,10%,EMPTA"
					( Origin gPackager )
				)
				( objectStatus "C1B16" )
				( pin "a"
					( attribute "PN" "1"
						( Origin gPackager )
					)
					( objectStatus "C1B16.1" )
				)
				( pin "b"
					( attribute "PN" "2"
						( Origin gPackager )
					)
					( objectStatus "C1B16.2" )
				)
			)
			( gate "@baseboard_fab2_lib.baseboard_fab2(sch_1):page209_i32"
				( attribute "CDS_LIB" "mstr_discrete"
					( Origin gPackager )
				)
				( attribute "CDS_LOCATION" "L1B2"
					( Origin gPackager )
				)
				( attribute "CDS_SEC" "1"
					( Origin gPackager )
				)
				( attribute "LOCATION" "L1B2"
					( Origin gFrontEnd )
				)
				( attribute "MATERIAL" "IND"
					( Origin gFrontEnd )
				)
				( attribute "PACK_TYPE" "SM"
					( Origin gFrontEnd )
				)
				( attribute "PART_NUMBER" "D92183-019"
					( Origin gFrontEnd )
				)
				( attribute "PHYS_PAGE" "209"
					( Origin gFrontEnd )
				)
				( attribute "ROOM" "PVCCIN_CPU1_FILTER_VR"
					( Origin gFrontEnd )
				)
				( attribute "ROT" "0"
					( Origin gFrontEnd )
				)
				( attribute "SEC" "1"
					( Origin gFrontEnd )
				)
				( attribute "SEC_TYPE" "SM"
					( Origin gFrontEnd )
				)
				( attribute "VALUE" "100NH"
					( Origin gFrontEnd )
				)
				( attribute "VER" "1"
					( Origin gFrontEnd )
				)
				( attribute "XY" "(-3000,2250)"
					( Origin gFrontEnd )
				)
				( attribute "CHIPS_PART_NAME" "INDUCTOR"
					( Origin gPackager )
				)
				( attribute "CDS_PART_NAME" "INDUCTOR_SM-100NH,IND,D92183-0A"
					( Origin gPackager )
				)
				( objectStatus "L1B2" )
				( pin "ina"
					( attribute "PN" "1"
						( Origin gPackager )
					)
					( objectStatus "L1B2.1" )
				)
				( pin "inb"
					( attribute "PN" "2"
						( Origin gPackager )
					)
					( objectStatus "L1B2.2" )
				)
			)
			( gate "@baseboard_fab2_lib.baseboard_fab2(sch_1):page209_i35"
				( attribute "CDS_LIB" "mstr_discrete"
					( Origin gPackager )
				)
				( attribute "CDS_LOCATION" "C1C1"
					( Origin gPackager )
				)
				( attribute "CDS_SEC" "1"
					( Origin gPackager )
				)
				( attribute "LOCATION" "C1C1"
					( Origin gFrontEnd )
				)
				( attribute "MATERIAL" "OSCON"
					( Origin gFrontEnd )
				)
				( attribute "PACK_TYPE" "2626"
					( Origin gFrontEnd )
				)
				( attribute "PART_NUMBER" "A31228-047"
					( Origin gFrontEnd )
				)
				( attribute "PHYS_PAGE" "209"
					( Origin gFrontEnd )
				)
				( attribute "ROOM" "PVCCIN_CPU1_FILTER_VR"
					( Origin gFrontEnd )
				)
				( attribute "ROT" "0"
					( Origin gFrontEnd )
				)
				( attribute "SEC" "1"
					( Origin gFrontEnd )
				)
				( attribute "SEC_TYPE" "2626"
					( Origin gFrontEnd )
				)
				( attribute "TOLERANCE" "20%"
					( Origin gFrontEnd )
				)
				( attribute "VALUE" "270UF"
					( Origin gFrontEnd )
				)
				( attribute "VER" "1"
					( Origin gFrontEnd )
				)
				( attribute "VOLTAGE" "16V"
					( Units "uVoltage" "V" 1.000000)
					( Origin gFrontEnd )
				)
				( attribute "XY" "(-1425,2075)"
					( Origin gFrontEnd )
				)
				( attribute "CHIPS_PART_NAME" "CAPP"
					( Origin gPackager )
				)
				( attribute "CDS_PART_NAME" "CAPP_2626-270UF,16V,20%,OSCON,A"
					( Origin gPackager )
				)
				( objectStatus "C1C1" )
				( pin "a"
					( attribute "PN" "1"
						( Origin gPackager )
					)
					( objectStatus "C1C1.1" )
				)
				( pin "b"
					( attribute "PN" "2"
						( Origin gPackager )
					)
					( objectStatus "C1C1.2" )
				)
			)
			( gate "@baseboard_fab2_lib.baseboard_fab2(sch_1):page209_i37"
				( attribute "CDS_LIB" "mstr_discrete"
					( Origin gPackager )
				)
				( attribute "CDS_LOCATION" "C1E18"
					( Origin gPackager )
				)
				( attribute "CDS_SEC" "1"
					( Origin gPackager )
				)
				( attribute "LOCATION" "C1E18"
					( Origin gFrontEnd )
				)
				( attribute "MATERIAL" "OSCON"
					( Origin gFrontEnd )
				)
				( attribute "PACK_TYPE" "2626"
					( Origin gFrontEnd )
				)
				( attribute "PART_NUMBER" "A31228-047"
					( Origin gFrontEnd )
				)
				( attribute "PHYS_PAGE" "209"
					( Origin gFrontEnd )
				)
				( attribute "ROOM" "PVCCIN_CPU1_FILTER_VR"
					( Origin gFrontEnd )
				)
				( attribute "ROT" "0"
					( Origin gFrontEnd )
				)
				( attribute "SEC" "1"
					( Origin gFrontEnd )
				)
				( attribute "SEC_TYPE" "2626"
					( Origin gFrontEnd )
				)
				( attribute "TOLERANCE" "20%"
					( Origin gFrontEnd )
				)
				( attribute "VALUE" "270UF"
					( Origin gFrontEnd )
				)
				( attribute "VER" "1"
					( Origin gFrontEnd )
				)
				( attribute "VOLTAGE" "16V"
					( Units "uVoltage" "V" 1.000000)
					( Origin gFrontEnd )
				)
				( attribute "XY" "(-950,2050)"
					( Origin gFrontEnd )
				)
				( attribute "CHIPS_PART_NAME" "CAPP"
					( Origin gPackager )
				)
				( attribute "CDS_PART_NAME" "CAPP_2626-270UF,16V,20%,OSCON,A"
					( Origin gPackager )
				)
				( objectStatus "C1E18" )
				( pin "a"
					( attribute "PN" "1"
						( Origin gPackager )
					)
					( objectStatus "C1E18.1" )
				)
				( pin "b"
					( attribute "PN" "2"
						( Origin gPackager )
					)
					( objectStatus "C1E18.2" )
				)
			)
			( gate "@baseboard_fab2_lib.baseboard_fab2(sch_1):page209_i38"
				( attribute "CDS_LIB" "mstr_discrete"
					( Origin gPackager )
				)
				( attribute "CDS_LOCATION" "C1C2"
					( Origin gPackager )
				)
				( attribute "CDS_SEC" "1"
					( Origin gPackager )
				)
				( attribute "LOCATION" "C1C2"
					( Origin gFrontEnd )
				)
				( attribute "MATERIAL" "OSCON"
					( Origin gFrontEnd )
				)
				( attribute "PACK_TYPE" "2626"
					( Origin gFrontEnd )
				)
				( attribute "PART_NUMBER" "A31228-047"
					( Origin gFrontEnd )
				)
				( attribute "PHYS_PAGE" "209"
					( Origin gFrontEnd )
				)
				( attribute "ROOM" "PVCCIN_CPU1_FILTER_VR"
					( Origin gFrontEnd )
				)
				( attribute "ROT" "0"
					( Origin gFrontEnd )
				)
				( attribute "SEC" "1"
					( Origin gFrontEnd )
				)
				( attribute "SEC_TYPE" "2626"
					( Origin gFrontEnd )
				)
				( attribute "TOLERANCE" "20%"
					( Origin gFrontEnd )
				)
				( attribute "VALUE" "270UF"
					( Origin gFrontEnd )
				)
				( attribute "VER" "1"
					( Origin gFrontEnd )
				)
				( attribute "VOLTAGE" "16V"
					( Units "uVoltage" "V" 1.000000)
					( Origin gFrontEnd )
				)
				( attribute "XY" "(-600,2050)"
					( Origin gFrontEnd )
				)
				( attribute "CHIPS_PART_NAME" "CAPP"
					( Origin gPackager )
				)
				( attribute "CDS_PART_NAME" "CAPP_2626-270UF,16V,20%,OSCON,A"
					( Origin gPackager )
				)
				( objectStatus "C1C2" )
				( pin "a"
					( attribute "PN" "1"
						( Origin gPackager )
					)
					( objectStatus "C1C2.1" )
				)
				( pin "b"
					( attribute "PN" "2"
						( Origin gPackager )
					)
					( objectStatus "C1C2.2" )
				)
			)
			( gate "@baseboard_fab2_lib.baseboard_fab2(sch_1):page209_i39"
				( attribute "CDS_LIB" "mstr_discrete"
					( Origin gPackager )
				)
				( attribute "CDS_LOCATION" "R1B20"
					( Origin gPackager )
				)
				( attribute "CDS_SEC" "1"
					( Origin gPackager )
				)
				( attribute "LOCATION" "R1B20"
					( Origin gFrontEnd )
				)
				( attribute "MATERIAL" "CHIP"
					( Origin gFrontEnd )
				)
				( attribute "PACK_TYPE" "2010"
					( Origin gFrontEnd )
				)
				( attribute "PART_NUMBER" "E30969-002"
					( Origin gFrontEnd )
				)
				( attribute "PHYS_PAGE" "209"
					( Origin gFrontEnd )
				)
				( attribute "ROOM" "PVCCIN_CPU1_FILTER_VR"
					( Origin gFrontEnd )
				)
				( attribute "ROT" "0"
					( Origin gFrontEnd )
				)
				( attribute "SEC" "1"
					( Origin gFrontEnd )
				)
				( attribute "SEC_TYPE" "2010"
					( Origin gFrontEnd )
				)
				( attribute "TOLERANCE" "1%"
					( Origin gFrontEnd )
				)
				( attribute "VALUE" "0.001"
					( Origin gFrontEnd )
				)
				( attribute "VER" "1"
					( Origin gFrontEnd )
				)
				( attribute "WATTAGE" "1W"
					( Origin gFrontEnd )
				)
				( attribute "XY" "(-1850,2250)"
					( Origin gFrontEnd )
				)
				( attribute "CHIPS_PART_NAME" "RES"
					( Origin gPackager )
				)
				( attribute "CDS_PART_NAME" "RES_2010-0.001,1%,1W,CHIP,E309A"
					( Origin gPackager )
				)
				( objectStatus "R1B20" )
				( pin "a"
					( attribute "PN" "1"
						( Origin gPackager )
					)
					( objectStatus "R1B20.1" )
				)
				( pin "b"
					( attribute "PN" "2"
						( Origin gPackager )
					)
					( objectStatus "R1B20.2" )
				)
			)
			( gate "@baseboard_fab2_lib.baseboard_fab2(sch_1):page209_i40"
				( attribute "CDS_LIB" "mstr_discrete"
					( Origin gPackager )
				)
				( attribute "CDS_LOCATION" "L1C2"
					( Origin gPackager )
				)
				( attribute "CDS_SEC" "1"
					( Origin gPackager )
				)
				( attribute "LOCATION" "L1C2"
					( Origin gFrontEnd )
				)
				( attribute "MATERIAL" "IND"
					( Origin gFrontEnd )
				)
				( attribute "PACK_TYPE" "SM"
					( Origin gFrontEnd )
				)
				( attribute "PART_NUMBER" "D92183-034"
					( Origin gFrontEnd )
				)
				( attribute "PHYS_PAGE" "209"
					( Origin gFrontEnd )
				)
				( attribute "ROOM" "PVCCIN_CPU1_PWR_VR"
					( Origin gFrontEnd )
				)
				( attribute "ROT" "0"
					( Origin gFrontEnd )
				)
				( attribute "SEC" "1"
					( Origin gPackager )
				)
				( attribute "VALUE" "0.12UH"
					( Origin gFrontEnd )
				)
				( attribute "VER" "1"
					( Origin gFrontEnd )
				)
				( attribute "XY" "(-1450,3475)"
					( Origin gFrontEnd )
				)
				( attribute "CHIPS_PART_NAME" "INDUCTOR"
					( Origin gPackager )
				)
				( attribute "CDS_PART_NAME" "INDUCTOR_SM-0.12UH,IND,D92183-A"
					( Origin gPackager )
				)
				( objectStatus "L1C2" )
				( pin "ina"
					( attribute "PN" "1"
						( Origin gPackager )
					)
					( objectStatus "L1C2.1" )
				)
				( pin "inb"
					( attribute "PN" "2"
						( Origin gPackager )
					)
					( objectStatus "L1C2.2" )
				)
			)
			( gate "@baseboard_fab2_lib.baseboard_fab2(sch_1):page209_i42"
				( attribute "BOM_COST" "PROC_VRD_VCCIN_CPU0"
					( Origin gFrontEnd )
				)
				( attribute "CDS_LIB" "dev_discrete"
					( Origin gPackager )
				)
				( attribute "CDS_LOCATION" "C1D24"
					( Origin gPackager )
				)
				( attribute "CDS_SEC" "1"
					( Origin gPackager )
				)
				( attribute "LOCATION" "C1D24"
					( Origin gFrontEnd )
				)
				( attribute "MATERIAL" "X6S"
					( Origin gFrontEnd )
				)
				( attribute "PACK_TYPE" "0603V"
					( Origin gFrontEnd )
				)
				( attribute "PART_NUMBER" "E15431-004"
					( Origin gFrontEnd )
				)
				( attribute "PHYS_PAGE" "209"
					( Origin gFrontEnd )
				)
				( attribute "ROOM" "PVCCIN_CPU1_PWR_VR"
					( Origin gFrontEnd )
				)
				( attribute "ROT" "0"
					( Origin gFrontEnd )
				)
				( attribute "SEC" "1"
					( Origin gFrontEnd )
				)
				( attribute "SEC_TYPE" "0603V"
					( Origin gFrontEnd )
				)
				( attribute "TOLERANCE" "20%"
					( Origin gFrontEnd )
				)
				( attribute "VALUE" "22.0UF"
					( Origin gFrontEnd )
				)
				( attribute "VER" "1"
					( Origin gFrontEnd )
				)
				( attribute "VOLTAGE" "4V"
					( Units "uVoltage" "V" 1.000000)
					( Origin gFrontEnd )
				)
				( attribute "XY" "(-750,3225)"
					( Origin gFrontEnd )
				)
				( attribute "CHIPS_PART_NAME" "CAP_A"
					( Origin gPackager )
				)
				( attribute "CDS_PART_NAME" "CAP_A_0603V-22.0UF,4V,20%,X6S,A"
					( Origin gPackager )
				)
				( objectStatus "C1D24" )
				( pin "a"
					( attribute "PN" "1"
						( Origin gPackager )
					)
					( objectStatus "C1D24.1" )
				)
				( pin "b"
					( attribute "PN" "2"
						( Origin gPackager )
					)
					( objectStatus "C1D24.2" )
				)
			)
			( gate "@baseboard_fab2_lib.baseboard_fab2(sch_1):page209_i52"
				( attribute "CDS_LIB" "mstr_analog"
					( Origin gPackager )
				)
				( attribute "CDS_LOCATION" "U1B3"
					( Origin gPackager )
				)
				( attribute "CDS_SEC" "1"
					( Origin gPackager )
				)
				( attribute "LOCATION" "U1B3"
					( Origin gFrontEnd )
				)
				( attribute "MATERIAL" "EMPTY"
					( Origin gFrontEnd )
				)
				( attribute "PACK_TYPE" "SM"
					( Origin gFrontEnd )
				)
				( attribute "PART_NUMBER" "G12194-001"
					( Origin gFrontEnd )
				)
				( attribute "PHYS_PAGE" "209"
					( Origin gFrontEnd )
				)
				( attribute "ROOM" "PVCCIN_CPU1_FILTER_VR"
					( Origin gFrontEnd )
				)
				( attribute "ROT" "2"
					( Origin gFrontEnd )
				)
				( attribute "SEC" "1"
					( Origin gFrontEnd )
				)
				( attribute "SEC_TYPE" "SM"
					( Origin gFrontEnd )
				)
				( attribute "VER" "1"
					( Origin gFrontEnd )
				)
				( attribute "XY" "(-2775,1350)"
					( Origin gFrontEnd )
				)
				( attribute "CHIPS_PART_NAME" "ADM4073"
					( Origin gPackager )
				)
				( attribute "CDS_PART_NAME" "ADM4073_SM-EMPTY,G12194-001"
					( Origin gPackager )
				)
				( objectStatus "U1B3" )
				( pin "gnd(0)"
					( attribute "PN" "1"
						( Origin gPackager )
					)
					( objectStatus "U1B3.1" )
				)
				( pin "gnd(1)"
					( attribute "PN" "2"
						( Origin gPackager )
					)
					( objectStatus "U1B3.2" )
				)
				( pin "\out\"
					( attribute "PN" "6"
						( Origin gPackager )
					)
					( objectStatus "U1B3.6" )
				)
				( pin "rsn"
					( attribute "PN" "5"
						( Origin gPackager )
					)
					( objectStatus "U1B3.5" )
				)
				( pin "rsp"
					( attribute "PN" "4"
						( Origin gPackager )
					)
					( objectStatus "U1B3.4" )
				)
				( pin "vcc"
					( attribute "PN" "3"
						( Origin gPackager )
					)
					( objectStatus "U1B3.3" )
				)
			)
			( gate "@baseboard_fab2_lib.baseboard_fab2(sch_1):page209_i55"
				( attribute "CDS_LIB" "dev_discrete"
					( Origin gPackager )
				)
				( attribute "CDS_LOCATION" "C9P20"
					( Origin gPackager )
				)
				( attribute "CDS_SEC" "1"
					( Origin gPackager )
				)
				( attribute "LOCATION" "C9P20"
					( Origin gFrontEnd )
				)
				( attribute "MATERIAL" "X6S"
					( Origin gFrontEnd )
				)
				( attribute "PACK_TYPE" "0603V"
					( Origin gFrontEnd )
				)
				( attribute "PART_NUMBER" "E15431-004"
					( Origin gFrontEnd )
				)
				( attribute "PHYS_PAGE" "209"
					( Origin gFrontEnd )
				)
				( attribute "ROT" "0"
					( Origin gFrontEnd )
				)
				( attribute "SEC" "1"
					( Origin gFrontEnd )
				)
				( attribute "SEC_TYPE" "0603V"
					( Origin gFrontEnd )
				)
				( attribute "TOLERANCE" "20%"
					( Origin gFrontEnd )
				)
				( attribute "VALUE" "22.0UF"
					( Origin gFrontEnd )
				)
				( attribute "VER" "1"
					( Origin gFrontEnd )
				)
				( attribute "VOLTAGE" "4V"
					( Units "uVoltage" "V" 1.000000)
					( Origin gFrontEnd )
				)
				( attribute "XY" "(-375,3250)"
					( Origin gFrontEnd )
				)
				( attribute "CHIPS_PART_NAME" "CAP_A"
					( Origin gPackager )
				)
				( attribute "CDS_PART_NAME" "CAP_A_0603V-22.0UF,4V,20%,X6S,A"
					( Origin gPackager )
				)
				( objectStatus "C9P20" )
				( pin "a"
					( attribute "PN" "1"
						( Origin gPackager )
					)
					( objectStatus "C9P20.1" )
				)
				( pin "b"
					( attribute "PN" "2"
						( Origin gPackager )
					)
					( objectStatus "C9P20.2" )
				)
			)
			( gate "@baseboard_fab2_lib.baseboard_fab2(sch_1):page209_i56"
				( attribute "CDS_LIB" "mstr_discrete"
					( Origin gPackager )
				)
				( attribute "CDS_LOCATION" "EU1C3"
					( Origin gPackager )
				)
				( attribute "CDS_SEC" "1"
					( Origin gPackager )
				)
				( attribute "LOCATION" "EU1C3"
					( Origin gFrontEnd )
				)
				( attribute "MATERIAL" "IC"
					( Origin gFrontEnd )
				)
				( attribute "PACK_TYPE" "SM"
					( Origin gFrontEnd )
				)
				( attribute "PART_NUMBER" "H73688-001"
					( Origin gFrontEnd )
				)
				( attribute "PHYS_PAGE" "209"
					( Origin gFrontEnd )
				)
				( attribute "ROOM" "PVCCIN_CPU1_PWR_VR"
					( Origin gFrontEnd )
				)
				( attribute "ROT" "0"
					( Origin gFrontEnd )
				)
				( attribute "SEC" "1"
					( Origin gFrontEnd )
				)
				( attribute "SEC_TYPE" "SM"
					( Origin gFrontEnd )
				)
				( attribute "VALUE" "IR35411"
					( Origin gFrontEnd )
				)
				( attribute "VER" "1"
					( Origin gFrontEnd )
				)
				( attribute "XY" "(-3250,3775)"
					( Origin gFrontEnd )
				)
				( attribute "CHIPS_PART_NAME" "IR354XX"
					( Origin gPackager )
				)
				( attribute "CDS_PART_NAME" "IR354XX_SM-IR35411,IC,H73688-0A"
					( Origin gPackager )
				)
				( objectStatus "EU1C3" )
				( pin "boost"
					( attribute "PN" "33"
						( Origin gPackager )
					)
					( objectStatus "EU1C3.33" )
				)
				( pin "en"
					( attribute "PN" "35"
						( Origin gPackager )
					)
					( objectStatus "EU1C3.35" )
				)
				( pin "gl(0)"
					( attribute "PN" "6"
						( Origin gPackager )
					)
					( objectStatus "EU1C3.6" )
				)
				( pin "gl(1)"
					( attribute "PN" "41"
						( Origin gPackager )
					)
					( objectStatus "EU1C3.41" )
				)
				( pin "iout"
					( attribute "PN" "38"
						( Origin gPackager )
					)
					( objectStatus "EU1C3.38" )
				)
				( pin "lgnd"
					( attribute "PN" "2"
						( Origin gPackager )
					)
					( objectStatus "EU1C3.2" )
				)
				( pin "nc"
					( attribute "PN" "31"
						( Origin gPackager )
					)
					( objectStatus "EU1C3.31" )
				)
				( pin "ocset"
					( attribute "PN" "37"
						( Origin gPackager )
					)
					( objectStatus "EU1C3.37" )
				)
				( pin "pgnd(0)"
					( attribute "PN" "5"
						( Origin gPackager )
					)
					( objectStatus "EU1C3.5" )
				)
				( pin "pgnd(1)"
					( attribute "PN" "7"
						( Origin gPackager )
					)
					( objectStatus "EU1C3.7" )
				)
				( pin "pgnd(2)"
					( attribute "PN" "40"
						( Origin gPackager )
					)
					( objectStatus "EU1C3.40" )
				)
				( pin "phase"
					( attribute "PN" "32"
						( Origin gPackager )
					)
					( objectStatus "EU1C3.32" )
				)
				( pin "pwm"
					( attribute "PN" "34"
						( Origin gPackager )
					)
					( objectStatus "EU1C3.34" )
				)
				( pin "refin"
					( attribute "PN" "39"
						( Origin gPackager )
					)
					( objectStatus "EU1C3.39" )
				)
				( pin "sw"
					( attribute "PN" "10"
						( Origin gPackager )
					)
					( objectStatus "EU1C3.10" )
				)
				( pin "tout_flt"
					( attribute "PN" "36"
						( Origin gPackager )
					)
					( objectStatus "EU1C3.36" )
				)
				( pin "vcc"
					( attribute "PN" "3"
						( Origin gPackager )
					)
					( objectStatus "EU1C3.3" )
				)
				( pin "vdrv"
					( attribute "PN" "4"
						( Origin gPackager )
					)
					( objectStatus "EU1C3.4" )
				)
				( pin "vin(0)"
					( attribute "PN" "25"
						( Origin gPackager )
					)
					( objectStatus "EU1C3.25" )
				)
				( pin "vin(1)"
					( attribute "PN" "30"
						( Origin gPackager )
					)
					( objectStatus "EU1C3.30" )
				)
				( pin "vos"
					( attribute "PN" "1"
						( Origin gPackager )
					)
					( objectStatus "EU1C3.1" )
				)
			)
			( gate "@baseboard_fab2_lib.baseboard_fab2(sch_1):page209_i59"
				( attribute "CDS_LIB" "mstr_discrete"
					( Origin gPackager )
				)
				( attribute "CDS_LOCATION" "R1D52"
					( Origin gPackager )
				)
				( attribute "CDS_SEC" "1"
					( Origin gPackager )
				)
				( attribute "LOCATION" "R1D52"
					( Origin gFrontEnd )
				)
				( attribute "MATERIAL" "EMPTY"
					( Origin gFrontEnd )
				)
				( attribute "PACK_TYPE" "0402"
					( Origin gFrontEnd )
				)
				( attribute "PART_NUMBER" "G21796-187"
					( Origin gFrontEnd )
				)
				( attribute "PHYS_PAGE" "209"
					( Origin gFrontEnd )
				)
				( attribute "ROT" "0"
					( Origin gFrontEnd )
				)
				( attribute "SEC" "1"
					( Origin gPackager )
				)
				( attribute "TOLERANCE" "1%"
					( Origin gFrontEnd )
				)
				( attribute "VALUE" "68.1K"
					( Origin gFrontEnd )
				)
				( attribute "VER" "2"
					( Origin gFrontEnd )
				)
				( attribute "WATTAGE" "1/16W"
					( Origin gFrontEnd )
				)
				( attribute "XY" "(-1000,3925)"
					( Origin gFrontEnd )
				)
				( attribute "CHIPS_PART_NAME" "RES"
					( Origin gPackager )
				)
				( attribute "CDS_PART_NAME" "RES_0402-68.1K,1%,1/16W,EMPTY,A"
					( Origin gPackager )
				)
				( objectStatus "R1D52" )
				( pin "a"
					( attribute "PN" "1"
						( Origin gPackager )
					)
					( objectStatus "R1D52.1" )
				)
				( pin "b"
					( attribute "PN" "2"
						( Origin gPackager )
					)
					( objectStatus "R1D52.2" )
				)
			)
			( gate "@baseboard_fab2_lib.baseboard_fab2(sch_1):page210_i8"
				( attribute "BOM_COST" "PROC_VRD_VCCIN_CPU0"
					( Origin gFrontEnd )
				)
				( attribute "CDS_LIB" "dev_discrete"
					( Origin gPackager )
				)
				( attribute "CDS_LOCATION" "C1C19"
					( Origin gPackager )
				)
				( attribute "CDS_SEC" "1"
					( Origin gPackager )
				)
				( attribute "LOCATION" "C1C19"
					( Origin gFrontEnd )
				)
				( attribute "MATERIAL" "X6S"
					( Origin gFrontEnd )
				)
				( attribute "PACK_TYPE" "0603V"
					( Origin gFrontEnd )
				)
				( attribute "PART_NUMBER" "E15431-004"
					( Origin gFrontEnd )
				)
				( attribute "PHYS_PAGE" "210"
					( Origin gFrontEnd )
				)
				( attribute "ROOM" "PVSA_CPU1_PWR_VR"
					( Origin gFrontEnd )
				)
				( attribute "ROT" "0"
					( Origin gFrontEnd )
				)
				( attribute "SEC" "1"
					( Origin gFrontEnd )
				)
				( attribute "SEC_TYPE" "0603V"
					( Origin gFrontEnd )
				)
				( attribute "TOLERANCE" "20%"
					( Origin gFrontEnd )
				)
				( attribute "VALUE" "22.0UF"
					( Origin gFrontEnd )
				)
				( attribute "VER" "1"
					( Origin gFrontEnd )
				)
				( attribute "VOLTAGE" "4V"
					( Units "uVoltage" "V" 1.000000)
					( Origin gFrontEnd )
				)
				( attribute "XY" "(-1400,3050)"
					( Origin gFrontEnd )
				)
				( attribute "CHIPS_PART_NAME" "CAP_A"
					( Origin gPackager )
				)
				( attribute "CDS_PART_NAME" "CAP_A_0603V-22.0UF,4V,20%,X6S,A"
					( Origin gPackager )
				)
				( objectStatus "C1C19" )
				( pin "a"
					( attribute "PN" "1"
						( Origin gPackager )
					)
					( objectStatus "C1C19.1" )
				)
				( pin "b"
					( attribute "PN" "2"
						( Origin gPackager )
					)
					( objectStatus "C1C19.2" )
				)
			)
			( gate "@baseboard_fab2_lib.baseboard_fab2(sch_1):page210_i10"
				( attribute "CDS_LIB" "mstr_discrete"
					( Origin gPackager )
				)
				( attribute "CDS_LOCATION" "L1C1"
					( Origin gPackager )
				)
				( attribute "CDS_SEC" "1"
					( Origin gPackager )
				)
				( attribute "LOCATION" "L1C1"
					( Origin gFrontEnd )
				)
				( attribute "MATERIAL" "IND"
					( Origin gFrontEnd )
				)
				( attribute "PACK_TYPE" "SM"
					( Origin gFrontEnd )
				)
				( attribute "PART_NUMBER" "D92183-036"
					( Origin gFrontEnd )
				)
				( attribute "PHYS_PAGE" "210"
					( Origin gFrontEnd )
				)
				( attribute "ROOM" "PVSA_CPU1_PWR_VR"
					( Origin gFrontEnd )
				)
				( attribute "ROT" "0"
					( Origin gFrontEnd )
				)
				( attribute "SEC" "1"
					( Origin gFrontEnd )
				)
				( attribute "SEC_TYPE" "SM"
					( Origin gFrontEnd )
				)
				( attribute "VALUE" "0.3UH"
					( Origin gFrontEnd )
				)
				( attribute "VER" "1"
					( Origin gFrontEnd )
				)
				( attribute "XY" "(-1900,3300)"
					( Origin gFrontEnd )
				)
				( attribute "CHIPS_PART_NAME" "INDUCTOR"
					( Origin gPackager )
				)
				( attribute "CDS_PART_NAME" "INDUCTOR_SM-0.3UH,IND,D92183-0A"
					( Origin gPackager )
				)
				( objectStatus "L1C1" )
				( pin "ina"
					( attribute "PN" "1"
						( Origin gPackager )
					)
					( objectStatus "L1C1.1" )
				)
				( pin "inb"
					( attribute "PN" "2"
						( Origin gPackager )
					)
					( objectStatus "L1C1.2" )
				)
			)
			( gate "@baseboard_fab2_lib.baseboard_fab2(sch_1):page210_i12"
				( attribute "BOM_COST" "PROC_VRD_VCCIN_CPU0"
					( Origin gFrontEnd )
				)
				( attribute "CDS_LIB" "mstr_discrete"
					( Origin gPackager )
				)
				( attribute "CDS_LOCATION" "C9N11"
					( Origin gPackager )
				)
				( attribute "CDS_SEC" "1"
					( Origin gPackager )
				)
				( attribute "LOCATION" "C9N11"
					( Origin gFrontEnd )
				)
				( attribute "MATERIAL" "ALUM"
					( Origin gFrontEnd )
				)
				( attribute "PACK_TYPE" "3018"
					( Origin gFrontEnd )
				)
				( attribute "PART_NUMBER" "699013-049"
					( Origin gFrontEnd )
				)
				( attribute "PHYS_PAGE" "210"
					( Origin gFrontEnd )
				)
				( attribute "ROOM" "PVSA_CPU1_DECAP_VR"
					( Origin gFrontEnd )
				)
				( attribute "ROT" "0"
					( Origin gFrontEnd )
				)
				( attribute "SEC" "1"
					( Origin gFrontEnd )
				)
				( attribute "SEC_TYPE" "3018"
					( Origin gFrontEnd )
				)
				( attribute "TOLERANCE" "20%"
					( Origin gFrontEnd )
				)
				( attribute "VALUE" "470UF"
					( Origin gFrontEnd )
				)
				( attribute "VER" "1"
					( Origin gFrontEnd )
				)
				( attribute "VOLTAGE" "2.5V"
					( Units "uVoltage" "V" 1.000000)
					( Origin gFrontEnd )
				)
				( attribute "XY" "(-1325,1375)"
					( Origin gFrontEnd )
				)
				( attribute "CHIPS_PART_NAME" "CAPP"
					( Origin gPackager )
				)
				( attribute "CDS_PART_NAME" "CAPP_3018-470UF,2.5V,20%,ALUM,A"
					( Origin gPackager )
				)
				( objectStatus "C9N11" )
				( pin "a"
					( attribute "PN" "1"
						( Origin gPackager )
					)
					( objectStatus "C9N11.1" )
				)
				( pin "b"
					( attribute "PN" "2"
						( Origin gPackager )
					)
					( objectStatus "C9N11.2" )
				)
			)
			( gate "@baseboard_fab2_lib.baseboard_fab2(sch_1):page210_i14"
				( attribute "BOM_COST" "PROC_VRD_VCCIN_CPU0"
					( Origin gFrontEnd )
				)
				( attribute "CDS_LIB" "mstr_discrete"
					( Origin gPackager )
				)
				( attribute "CDS_LOCATION" "C9N20"
					( Origin gPackager )
				)
				( attribute "CDS_SEC" "1"
					( Origin gPackager )
				)
				( attribute "LOCATION" "C9N20"
					( Origin gFrontEnd )
				)
				( attribute "MATERIAL" "ALUM"
					( Origin gFrontEnd )
				)
				( attribute "PACK_TYPE" "3018"
					( Origin gFrontEnd )
				)
				( attribute "PART_NUMBER" "699013-049"
					( Origin gFrontEnd )
				)
				( attribute "PHYS_PAGE" "210"
					( Origin gFrontEnd )
				)
				( attribute "ROOM" "PVSA_CPU1_DECAP_VR"
					( Origin gFrontEnd )
				)
				( attribute "ROT" "2"
					( Origin gFrontEnd )
				)
				( attribute "SEC" "1"
					( Origin gFrontEnd )
				)
				( attribute "SEC_TYPE" "3018"
					( Origin gFrontEnd )
				)
				( attribute "TOLERANCE" "20%"
					( Origin gFrontEnd )
				)
				( attribute "VALUE" "470UF"
					( Origin gFrontEnd )
				)
				( attribute "VER" "1"
					( Origin gFrontEnd )
				)
				( attribute "VOLTAGE" "2.5V"
					( Units "uVoltage" "V" 1.000000)
					( Origin gFrontEnd )
				)
				( attribute "XY" "(-1575,1375)"
					( Origin gFrontEnd )
				)
				( attribute "CHIPS_PART_NAME" "CAPP"
					( Origin gPackager )
				)
				( attribute "CDS_PART_NAME" "CAPP_3018-470UF,2.5V,20%,ALUM,A"
					( Origin gPackager )
				)
				( objectStatus "C9N20" )
				( pin "a"
					( attribute "PN" "1"
						( Origin gPackager )
					)
					( objectStatus "C9N20.1" )
				)
				( pin "b"
					( attribute "PN" "2"
						( Origin gPackager )
					)
					( objectStatus "C9N20.2" )
				)
			)
			( gate "@baseboard_fab2_lib.baseboard_fab2(sch_1):page210_i20"
				( attribute "CDS_LIB" "mstr_discrete"
					( Origin gPackager )
				)
				( attribute "CDS_LOCATION" "R9N3"
					( Origin gPackager )
				)
				( attribute "CDS_SEC" "1"
					( Origin gPackager )
				)
				( attribute "LOCATION" "R9N3"
					( Origin gFrontEnd )
				)
				( attribute "MATERIAL" "CHIP"
					( Origin gFrontEnd )
				)
				( attribute "PACK_TYPE" "0402"
					( Origin gFrontEnd )
				)
				( attribute "PART_NUMBER" "G21796-090"
					( Origin gFrontEnd )
				)
				( attribute "PHYS_PAGE" "210"
					( Origin gFrontEnd )
				)
				( attribute "ROOM" "PVSA_CPU1_PWR_VR"
					( Origin gFrontEnd )
				)
				( attribute "ROT" "0"
					( Origin gFrontEnd )
				)
				( attribute "SEC" "1"
					( Origin gFrontEnd )
				)
				( attribute "SEC_TYPE" "0402"
					( Origin gFrontEnd )
				)
				( attribute "TOLERANCE" "1%"
					( Origin gFrontEnd )
				)
				( attribute "VALUE" "1.0"
					( Origin gFrontEnd )
				)
				( attribute "VER" "1"
					( Origin gFrontEnd )
				)
				( attribute "WATTAGE" "1/16W"
					( Origin gFrontEnd )
				)
				( attribute "XY" "(-5700,4425)"
					( Origin gFrontEnd )
				)
				( attribute "CHIPS_PART_NAME" "RES"
					( Origin gPackager )
				)
				( attribute "CDS_PART_NAME" "RES_0402-1.0,1%,1/16W,CHIP,G21A"
					( Origin gPackager )
				)
				( objectStatus "R9N3" )
				( pin "a"
					( attribute "PN" "1"
						( Origin gPackager )
					)
					( objectStatus "R9N3.1" )
				)
				( pin "b"
					( attribute "PN" "2"
						( Origin gPackager )
					)
					( objectStatus "R9N3.2" )
				)
			)
			( gate "@baseboard_fab2_lib.baseboard_fab2(sch_1):page210_i22"
				( attribute "CDS_LIB" "mstr_discrete"
					( Origin gPackager )
				)
				( attribute "CDS_LOCATION" "C1C4"
					( Origin gPackager )
				)
				( attribute "CDS_SEC" "1"
					( Origin gPackager )
				)
				( attribute "LOCATION" "C1C4"
					( Origin gFrontEnd )
				)
				( attribute "MATERIAL" "X7R"
					( Origin gFrontEnd )
				)
				( attribute "PACK_TYPE" "0402"
					( Origin gFrontEnd )
				)
				( attribute "PART_NUMBER" "A36096-155"
					( Origin gFrontEnd )
				)
				( attribute "PHYS_PAGE" "210"
					( Origin gFrontEnd )
				)
				( attribute "ROOM" "PVSA_CPU1_PWR_VR"
					( Origin gFrontEnd )
				)
				( attribute "ROT" "0"
					( Origin gFrontEnd )
				)
				( attribute "SEC" "1"
					( Origin gFrontEnd )
				)
				( attribute "SEC_TYPE" "0402"
					( Origin gFrontEnd )
				)
				( attribute "TOLERANCE" "10%"
					( Origin gFrontEnd )
				)
				( attribute "VALUE" "0.22UF"
					( Origin gFrontEnd )
				)
				( attribute "VER" "1"
					( Origin gFrontEnd )
				)
				( attribute "VOLTAGE" "16V"
					( Units "uVoltage" "V" 1.000000)
					( Origin gFrontEnd )
				)
				( attribute "XY" "(-5375,3850)"
					( Origin gFrontEnd )
				)
				( attribute "CHIPS_PART_NAME" "CAP"
					( Origin gPackager )
				)
				( attribute "CDS_PART_NAME" "CAP_0402-0.22UF,16V,10%,X7R,A3A"
					( Origin gPackager )
				)
				( objectStatus "C1C4" )
				( pin "a"
					( attribute "PN" "1"
						( Origin gPackager )
					)
					( objectStatus "C1C4.1" )
				)
				( pin "b"
					( attribute "PN" "2"
						( Origin gPackager )
					)
					( objectStatus "C1C4.2" )
				)
			)
			( gate "@baseboard_fab2_lib.baseboard_fab2(sch_1):page210_i23"
				( attribute "CDS_LIB" "dev_discrete"
					( Origin gPackager )
				)
				( attribute "CDS_LOCATION" "C1C3"
					( Origin gPackager )
				)
				( attribute "CDS_SEC" "1"
					( Origin gPackager )
				)
				( attribute "LOCATION" "C1C3"
					( Origin gFrontEnd )
				)
				( attribute "MATERIAL" "X6S"
					( Origin gFrontEnd )
				)
				( attribute "PACK_TYPE" "0402V"
					( Origin gFrontEnd )
				)
				( attribute "PART_NUMBER" "D97712-004"
					( Origin gFrontEnd )
				)
				( attribute "PHYS_PAGE" "210"
					( Origin gFrontEnd )
				)
				( attribute "ROOM" "PVSA_CPU1_PWR_VR"
					( Origin gFrontEnd )
				)
				( attribute "ROT" "2"
					( Origin gFrontEnd )
				)
				( attribute "SEC" "1"
					( Origin gFrontEnd )
				)
				( attribute "SEC_TYPE" "0402V"
					( Origin gFrontEnd )
				)
				( attribute "TOLERANCE" "10%"
					( Origin gFrontEnd )
				)
				( attribute "VALUE" "1.0UF"
					( Origin gFrontEnd )
				)
				( attribute "VER" "1"
					( Origin gFrontEnd )
				)
				( attribute "VOLTAGE" "6.3V"
					( Units "uVoltage" "V" 1.000000)
					( Origin gFrontEnd )
				)
				( attribute "XY" "(-5500,3850)"
					( Origin gFrontEnd )
				)
				( attribute "CHIPS_PART_NAME" "CAP_A"
					( Origin gPackager )
				)
				( attribute "CDS_PART_NAME" "CAP_A_0402V-1.0UF,6.3V,10%,X6SA"
					( Origin gPackager )
				)
				( objectStatus "C1C3" )
				( pin "a"
					( attribute "PN" "1"
						( Origin gPackager )
					)
					( objectStatus "C1C3.1" )
				)
				( pin "b"
					( attribute "PN" "2"
						( Origin gPackager )
					)
					( objectStatus "C1C3.2" )
				)
			)
			( gate "@baseboard_fab2_lib.baseboard_fab2(sch_1):page210_i24"
				( attribute "CDS_LIB" "mstr_discrete"
					( Origin gPackager )
				)
				( attribute "CDS_LOCATION" "C1C12"
					( Origin gPackager )
				)
				( attribute "CDS_SEC" "1"
					( Origin gPackager )
				)
				( attribute "LOCATION" "C1C12"
					( Origin gFrontEnd )
				)
				( attribute "MATERIAL" "X7R"
					( Origin gFrontEnd )
				)
				( attribute "PACK_TYPE" "0402"
					( Origin gFrontEnd )
				)
				( attribute "PART_NUMBER" "A36096-104"
					( Origin gFrontEnd )
				)
				( attribute "PHYS_PAGE" "210"
					( Origin gFrontEnd )
				)
				( attribute "ROOM" "PVSA_CPU1_PWR_VR"
					( Origin gFrontEnd )
				)
				( attribute "ROT" "2"
					( Origin gFrontEnd )
				)
				( attribute "SEC" "1"
					( Origin gFrontEnd )
				)
				( attribute "SEC_TYPE" "0402"
					( Origin gFrontEnd )
				)
				( attribute "SPOF" "TRUE"
					( Origin gFrontEnd )
				)
				( attribute "TOLERANCE" "10%"
					( Origin gFrontEnd )
				)
				( attribute "VALUE" "0.220UF"
					( Origin gFrontEnd )
				)
				( attribute "VER" "1"
					( Origin gFrontEnd )
				)
				( attribute "VOLTAGE" "16V"
					( Units "uVoltage" "V" 1.000000)
					( Origin gFrontEnd )
				)
				( attribute "XY" "(-6125,3250)"
					( Origin gFrontEnd )
				)
				( attribute "CHIPS_PART_NAME" "CAP"
					( Origin gPackager )
				)
				( attribute "CDS_PART_NAME" "CAP_0402-0.220UF,16V,10%,X7R,AA"
					( Origin gPackager )
				)
				( objectStatus "C1C12" )
				( pin "a"
					( attribute "PN" "1"
						( Origin gPackager )
					)
					( objectStatus "C1C12.1" )
				)
				( pin "b"
					( attribute "PN" "2"
						( Origin gPackager )
					)
					( objectStatus "C1C12.2" )
				)
			)
			( gate "@baseboard_fab2_lib.baseboard_fab2(sch_1):page210_i26"
				( attribute "CDS_LIB" "mstr_discrete"
					( Origin gPackager )
				)
				( attribute "CDS_LOCATION" "C1C5"
					( Origin gPackager )
				)
				( attribute "CDS_SEC" "1"
					( Origin gPackager )
				)
				( attribute "LOCATION" "C1C5"
					( Origin gFrontEnd )
				)
				( attribute "MATERIAL" "X6S"
					( Origin gFrontEnd )
				)
				( attribute "PACK_TYPE" "0402"
					( Origin gFrontEnd )
				)
				( attribute "PART_NUMBER" "D97712-011"
					( Origin gFrontEnd )
				)
				( attribute "PHYS_PAGE" "210"
					( Origin gFrontEnd )
				)
				( attribute "ROOM" "PVSA_CPU1_PWR_VR"
					( Origin gFrontEnd )
				)
				( attribute "ROT" "0"
					( Origin gFrontEnd )
				)
				( attribute "SEC" "1"
					( Origin gFrontEnd )
				)
				( attribute "SEC_TYPE" "0402"
					( Origin gFrontEnd )
				)
				( attribute "TOLERANCE" "10%"
					( Origin gFrontEnd )
				)
				( attribute "VALUE" "1.0UF"
					( Origin gFrontEnd )
				)
				( attribute "VER" "1"
					( Origin gFrontEnd )
				)
				( attribute "VOLTAGE" "16V"
					( Units "uVoltage" "V" 1.000000)
					( Origin gFrontEnd )
				)
				( attribute "XY" "(-6025,3825)"
					( Origin gFrontEnd )
				)
				( attribute "CHIPS_PART_NAME" "CAP"
					( Origin gPackager )
				)
				( attribute "CDS_PART_NAME" "CAP_0402-1.0UF,16V,10%,X6S,D97A"
					( Origin gPackager )
				)
				( objectStatus "C1C5" )
				( pin "a"
					( attribute "PN" "1"
						( Origin gPackager )
					)
					( objectStatus "C1C5.1" )
				)
				( pin "b"
					( attribute "PN" "2"
						( Origin gPackager )
					)
					( objectStatus "C1C5.2" )
				)
			)
			( gate "@baseboard_fab2_lib.baseboard_fab2(sch_1):page210_i27"
				( attribute "CDS_LIB" "dev_discrete"
					( Origin gPackager )
				)
				( attribute "CDS_LOCATION" "C1C17"
					( Origin gPackager )
				)
				( attribute "CDS_SEC" "1"
					( Origin gPackager )
				)
				( attribute "LOCATION" "C1C17"
					( Origin gFrontEnd )
				)
				( attribute "MATERIAL" "X7R"
					( Origin gFrontEnd )
				)
				( attribute "PACK_TYPE" "0402V"
					( Origin gFrontEnd )
				)
				( attribute "PART_NUMBER" "A36096-030"
					( Origin gFrontEnd )
				)
				( attribute "PHYS_PAGE" "210"
					( Origin gFrontEnd )
				)
				( attribute "ROOM" "PVSA_CPU1_PWR_VR"
					( Origin gFrontEnd )
				)
				( attribute "ROT" "0"
					( Origin gFrontEnd )
				)
				( attribute "SEC" "1"
					( Origin gFrontEnd )
				)
				( attribute "SEC_TYPE" "0402V"
					( Origin gFrontEnd )
				)
				( attribute "TOLERANCE" "10%"
					( Origin gFrontEnd )
				)
				( attribute "VALUE" "0.1UF"
					( Origin gFrontEnd )
				)
				( attribute "VER" "1"
					( Origin gFrontEnd )
				)
				( attribute "VOLTAGE" "16V"
					( Units "uVoltage" "V" 1.000000)
					( Origin gFrontEnd )
				)
				( attribute "XY" "(-6325,3850)"
					( Origin gFrontEnd )
				)
				( attribute "CHIPS_PART_NAME" "CAP_A"
					( Origin gPackager )
				)
				( attribute "CDS_PART_NAME" "CAP_A_0402V-0.1UF,16V,10%,X7R,A"
					( Origin gPackager )
				)
				( objectStatus "C1C17" )
				( pin "a"
					( attribute "PN" "1"
						( Origin gPackager )
					)
					( objectStatus "C1C17.1" )
				)
				( pin "b"
					( attribute "PN" "2"
						( Origin gPackager )
					)
					( objectStatus "C1C17.2" )
				)
			)
			( gate "@baseboard_fab2_lib.baseboard_fab2(sch_1):page210_i28"
				( attribute "CDS_LIB" "mstr_discrete"
					( Origin gPackager )
				)
				( attribute "CDS_LOCATION" "C1C15"
					( Origin gPackager )
				)
				( attribute "CDS_SEC" "1"
					( Origin gPackager )
				)
				( attribute "LOCATION" "C1C15"
					( Origin gFrontEnd )
				)
				( attribute "MATERIAL" "X6S"
					( Origin gFrontEnd )
				)
				( attribute "PACK_TYPE" "0402"
					( Origin gFrontEnd )
				)
				( attribute "PART_NUMBER" "D97712-011"
					( Origin gFrontEnd )
				)
				( attribute "PHYS_PAGE" "210"
					( Origin gFrontEnd )
				)
				( attribute "ROOM" "PVSA_CPU1_PWR_VR"
					( Origin gFrontEnd )
				)
				( attribute "ROT" "0"
					( Origin gFrontEnd )
				)
				( attribute "SEC" "1"
					( Origin gFrontEnd )
				)
				( attribute "SEC_TYPE" "0402"
					( Origin gFrontEnd )
				)
				( attribute "TOLERANCE" "10%"
					( Origin gFrontEnd )
				)
				( attribute "VALUE" "1.0UF"
					( Origin gFrontEnd )
				)
				( attribute "VER" "1"
					( Origin gFrontEnd )
				)
				( attribute "VOLTAGE" "16V"
					( Units "uVoltage" "V" 1.000000)
					( Origin gFrontEnd )
				)
				( attribute "XY" "(-6600,3850)"
					( Origin gFrontEnd )
				)
				( attribute "CHIPS_PART_NAME" "CAP"
					( Origin gPackager )
				)
				( attribute "CDS_PART_NAME" "CAP_0402-1.0UF,16V,10%,X6S,D97A"
					( Origin gPackager )
				)
				( objectStatus "C1C15" )
				( pin "a"
					( attribute "PN" "1"
						( Origin gPackager )
					)
					( objectStatus "C1C15.1" )
				)
				( pin "b"
					( attribute "PN" "2"
						( Origin gPackager )
					)
					( objectStatus "C1C15.2" )
				)
			)
			( gate "@baseboard_fab2_lib.baseboard_fab2(sch_1):page210_i29"
				( attribute "BOM_COST" "PROC_VRD_VCCIN_CPU0"
					( Origin gFrontEnd )
				)
				( attribute "CDS_LIB" "mstr_discrete"
					( Origin gPackager )
				)
				( attribute "CDS_LOCATION" "R1C12"
					( Origin gPackager )
				)
				( attribute "CDS_SEC" "1"
					( Origin gPackager )
				)
				( attribute "LOCATION" "R1C12"
					( Origin gFrontEnd )
				)
				( attribute "MATERIAL" "CHIP"
					( Origin gFrontEnd )
				)
				( attribute "PACK_TYPE" "0402"
					( Origin gFrontEnd )
				)
				( attribute "PART_NUMBER" "G21796-017"
					( Origin gFrontEnd )
				)
				( attribute "PHYS_PAGE" "210"
					( Origin gFrontEnd )
				)
				( attribute "ROOM" "PVSA_CPU1_VSENSE_VR"
					( Origin gFrontEnd )
				)
				( attribute "ROT" "0"
					( Origin gFrontEnd )
				)
				( attribute "SEC" "1"
					( Origin gFrontEnd )
				)
				( attribute "SEC_TYPE" "0402"
					( Origin gFrontEnd )
				)
				( attribute "TOLERANCE" "1%"
					( Origin gFrontEnd )
				)
				( attribute "VALUE" "100.0"
					( Origin gFrontEnd )
				)
				( attribute "VER" "1"
					( Origin gFrontEnd )
				)
				( attribute "WATTAGE" "1/16W"
					( Origin gFrontEnd )
				)
				( attribute "XY" "(-5300,2325)"
					( Origin gFrontEnd )
				)
				( attribute "CHIPS_PART_NAME" "RES"
					( Origin gPackager )
				)
				( attribute "CDS_PART_NAME" "RES_0402-100.0,1%,1/16W,CHIP,GA"
					( Origin gPackager )
				)
				( objectStatus "R1C12" )
				( pin "a"
					( attribute "PN" "1"
						( Origin gPackager )
					)
					( objectStatus "R1C12.1" )
				)
				( pin "b"
					( attribute "PN" "2"
						( Origin gPackager )
					)
					( objectStatus "R1C12.2" )
				)
			)
			( gate "@baseboard_fab2_lib.baseboard_fab2(sch_1):page210_i31"
				( attribute "BOM_COST" "PROC_VRD_VCCIN_CPU0"
					( Origin gFrontEnd )
				)
				( attribute "CDS_LIB" "mstr_discrete"
					( Origin gPackager )
				)
				( attribute "CDS_LOCATION" "R1C7"
					( Origin gPackager )
				)
				( attribute "CDS_SEC" "1"
					( Origin gPackager )
				)
				( attribute "LOCATION" "R1C7"
					( Origin gFrontEnd )
				)
				( attribute "MATERIAL" "CHIP"
					( Origin gFrontEnd )
				)
				( attribute "PACK_TYPE" "0402"
					( Origin gFrontEnd )
				)
				( attribute "PART_NUMBER" "G21497-005"
					( Origin gFrontEnd )
				)
				( attribute "PHYS_PAGE" "210"
					( Origin gFrontEnd )
				)
				( attribute "ROOM" "PVSA_CPU1_VSENSE_VR"
					( Origin gFrontEnd )
				)
				( attribute "ROT" "0"
					( Origin gFrontEnd )
				)
				( attribute "SEC" "1"
					( Origin gFrontEnd )
				)
				( attribute "SEC_TYPE" "0402"
					( Origin gFrontEnd )
				)
				( attribute "TOLERANCE" "5%"
					( Origin gFrontEnd )
				)
				( attribute "VALUE" "0.0"
					( Origin gFrontEnd )
				)
				( attribute "VER" "1"
					( Origin gFrontEnd )
				)
				( attribute "WATTAGE" "1/16W"
					( Origin gFrontEnd )
				)
				( attribute "XY" "(-5275,1925)"
					( Origin gFrontEnd )
				)
				( attribute "CHIPS_PART_NAME" "RES"
					( Origin gPackager )
				)
				( attribute "CDS_PART_NAME" "RES_0402-0.0,5%,1/16W,CHIP,G21A"
					( Origin gPackager )
				)
				( objectStatus "R1C7" )
				( pin "a"
					( attribute "PN" "1"
						( Origin gPackager )
					)
					( objectStatus "R1C7.1" )
				)
				( pin "b"
					( attribute "PN" "2"
						( Origin gPackager )
					)
					( objectStatus "R1C7.2" )
				)
			)
			( gate "@baseboard_fab2_lib.baseboard_fab2(sch_1):page210_i32"
				( attribute "BOM_COST" "PROC_VRD_VCCIN_CPU0"
					( Origin gFrontEnd )
				)
				( attribute "CDS_LIB" "mstr_discrete"
					( Origin gPackager )
				)
				( attribute "CDS_LOCATION" "R1C5"
					( Origin gPackager )
				)
				( attribute "CDS_SEC" "1"
					( Origin gPackager )
				)
				( attribute "LOCATION" "R1C5"
					( Origin gFrontEnd )
				)
				( attribute "MATERIAL" "CHIP"
					( Origin gFrontEnd )
				)
				( attribute "PACK_TYPE" "0402"
					( Origin gFrontEnd )
				)
				( attribute "PART_NUMBER" "G21497-005"
					( Origin gFrontEnd )
				)
				( attribute "PHYS_PAGE" "210"
					( Origin gFrontEnd )
				)
				( attribute "ROOM" "PVSA_CPU1_VSENSE_VR"
					( Origin gFrontEnd )
				)
				( attribute "ROT" "0"
					( Origin gFrontEnd )
				)
				( attribute "SEC" "1"
					( Origin gFrontEnd )
				)
				( attribute "SEC_TYPE" "0402"
					( Origin gFrontEnd )
				)
				( attribute "TOLERANCE" "5%"
					( Origin gFrontEnd )
				)
				( attribute "VALUE" "0.0"
					( Origin gFrontEnd )
				)
				( attribute "VER" "1"
					( Origin gFrontEnd )
				)
				( attribute "WATTAGE" "1/16W"
					( Origin gFrontEnd )
				)
				( attribute "XY" "(-5275,1475)"
					( Origin gFrontEnd )
				)
				( attribute "CHIPS_PART_NAME" "RES"
					( Origin gPackager )
				)
				( attribute "CDS_PART_NAME" "RES_0402-0.0,5%,1/16W,CHIP,G21A"
					( Origin gPackager )
				)
				( objectStatus "R1C5" )
				( pin "a"
					( attribute "PN" "1"
						( Origin gPackager )
					)
					( objectStatus "R1C5.1" )
				)
				( pin "b"
					( attribute "PN" "2"
						( Origin gPackager )
					)
					( objectStatus "R1C5.2" )
				)
			)
			( gate "@baseboard_fab2_lib.baseboard_fab2(sch_1):page210_i33"
				( attribute "BOM_COST" "PROC_VRD_VCCIN_CPU0"
					( Origin gFrontEnd )
				)
				( attribute "CDS_LIB" "mstr_discrete"
					( Origin gPackager )
				)
				( attribute "CDS_LOCATION" "R1C4"
					( Origin gPackager )
				)
				( attribute "CDS_SEC" "1"
					( Origin gPackager )
				)
				( attribute "LOCATION" "R1C4"
					( Origin gFrontEnd )
				)
				( attribute "MATERIAL" "CHIP"
					( Origin gFrontEnd )
				)
				( attribute "PACK_TYPE" "0402"
					( Origin gFrontEnd )
				)
				( attribute "PART_NUMBER" "G21796-017"
					( Origin gFrontEnd )
				)
				( attribute "PHYS_PAGE" "210"
					( Origin gFrontEnd )
				)
				( attribute "ROOM" "PVSA_CPU1_VSENSE_VR"
					( Origin gFrontEnd )
				)
				( attribute "ROT" "0"
					( Origin gFrontEnd )
				)
				( attribute "SEC" "1"
					( Origin gFrontEnd )
				)
				( attribute "SEC_TYPE" "0402"
					( Origin gFrontEnd )
				)
				( attribute "TOLERANCE" "1%"
					( Origin gFrontEnd )
				)
				( attribute "VALUE" "100.0"
					( Origin gFrontEnd )
				)
				( attribute "VER" "1"
					( Origin gFrontEnd )
				)
				( attribute "WATTAGE" "1/16W"
					( Origin gFrontEnd )
				)
				( attribute "XY" "(-5275,1100)"
					( Origin gFrontEnd )
				)
				( attribute "CHIPS_PART_NAME" "RES"
					( Origin gPackager )
				)
				( attribute "CDS_PART_NAME" "RES_0402-100.0,1%,1/16W,CHIP,GA"
					( Origin gPackager )
				)
				( objectStatus "R1C4" )
				( pin "a"
					( attribute "PN" "1"
						( Origin gPackager )
					)
					( objectStatus "R1C4.1" )
				)
				( pin "b"
					( attribute "PN" "2"
						( Origin gPackager )
					)
					( objectStatus "R1C4.2" )
				)
			)
			( gate "@baseboard_fab2_lib.baseboard_fab2(sch_1):page210_i34"
				( attribute "BOM_COST" "PROC_VRD_VCCIN_CPU0"
					( Origin gFrontEnd )
				)
				( attribute "CDS_LIB" "mstr_discrete"
					( Origin gPackager )
				)
				( attribute "CDS_LOCATION" "R1C6"
					( Origin gPackager )
				)
				( attribute "CDS_SEC" "1"
					( Origin gPackager )
				)
				( attribute "LOCATION" "R1C6"
					( Origin gFrontEnd )
				)
				( attribute "MATERIAL" "EMPTY"
					( Origin gFrontEnd )
				)
				( attribute "NO_XNET_CONNECTION" "1"
					( Origin gFrontEnd )
				)
				( attribute "PACK_TYPE" "0402"
					( Origin gFrontEnd )
				)
				( attribute "PART_NUMBER" "G21796-026"
					( Origin gFrontEnd )
				)
				( attribute "PHYS_PAGE" "210"
					( Origin gFrontEnd )
				)
				( attribute "ROOM" "PVSA_CPU1_VSENSE_VR"
					( Origin gFrontEnd )
				)
				( attribute "ROT" "0"
					( Origin gFrontEnd )
				)
				( attribute "SEC" "1"
					( Origin gFrontEnd )
				)
				( attribute "SEC_TYPE" "0402"
					( Origin gFrontEnd )
				)
				( attribute "TOLERANCE" "1%"
					( Origin gFrontEnd )
				)
				( attribute "VALUE" "1.00K"
					( Origin gFrontEnd )
				)
				( attribute "VER" "2"
					( Origin gFrontEnd )
				)
				( attribute "WATTAGE" "1/16W"
					( Origin gFrontEnd )
				)
				( attribute "XY" "(-5950,1725)"
					( Origin gFrontEnd )
				)
				( attribute "CHIPS_PART_NAME" "RES"
					( Origin gPackager )
				)
				( attribute "CDS_PART_NAME" "RES_0402-1.00K,1%,1/16W,EMPTY,A"
					( Origin gPackager )
				)
				( objectStatus "R1C6" )
				( pin "a"
					( attribute "PN" "1"
						( Origin gPackager )
					)
					( objectStatus "R1C6.1" )
				)
				( pin "b"
					( attribute "PN" "2"
						( Origin gPackager )
					)
					( objectStatus "R1C6.2" )
				)
			)
			( gate "@baseboard_fab2_lib.baseboard_fab2(sch_1):page210_i35"
				( attribute "CDS_LIB" "mstr_discrete"
					( Origin gPackager )
				)
				( attribute "CDS_LOCATION" "C9N13"
					( Origin gPackager )
				)
				( attribute "CDS_SEC" "1"
					( Origin gPackager )
				)
				( attribute "LOCATION" "C9N13"
					( Origin gFrontEnd )
				)
				( attribute "MATERIAL" "X6S"
					( Origin gFrontEnd )
				)
				( attribute "PACK_TYPE" "0805"
					( Origin gFrontEnd )
				)
				( attribute "PART_NUMBER" "C95333-007"
					( Origin gFrontEnd )
				)
				( attribute "PHYS_PAGE" "210"
					( Origin gFrontEnd )
				)
				( attribute "ROOM" "PVSA_CPU1_PWR_VR"
					( Origin gFrontEnd )
				)
				( attribute "ROT" "0"
					( Origin gFrontEnd )
				)
				( attribute "SEC" "1"
					( Origin gFrontEnd )
				)
				( attribute "SEC_TYPE" "0805"
					( Origin gFrontEnd )
				)
				( attribute "TOLERANCE" "10%"
					( Origin gFrontEnd )
				)
				( attribute "VALUE" "10UF"
					( Origin gFrontEnd )
				)
				( attribute "VER" "1"
					( Origin gFrontEnd )
				)
				( attribute "VOLTAGE" "16V"
					( Units "uVoltage" "V" 1.000000)
					( Origin gFrontEnd )
				)
				( attribute "XY" "(-6850,3825)"
					( Origin gFrontEnd )
				)
				( attribute "CHIPS_PART_NAME" "CAP"
					( Origin gPackager )
				)
				( attribute "CDS_PART_NAME" "CAP_0805-10UF,16V,10%,X6S,C953A"
					( Origin gPackager )
				)
				( objectStatus "C9N13" )
				( pin "a"
					( attribute "PN" "1"
						( Origin gPackager )
					)
					( objectStatus "C9N13.1" )
				)
				( pin "b"
					( attribute "PN" "2"
						( Origin gPackager )
					)
					( objectStatus "C9N13.2" )
				)
			)
			( gate "@baseboard_fab2_lib.baseboard_fab2(sch_1):page210_i36"
				( attribute "CDS_LIB" "mstr_discrete"
					( Origin gPackager )
				)
				( attribute "CDS_LOCATION" "C9N19"
					( Origin gPackager )
				)
				( attribute "CDS_SEC" "1"
					( Origin gPackager )
				)
				( attribute "LOCATION" "C9N19"
					( Origin gFrontEnd )
				)
				( attribute "MATERIAL" "X6S"
					( Origin gFrontEnd )
				)
				( attribute "PACK_TYPE" "0805"
					( Origin gFrontEnd )
				)
				( attribute "PART_NUMBER" "C95333-007"
					( Origin gFrontEnd )
				)
				( attribute "PHYS_PAGE" "210"
					( Origin gFrontEnd )
				)
				( attribute "ROOM" "PVSA_CPU1_PWR_VR"
					( Origin gFrontEnd )
				)
				( attribute "ROT" "0"
					( Origin gFrontEnd )
				)
				( attribute "SEC" "1"
					( Origin gFrontEnd )
				)
				( attribute "SEC_TYPE" "0805"
					( Origin gFrontEnd )
				)
				( attribute "TOLERANCE" "10%"
					( Origin gFrontEnd )
				)
				( attribute "VALUE" "10UF"
					( Origin gFrontEnd )
				)
				( attribute "VER" "1"
					( Origin gFrontEnd )
				)
				( attribute "VOLTAGE" "16V"
					( Units "uVoltage" "V" 1.000000)
					( Origin gFrontEnd )
				)
				( attribute "XY" "(-7150,3850)"
					( Origin gFrontEnd )
				)
				( attribute "CHIPS_PART_NAME" "CAP"
					( Origin gPackager )
				)
				( attribute "CDS_PART_NAME" "CAP_0805-10UF,16V,10%,X6S,C953A"
					( Origin gPackager )
				)
				( objectStatus "C9N19" )
				( pin "a"
					( attribute "PN" "1"
						( Origin gPackager )
					)
					( objectStatus "C9N19.1" )
				)
				( pin "b"
					( attribute "PN" "2"
						( Origin gPackager )
					)
					( objectStatus "C9N19.2" )
				)
			)
			( gate "@baseboard_fab2_lib.baseboard_fab2(sch_1):page210_i38"
				( attribute "CDS_LIB" "mstr_discrete"
					( Origin gPackager )
				)
				( attribute "CDS_LOCATION" "C9N21"
					( Origin gPackager )
				)
				( attribute "CDS_SEC" "1"
					( Origin gPackager )
				)
				( attribute "LOCATION" "C9N21"
					( Origin gFrontEnd )
				)
				( attribute "MATERIAL" "X6S"
					( Origin gFrontEnd )
				)
				( attribute "PACK_TYPE" "0805"
					( Origin gFrontEnd )
				)
				( attribute "PART_NUMBER" "C95333-007"
					( Origin gFrontEnd )
				)
				( attribute "PHYS_PAGE" "210"
					( Origin gFrontEnd )
				)
				( attribute "ROOM" "PVSA_CPU1_PWR_VR"
					( Origin gFrontEnd )
				)
				( attribute "ROT" "0"
					( Origin gFrontEnd )
				)
				( attribute "SEC" "1"
					( Origin gFrontEnd )
				)
				( attribute "SEC_TYPE" "0805"
					( Origin gFrontEnd )
				)
				( attribute "TOLERANCE" "10%"
					( Origin gFrontEnd )
				)
				( attribute "VALUE" "10UF"
					( Origin gFrontEnd )
				)
				( attribute "VER" "1"
					( Origin gFrontEnd )
				)
				( attribute "VOLTAGE" "16V"
					( Units "uVoltage" "V" 1.000000)
					( Origin gFrontEnd )
				)
				( attribute "XY" "(-7400,3850)"
					( Origin gFrontEnd )
				)
				( attribute "CHIPS_PART_NAME" "CAP"
					( Origin gPackager )
				)
				( attribute "CDS_PART_NAME" "CAP_0805-10UF,16V,10%,X6S,C953A"
					( Origin gPackager )
				)
				( objectStatus "C9N21" )
				( pin "a"
					( attribute "PN" "1"
						( Origin gPackager )
					)
					( objectStatus "C9N21.1" )
				)
				( pin "b"
					( attribute "PN" "2"
						( Origin gPackager )
					)
					( objectStatus "C9N21.2" )
				)
			)
			( gate "@baseboard_fab2_lib.baseboard_fab2(sch_1):page210_i44"
				( attribute "CDS_LIB" "dev_discrete"
					( Origin gPackager )
				)
				( attribute "CDS_LOCATION" "C9N22"
					( Origin gPackager )
				)
				( attribute "CDS_SEC" "1"
					( Origin gPackager )
				)
				( attribute "LOCATION" "C9N22"
					( Origin gFrontEnd )
				)
				( attribute "MATERIAL" "X6S"
					( Origin gFrontEnd )
				)
				( attribute "PACK_TYPE" "0603V"
					( Origin gFrontEnd )
				)
				( attribute "PART_NUMBER" "E15431-004"
					( Origin gFrontEnd )
				)
				( attribute "PHYS_PAGE" "210"
					( Origin gFrontEnd )
				)
				( attribute "ROT" "0"
					( Origin gFrontEnd )
				)
				( attribute "SEC" "1"
					( Origin gFrontEnd )
				)
				( attribute "SEC_TYPE" "0603V"
					( Origin gFrontEnd )
				)
				( attribute "TOLERANCE" "20%"
					( Origin gFrontEnd )
				)
				( attribute "VALUE" "22.0UF"
					( Origin gFrontEnd )
				)
				( attribute "VER" "1"
					( Origin gFrontEnd )
				)
				( attribute "VOLTAGE" "4V"
					( Units "uVoltage" "V" 1.000000)
					( Origin gFrontEnd )
				)
				( attribute "XY" "(-1050,3050)"
					( Origin gFrontEnd )
				)
				( attribute "CHIPS_PART_NAME" "CAP_A"
					( Origin gPackager )
				)
				( attribute "CDS_PART_NAME" "CAP_A_0603V-22.0UF,4V,20%,X6S,A"
					( Origin gPackager )
				)
				( objectStatus "C9N22" )
				( pin "a"
					( attribute "PN" "1"
						( Origin gPackager )
					)
					( objectStatus "C9N22.1" )
				)
				( pin "b"
					( attribute "PN" "2"
						( Origin gPackager )
					)
					( objectStatus "C9N22.2" )
				)
			)
			( gate "@baseboard_fab2_lib.baseboard_fab2(sch_1):page210_i45"
				( attribute "CDS_LIB" "mstr_discrete"
					( Origin gPackager )
				)
				( attribute "CDS_LOCATION" "R9N4"
					( Origin gPackager )
				)
				( attribute "CDS_SEC" "1"
					( Origin gPackager )
				)
				( attribute "LOCATION" "R9N4"
					( Origin gFrontEnd )
				)
				( attribute "MATERIAL" "CHIP"
					( Origin gFrontEnd )
				)
				( attribute "PACK_TYPE" "0402"
					( Origin gFrontEnd )
				)
				( attribute "PART_NUMBER" "G21796-208"
					( Origin gFrontEnd )
				)
				( attribute "PHYS_PAGE" "210"
					( Origin gFrontEnd )
				)
				( attribute "ROT" "0"
					( Origin gFrontEnd )
				)
				( attribute "SEC" "1"
					( Origin gPackager )
				)
				( attribute "TOLERANCE" "1.0%"
					( Origin gFrontEnd )
				)
				( attribute "VALUE" "51.1"
					( Origin gFrontEnd )
				)
				( attribute "VER" "2"
					( Origin gFrontEnd )
				)
				( attribute "WATTAGE" "1/16W"
					( Origin gFrontEnd )
				)
				( attribute "XY" "(-625,3075)"
					( Origin gFrontEnd )
				)
				( attribute "CHIPS_PART_NAME" "RES"
					( Origin gPackager )
				)
				( attribute "CDS_PART_NAME" "RES_0402-51.1,1.0%,1/16W,CHIP,A"
					( Origin gPackager )
				)
				( objectStatus "R9N4" )
				( pin "a"
					( attribute "PN" "1"
						( Origin gPackager )
					)
					( objectStatus "R9N4.1" )
				)
				( pin "b"
					( attribute "PN" "2"
						( Origin gPackager )
					)
					( objectStatus "R9N4.2" )
				)
			)
			( gate "@baseboard_fab2_lib.baseboard_fab2(sch_1):page210_i51"
				( attribute "CDS_LIB" "mstr_discrete"
					( Origin gPackager )
				)
				( attribute "CDS_LOCATION" "EU1C1"
					( Origin gPackager )
				)
				( attribute "CDS_SEC" "1"
					( Origin gPackager )
				)
				( attribute "LOCATION" "EU1C1"
					( Origin gFrontEnd )
				)
				( attribute "MATERIAL" "IC"
					( Origin gFrontEnd )
				)
				( attribute "PACK_TYPE" "SM"
					( Origin gFrontEnd )
				)
				( attribute "PART_NUMBER" "H73684-001"
					( Origin gFrontEnd )
				)
				( attribute "PHYS_PAGE" "210"
					( Origin gFrontEnd )
				)
				( attribute "ROT" "0"
					( Origin gFrontEnd )
				)
				( attribute "SEC" "1"
					( Origin gFrontEnd )
				)
				( attribute "SEC_TYPE" "SM"
					( Origin gFrontEnd )
				)
				( attribute "VALUE" "IR35412"
					( Origin gFrontEnd )
				)
				( attribute "VER" "1"
					( Origin gFrontEnd )
				)
				( attribute "XY" "(-3725,3600)"
					( Origin gFrontEnd )
				)
				( attribute "CHIPS_PART_NAME" "IR354XX"
					( Origin gPackager )
				)
				( attribute "CDS_PART_NAME" "IR354XX_SM-IR35412,IC,H73684-0A"
					( Origin gPackager )
				)
				( objectStatus "EU1C1" )
				( pin "boost"
					( attribute "PN" "33"
						( Origin gPackager )
					)
					( objectStatus "EU1C1.33" )
				)
				( pin "en"
					( attribute "PN" "35"
						( Origin gPackager )
					)
					( objectStatus "EU1C1.35" )
				)
				( pin "gl(0)"
					( attribute "PN" "6"
						( Origin gPackager )
					)
					( objectStatus "EU1C1.6" )
				)
				( pin "gl(1)"
					( attribute "PN" "41"
						( Origin gPackager )
					)
					( objectStatus "EU1C1.41" )
				)
				( pin "iout"
					( attribute "PN" "38"
						( Origin gPackager )
					)
					( objectStatus "EU1C1.38" )
				)
				( pin "lgnd"
					( attribute "PN" "2"
						( Origin gPackager )
					)
					( objectStatus "EU1C1.2" )
				)
				( pin "nc"
					( attribute "PN" "31"
						( Origin gPackager )
					)
					( objectStatus "EU1C1.31" )
				)
				( pin "ocset"
					( attribute "PN" "37"
						( Origin gPackager )
					)
					( objectStatus "EU1C1.37" )
				)
				( pin "pgnd(0)"
					( attribute "PN" "5"
						( Origin gPackager )
					)
					( objectStatus "EU1C1.5" )
				)
				( pin "pgnd(1)"
					( attribute "PN" "7"
						( Origin gPackager )
					)
					( objectStatus "EU1C1.7" )
				)
				( pin "pgnd(2)"
					( attribute "PN" "40"
						( Origin gPackager )
					)
					( objectStatus "EU1C1.40" )
				)
				( pin "phase"
					( attribute "PN" "32"
						( Origin gPackager )
					)
					( objectStatus "EU1C1.32" )
				)
				( pin "pwm"
					( attribute "PN" "34"
						( Origin gPackager )
					)
					( objectStatus "EU1C1.34" )
				)
				( pin "refin"
					( attribute "PN" "39"
						( Origin gPackager )
					)
					( objectStatus "EU1C1.39" )
				)
				( pin "sw"
					( attribute "PN" "10"
						( Origin gPackager )
					)
					( objectStatus "EU1C1.10" )
				)
				( pin "tout_flt"
					( attribute "PN" "36"
						( Origin gPackager )
					)
					( objectStatus "EU1C1.36" )
				)
				( pin "vcc"
					( attribute "PN" "3"
						( Origin gPackager )
					)
					( objectStatus "EU1C1.3" )
				)
				( pin "vdrv"
					( attribute "PN" "4"
						( Origin gPackager )
					)
					( objectStatus "EU1C1.4" )
				)
				( pin "vin(0)"
					( attribute "PN" "25"
						( Origin gPackager )
					)
					( objectStatus "EU1C1.25" )
				)
				( pin "vin(1)"
					( attribute "PN" "30"
						( Origin gPackager )
					)
					( objectStatus "EU1C1.30" )
				)
				( pin "vos"
					( attribute "PN" "1"
						( Origin gPackager )
					)
					( objectStatus "EU1C1.1" )
				)
			)
			( gate "@baseboard_fab2_lib.baseboard_fab2(sch_1):page210_i52"
				( attribute "CDS_LIB" "mstr_discrete"
					( Origin gPackager )
				)
				( attribute "CDS_LOCATION" "R1C37"
					( Origin gPackager )
				)
				( attribute "CDS_SEC" "1"
					( Origin gPackager )
				)
				( attribute "LOCATION" "R1C37"
					( Origin gFrontEnd )
				)
				( attribute "MATERIAL" "EMPTY"
					( Origin gFrontEnd )
				)
				( attribute "PACK_TYPE" "0402"
					( Origin gFrontEnd )
				)
				( attribute "PART_NUMBER" "G21796-187"
					( Origin gFrontEnd )
				)
				( attribute "PHYS_PAGE" "210"
					( Origin gFrontEnd )
				)
				( attribute "ROT" "0"
					( Origin gFrontEnd )
				)
				( attribute "SEC" "1"
					( Origin gPackager )
				)
				( attribute "TOLERANCE" "1%"
					( Origin gFrontEnd )
				)
				( attribute "VALUE" "68.1K"
					( Origin gFrontEnd )
				)
				( attribute "VER" "2"
					( Origin gFrontEnd )
				)
				( attribute "WATTAGE" "1/16W"
					( Origin gFrontEnd )
				)
				( attribute "XY" "(-1450,3775)"
					( Origin gFrontEnd )
				)
				( attribute "CHIPS_PART_NAME" "RES"
					( Origin gPackager )
				)
				( attribute "CDS_PART_NAME" "RES_0402-68.1K,1%,1/16W,EMPTY,A"
					( Origin gPackager )
				)
				( objectStatus "R1C37" )
				( pin "a"
					( attribute "PN" "1"
						( Origin gPackager )
					)
					( objectStatus "R1C37.1" )
				)
				( pin "b"
					( attribute "PN" "2"
						( Origin gPackager )
					)
					( objectStatus "R1C37.2" )
				)
			)
			( gate "@baseboard_fab2_lib.baseboard_fab2(sch_1):page211_i11"
				( attribute "CDS_LIB" "dev_discrete"
					( Origin gPackager )
				)
				( attribute "CDS_LOCATION" "C3P4"
					( Origin gPackager )
				)
				( attribute "CDS_SEC" "1"
					( Origin gPackager )
				)
				( attribute "LOCATION" "C3P4"
					( Origin gFrontEnd )
				)
				( attribute "MATERIAL" "X6S"
					( Origin gFrontEnd )
				)
				( attribute "PACK_TYPE" "0402V"
					( Origin gFrontEnd )
				)
				( attribute "PART_NUMBER" "D97712-004"
					( Origin gFrontEnd )
				)
				( attribute "PHYS_PAGE" "211"
					( Origin gFrontEnd )
				)
				( attribute "ROOM" "PVCCIO_CPU0"
					( Origin gFrontEnd )
				)
				( attribute "ROT" "0"
					( Origin gFrontEnd )
				)
				( attribute "SEC" "1"
					( Origin gFrontEnd )
				)
				( attribute "SEC_TYPE" "0402V"
					( Origin gFrontEnd )
				)
				( attribute "TOLERANCE" "10%"
					( Origin gFrontEnd )
				)
				( attribute "VALUE" "1.0UF"
					( Origin gFrontEnd )
				)
				( attribute "VER" "1"
					( Origin gFrontEnd )
				)
				( attribute "VOLTAGE" "6.3V"
					( Units "uVoltage" "V" 1.000000)
					( Origin gFrontEnd )
				)
				( attribute "XY" "(2475,1425)"
					( Origin gFrontEnd )
				)
				( attribute "CHIPS_PART_NAME" "CAP_A"
					( Origin gPackager )
				)
				( attribute "CDS_PART_NAME" "CAP_A_0402V-1.0UF,6.3V,10%,X6SA"
					( Origin gPackager )
				)
				( objectStatus "C3P4" )
				( pin "a"
					( attribute "PN" "1"
						( Origin gPackager )
					)
					( objectStatus "C3P4.1" )
				)
				( pin "b"
					( attribute "PN" "2"
						( Origin gPackager )
					)
					( objectStatus "C3P4.2" )
				)
			)
			( gate "@baseboard_fab2_lib.baseboard_fab2(sch_1):page211_i13"
				( attribute "CDS_LIB" "dev_discrete"
					( Origin gPackager )
				)
				( attribute "CDS_LOCATION" "C3P5"
					( Origin gPackager )
				)
				( attribute "CDS_SEC" "1"
					( Origin gPackager )
				)
				( attribute "LOCATION" "C3P5"
					( Origin gFrontEnd )
				)
				( attribute "MATERIAL" "X7R"
					( Origin gFrontEnd )
				)
				( attribute "PACK_TYPE" "0402V"
					( Origin gFrontEnd )
				)
				( attribute "PART_NUMBER" "A36096-030"
					( Origin gFrontEnd )
				)
				( attribute "PHYS_PAGE" "211"
					( Origin gFrontEnd )
				)
				( attribute "ROOM" "PVCCIO_CPU0"
					( Origin gFrontEnd )
				)
				( attribute "ROT" "0"
					( Origin gFrontEnd )
				)
				( attribute "SEC" "1"
					( Origin gFrontEnd )
				)
				( attribute "SEC_TYPE" "0402V"
					( Origin gFrontEnd )
				)
				( attribute "TOLERANCE" "10%"
					( Origin gFrontEnd )
				)
				( attribute "VALUE" "0.1UF"
					( Origin gFrontEnd )
				)
				( attribute "VER" "1"
					( Origin gFrontEnd )
				)
				( attribute "VOLTAGE" "16V"
					( Units "uVoltage" "V" 1.000000)
					( Origin gFrontEnd )
				)
				( attribute "XY" "(2075,1425)"
					( Origin gFrontEnd )
				)
				( attribute "CHIPS_PART_NAME" "CAP_A"
					( Origin gPackager )
				)
				( attribute "CDS_PART_NAME" "CAP_A_0402V-0.1UF,16V,10%,X7R,A"
					( Origin gPackager )
				)
				( objectStatus "C3P5" )
				( pin "a"
					( attribute "PN" "1"
						( Origin gPackager )
					)
					( objectStatus "C3P5.1" )
				)
				( pin "b"
					( attribute "PN" "2"
						( Origin gPackager )
					)
					( objectStatus "C3P5.2" )
				)
			)
			( gate "@baseboard_fab2_lib.baseboard_fab2(sch_1):page211_i16"
				( attribute "CDS_LIB" "mstr_discrete"
					( Origin gPackager )
				)
				( attribute "CDS_LOCATION" "R3P11"
					( Origin gPackager )
				)
				( attribute "CDS_SEC" "1"
					( Origin gPackager )
				)
				( attribute "LOCATION" "R3P11"
					( Origin gFrontEnd )
				)
				( attribute "MATERIAL" "CHIP"
					( Origin gFrontEnd )
				)
				( attribute "PACK_TYPE" "0402"
					( Origin gFrontEnd )
				)
				( attribute "PART_NUMBER" "G21497-005"
					( Origin gFrontEnd )
				)
				( attribute "PHYS_PAGE" "211"
					( Origin gFrontEnd )
				)
				( attribute "ROOM" "PVCCIO_CPU0"
					( Origin gFrontEnd )
				)
				( attribute "ROT" "0"
					( Origin gFrontEnd )
				)
				( attribute "SEC" "1"
					( Origin gFrontEnd )
				)
				( attribute "SEC_TYPE" "0402"
					( Origin gFrontEnd )
				)
				( attribute "TOLERANCE" "5%"
					( Origin gFrontEnd )
				)
				( attribute "VALUE" "0.0"
					( Origin gFrontEnd )
				)
				( attribute "VER" "1"
					( Origin gFrontEnd )
				)
				( attribute "WATTAGE" "1/16W"
					( Origin gFrontEnd )
				)
				( attribute "XY" "(-1250,2950)"
					( Origin gFrontEnd )
				)
				( attribute "CHIPS_PART_NAME" "RES"
					( Origin gPackager )
				)
				( attribute "CDS_PART_NAME" "RES_0402-0.0,5%,1/16W,CHIP,G21A"
					( Origin gPackager )
				)
				( objectStatus "R3P11" )
				( pin "a"
					( attribute "PN" "1"
						( Origin gPackager )
					)
					( objectStatus "R3P11.1" )
				)
				( pin "b"
					( attribute "PN" "2"
						( Origin gPackager )
					)
					( objectStatus "R3P11.2" )
				)
			)
			( gate "@baseboard_fab2_lib.baseboard_fab2(sch_1):page211_i17"
				( attribute "CDS_LIB" "mstr_discrete"
					( Origin gPackager )
				)
				( attribute "CDS_LOCATION" "R3P13"
					( Origin gPackager )
				)
				( attribute "CDS_SEC" "1"
					( Origin gPackager )
				)
				( attribute "LOCATION" "R3P13"
					( Origin gFrontEnd )
				)
				( attribute "MATERIAL" "EMPTY"
					( Origin gFrontEnd )
				)
				( attribute "PACK_TYPE" "0402"
					( Origin gFrontEnd )
				)
				( attribute "PART_NUMBER" "G21796-017"
					( Origin gFrontEnd )
				)
				( attribute "PHYS_PAGE" "211"
					( Origin gFrontEnd )
				)
				( attribute "ROOM" "PVCCIO_CPU0"
					( Origin gFrontEnd )
				)
				( attribute "ROT" "0"
					( Origin gFrontEnd )
				)
				( attribute "SEC" "1"
					( Origin gFrontEnd )
				)
				( attribute "SEC_TYPE" "0402"
					( Origin gFrontEnd )
				)
				( attribute "TOLERANCE" "1%"
					( Origin gFrontEnd )
				)
				( attribute "VALUE" "100.0"
					( Origin gFrontEnd )
				)
				( attribute "VER" "2"
					( Origin gFrontEnd )
				)
				( attribute "WATTAGE" "1/16W"
					( Origin gFrontEnd )
				)
				( attribute "XY" "(-1675,4500)"
					( Origin gFrontEnd )
				)
				( attribute "CHIPS_PART_NAME" "RES"
					( Origin gPackager )
				)
				( attribute "CDS_PART_NAME" "RES_0402-100.0,1%,1/16W,EMPTY,A"
					( Origin gPackager )
				)
				( objectStatus "R3P13" )
				( pin "a"
					( attribute "PN" "1"
						( Origin gPackager )
					)
					( objectStatus "R3P13.1" )
				)
				( pin "b"
					( attribute "PN" "2"
						( Origin gPackager )
					)
					( objectStatus "R3P13.2" )
				)
			)
			( gate "@baseboard_fab2_lib.baseboard_fab2(sch_1):page211_i20"
				( attribute "CDS_LIB" "dev_discrete"
					( Origin gPackager )
				)
				( attribute "CDS_LOCATION" "C3P3"
					( Origin gPackager )
				)
				( attribute "CDS_SEC" "1"
					( Origin gPackager )
				)
				( attribute "LOCATION" "C3P3"
					( Origin gFrontEnd )
				)
				( attribute "MATERIAL" "X6S"
					( Origin gFrontEnd )
				)
				( attribute "PACK_TYPE" "0402V"
					( Origin gFrontEnd )
				)
				( attribute "PART_NUMBER" "D97712-004"
					( Origin gFrontEnd )
				)
				( attribute "PHYS_PAGE" "211"
					( Origin gFrontEnd )
				)
				( attribute "ROOM" "PVCCIO_CPU0"
					( Origin gFrontEnd )
				)
				( attribute "ROT" "0"
					( Origin gFrontEnd )
				)
				( attribute "SEC" "1"
					( Origin gPackager )
				)
				( attribute "TOLERANCE" "10%"
					( Origin gFrontEnd )
				)
				( attribute "VALUE" "1.0UF"
					( Origin gFrontEnd )
				)
				( attribute "VER" "1"
					( Origin gFrontEnd )
				)
				( attribute "VOLTAGE" "6.3V"
					( Units "uVoltage" "V" 1.000000)
					( Origin gFrontEnd )
				)
				( attribute "XY" "(75,4175)"
					( Origin gFrontEnd )
				)
				( attribute "CHIPS_PART_NAME" "CAP_A"
					( Origin gPackager )
				)
				( attribute "CDS_PART_NAME" "CAP_A_0402V-1.0UF,6.3V,10%,X6SA"
					( Origin gPackager )
				)
				( objectStatus "C3P3" )
				( pin "a"
					( attribute "PN" "1"
						( Origin gPackager )
					)
					( objectStatus "C3P3.1" )
				)
				( pin "b"
					( attribute "PN" "2"
						( Origin gPackager )
					)
					( objectStatus "C3P3.2" )
				)
			)
			( gate "@baseboard_fab2_lib.baseboard_fab2(sch_1):page211_i22"
				( attribute "CDS_LIB" "dev_discrete"
					( Origin gPackager )
				)
				( attribute "CDS_LOCATION" "C3P7"
					( Origin gPackager )
				)
				( attribute "CDS_SEC" "1"
					( Origin gPackager )
				)
				( attribute "LOCATION" "C3P7"
					( Origin gFrontEnd )
				)
				( attribute "MATERIAL" "X7R"
					( Origin gFrontEnd )
				)
				( attribute "PACK_TYPE" "0402V"
					( Origin gFrontEnd )
				)
				( attribute "PART_NUMBER" "A36096-030"
					( Origin gFrontEnd )
				)
				( attribute "PHYS_PAGE" "211"
					( Origin gFrontEnd )
				)
				( attribute "ROOM" "PVCCIO_CPU0"
					( Origin gFrontEnd )
				)
				( attribute "ROT" "0"
					( Origin gFrontEnd )
				)
				( attribute "SEC" "1"
					( Origin gFrontEnd )
				)
				( attribute "SEC_TYPE" "0402V"
					( Origin gFrontEnd )
				)
				( attribute "TOLERANCE" "10%"
					( Origin gFrontEnd )
				)
				( attribute "VALUE" "0.1UF"
					( Origin gFrontEnd )
				)
				( attribute "VER" "1"
					( Origin gFrontEnd )
				)
				( attribute "VOLTAGE" "16V"
					( Units "uVoltage" "V" 1.000000)
					( Origin gFrontEnd )
				)
				( attribute "XY" "(-325,4175)"
					( Origin gFrontEnd )
				)
				( attribute "CHIPS_PART_NAME" "CAP_A"
					( Origin gPackager )
				)
				( attribute "CDS_PART_NAME" "CAP_A_0402V-0.1UF,16V,10%,X7R,A"
					( Origin gPackager )
				)
				( objectStatus "C3P7" )
				( pin "a"
					( attribute "PN" "1"
						( Origin gPackager )
					)
					( objectStatus "C3P7.1" )
				)
				( pin "b"
					( attribute "PN" "2"
						( Origin gPackager )
					)
					( objectStatus "C3P7.2" )
				)
			)
			( gate "@baseboard_fab2_lib.baseboard_fab2(sch_1):page211_i24"
				( attribute "CDS_LIB" "mstr_discrete"
					( Origin gPackager )
				)
				( attribute "CDS_LOCATION" "R3P22"
					( Origin gPackager )
				)
				( attribute "CDS_SEC" "1"
					( Origin gPackager )
				)
				( attribute "LOCATION" "R3P22"
					( Origin gFrontEnd )
				)
				( attribute "MATERIAL" "CHIP"
					( Origin gFrontEnd )
				)
				( attribute "PACK_TYPE" "0402"
					( Origin gFrontEnd )
				)
				( attribute "PART_NUMBER" "G21497-005"
					( Origin gFrontEnd )
				)
				( attribute "PHYS_PAGE" "211"
					( Origin gFrontEnd )
				)
				( attribute "ROOM" "PVCCIO_CPU0"
					( Origin gFrontEnd )
				)
				( attribute "ROT" "0"
					( Origin gFrontEnd )
				)
				( attribute "SEC" "1"
					( Origin gFrontEnd )
				)
				( attribute "SEC_TYPE" "0402"
					( Origin gFrontEnd )
				)
				( attribute "TOLERANCE" "5%"
					( Origin gFrontEnd )
				)
				( attribute "VALUE" "0.0"
					( Origin gFrontEnd )
				)
				( attribute "VER" "2"
					( Origin gFrontEnd )
				)
				( attribute "WATTAGE" "1/16W"
					( Origin gFrontEnd )
				)
				( attribute "XY" "(-625,4525)"
					( Origin gFrontEnd )
				)
				( attribute "CHIPS_PART_NAME" "RES"
					( Origin gPackager )
				)
				( attribute "CDS_PART_NAME" "RES_0402-0.0,5%,1/16W,CHIP,G21A"
					( Origin gPackager )
				)
				( objectStatus "R3P22" )
				( pin "a"
					( attribute "PN" "1"
						( Origin gPackager )
					)
					( objectStatus "R3P22.1" )
				)
				( pin "b"
					( attribute "PN" "2"
						( Origin gPackager )
					)
					( objectStatus "R3P22.2" )
				)
			)
			( gate "@baseboard_fab2_lib.baseboard_fab2(sch_1):page211_i28"
				( attribute "CDS_LIB" "mstr_discrete"
					( Origin gPackager )
				)
				( attribute "CDS_LOCATION" "R3P17"
					( Origin gPackager )
				)
				( attribute "CDS_SEC" "1"
					( Origin gPackager )
				)
				( attribute "LOCATION" "R3P17"
					( Origin gFrontEnd )
				)
				( attribute "MATERIAL" "EMPTY"
					( Origin gFrontEnd )
				)
				( attribute "PACK_TYPE" "0402"
					( Origin gFrontEnd )
				)
				( attribute "PART_NUMBER" "G21796-047"
					( Origin gFrontEnd )
				)
				( attribute "PHYS_PAGE" "211"
					( Origin gFrontEnd )
				)
				( attribute "ROOM" "PVCCIO_CPU0"
					( Origin gFrontEnd )
				)
				( attribute "ROT" "0"
					( Origin gFrontEnd )
				)
				( attribute "SEC" "1"
					( Origin gFrontEnd )
				)
				( attribute "SEC_TYPE" "0402"
					( Origin gFrontEnd )
				)
				( attribute "TOLERANCE" "1%"
					( Origin gFrontEnd )
				)
				( attribute "VALUE" "49.9"
					( Origin gFrontEnd )
				)
				( attribute "VER" "2"
					( Origin gFrontEnd )
				)
				( attribute "WATTAGE" "1/16W"
					( Origin gFrontEnd )
				)
				( attribute "XY" "(-2125,4525)"
					( Origin gFrontEnd )
				)
				( attribute "CHIPS_PART_NAME" "RES"
					( Origin gPackager )
				)
				( attribute "CDS_PART_NAME" "RES_0402-49.9,1%,1/16W,EMPTY,GA"
					( Origin gPackager )
				)
				( objectStatus "R3P17" )
				( pin "a"
					( attribute "PN" "1"
						( Origin gPackager )
					)
					( objectStatus "R3P17.1" )
				)
				( pin "b"
					( attribute "PN" "2"
						( Origin gPackager )
					)
					( objectStatus "R3P17.2" )
				)
			)
			( gate "@baseboard_fab2_lib.baseboard_fab2(sch_1):page211_i29"
				( attribute "CDS_LIB" "mstr_discrete"
					( Origin gPackager )
				)
				( attribute "CDS_LOCATION" "R3P15"
					( Origin gPackager )
				)
				( attribute "CDS_SEC" "1"
					( Origin gPackager )
				)
				( attribute "LOCATION" "R3P15"
					( Origin gFrontEnd )
				)
				( attribute "MATERIAL" "CHIP"
					( Origin gFrontEnd )
				)
				( attribute "PACK_TYPE" "0402"
					( Origin gFrontEnd )
				)
				( attribute "PART_NUMBER" "G21796-009"
					( Origin gFrontEnd )
				)
				( attribute "PHYS_PAGE" "211"
					( Origin gFrontEnd )
				)
				( attribute "ROOM" "PVCCIO_CPU0"
					( Origin gFrontEnd )
				)
				( attribute "ROT" "0"
					( Origin gFrontEnd )
				)
				( attribute "SEC" "1"
					( Origin gFrontEnd )
				)
				( attribute "SEC_TYPE" "0402"
					( Origin gFrontEnd )
				)
				( attribute "TOLERANCE" "1%"
					( Origin gFrontEnd )
				)
				( attribute "VALUE" "150.0"
					( Origin gFrontEnd )
				)
				( attribute "VER" "1"
					( Origin gFrontEnd )
				)
				( attribute "WATTAGE" "1/16W"
					( Origin gFrontEnd )
				)
				( attribute "XY" "(-1975,3975)"
					( Origin gFrontEnd )
				)
				( attribute "CHIPS_PART_NAME" "RES"
					( Origin gPackager )
				)
				( attribute "CDS_PART_NAME" "RES_0402-150.0,1%,1/16W,CHIP,GA"
					( Origin gPackager )
				)
				( objectStatus "R3P15" )
				( pin "a"
					( attribute "PN" "1"
						( Origin gPackager )
					)
					( objectStatus "R3P15.1" )
				)
				( pin "b"
					( attribute "PN" "2"
						( Origin gPackager )
					)
					( objectStatus "R3P15.2" )
				)
			)
			( gate "@baseboard_fab2_lib.baseboard_fab2(sch_1):page211_i31"
				( attribute "CDS_LIB" "mstr_discrete"
					( Origin gPackager )
				)
				( attribute "CDS_LOCATION" "R3P12"
					( Origin gPackager )
				)
				( attribute "CDS_SEC" "1"
					( Origin gPackager )
				)
				( attribute "LOCATION" "R3P12"
					( Origin gFrontEnd )
				)
				( attribute "MATERIAL" "CHIP"
					( Origin gFrontEnd )
				)
				( attribute "NO_XNET_CONNECTION" "1"
					( Origin gFrontEnd )
				)
				( attribute "PACK_TYPE" "0402"
					( Origin gFrontEnd )
				)
				( attribute "PART_NUMBER" "G21796-160"
					( Origin gFrontEnd )
				)
				( attribute "PHYS_PAGE" "211"
					( Origin gFrontEnd )
				)
				( attribute "ROOM" "PVCCIO_CPU0"
					( Origin gFrontEnd )
				)
				( attribute "ROT" "0"
					( Origin gFrontEnd )
				)
				( attribute "SEC" "1"
					( Origin gFrontEnd )
				)
				( attribute "SEC_TYPE" "0402"
					( Origin gFrontEnd )
				)
				( attribute "TOLERANCE" "1%"
					( Origin gFrontEnd )
				)
				( attribute "VALUE" "100.0K"
					( Origin gFrontEnd )
				)
				( attribute "VER" "2"
					( Origin gFrontEnd )
				)
				( attribute "WATTAGE" "1/16W"
					( Origin gFrontEnd )
				)
				( attribute "XY" "(-2500,4650)"
					( Origin gFrontEnd )
				)
				( attribute "CHIPS_PART_NAME" "RES"
					( Origin gPackager )
				)
				( attribute "CDS_PART_NAME" "RES_0402-100.0K,1%,1/16W,CHIP,B"
					( Origin gPackager )
				)
				( objectStatus "R3P12" )
				( pin "a"
					( attribute "PN" "1"
						( Origin gPackager )
					)
					( objectStatus "R3P12.1" )
				)
				( pin "b"
					( attribute "PN" "2"
						( Origin gPackager )
					)
					( objectStatus "R3P12.2" )
				)
			)
			( gate "@baseboard_fab2_lib.baseboard_fab2(sch_1):page211_i32"
				( attribute "CDS_LIB" "mstr_discrete"
					( Origin gPackager )
				)
				( attribute "CDS_LOCATION" "R3P16"
					( Origin gPackager )
				)
				( attribute "CDS_SEC" "1"
					( Origin gPackager )
				)
				( attribute "LOCATION" "R3P16"
					( Origin gFrontEnd )
				)
				( attribute "MATERIAL" "CHIP"
					( Origin gFrontEnd )
				)
				( attribute "PACK_TYPE" "0402"
					( Origin gFrontEnd )
				)
				( attribute "PART_NUMBER" "G21796-003"
					( Origin gFrontEnd )
				)
				( attribute "PHYS_PAGE" "211"
					( Origin gFrontEnd )
				)
				( attribute "ROOM" "PVCCIO_CPU0"
					( Origin gFrontEnd )
				)
				( attribute "ROT" "0"
					( Origin gFrontEnd )
				)
				( attribute "SEC" "1"
					( Origin gFrontEnd )
				)
				( attribute "SEC_TYPE" "0402"
					( Origin gFrontEnd )
				)
				( attribute "TOLERANCE" "1%"
					( Origin gFrontEnd )
				)
				( attribute "VALUE" "1.5K"
					( Origin gFrontEnd )
				)
				( attribute "VER" "2"
					( Origin gFrontEnd )
				)
				( attribute "WATTAGE" "1/16W"
					( Origin gFrontEnd )
				)
				( attribute "XY" "(-2500,4300)"
					( Origin gFrontEnd )
				)
				( attribute "CHIPS_PART_NAME" "RES"
					( Origin gPackager )
				)
				( attribute "CDS_PART_NAME" "RES_0402-1.5K,1%,1/16W,CHIP,G2A"
					( Origin gPackager )
				)
				( objectStatus "R3P16" )
				( pin "a"
					( attribute "PN" "1"
						( Origin gPackager )
					)
					( objectStatus "R3P16.1" )
				)
				( pin "b"
					( attribute "PN" "2"
						( Origin gPackager )
					)
					( objectStatus "R3P16.2" )
				)
			)
			( gate "@baseboard_fab2_lib.baseboard_fab2(sch_1):page211_i33"
				( attribute "CDS_LIB" "mstr_discrete"
					( Origin gPackager )
				)
				( attribute "CDS_LOCATION" "C3P2"
					( Origin gPackager )
				)
				( attribute "CDS_SEC" "1"
					( Origin gPackager )
				)
				( attribute "LOCATION" "C3P2"
					( Origin gFrontEnd )
				)
				( attribute "MATERIAL" "X7R"
					( Origin gFrontEnd )
				)
				( attribute "PACK_TYPE" "0402LF"
					( Origin gFrontEnd )
				)
				( attribute "PART_NUMBER" "A36096-046"
					( Origin gFrontEnd )
				)
				( attribute "PHYS_PAGE" "211"
					( Origin gFrontEnd )
				)
				( attribute "ROOM" "PVCCIO_CPU0"
					( Origin gFrontEnd )
				)
				( attribute "ROT" "2"
					( Origin gFrontEnd )
				)
				( attribute "SEC" "1"
					( Origin gFrontEnd )
				)
				( attribute "SEC_TYPE" "0402LF"
					( Origin gFrontEnd )
				)
				( attribute "TOLERANCE" "10%"
					( Origin gFrontEnd )
				)
				( attribute "VALUE" "1000PF"
					( Origin gFrontEnd )
				)
				( attribute "VER" "1"
					( Origin gFrontEnd )
				)
				( attribute "VOLTAGE" "50V"
					( Units "uVoltage" "V" 1.000000)
					( Origin gFrontEnd )
				)
				( attribute "XY" "(-2725,4275)"
					( Origin gFrontEnd )
				)
				( attribute "CHIPS_PART_NAME" "CAP"
					( Origin gPackager )
				)
				( attribute "CDS_PART_NAME" "CAP_0402LF-1000PF,50V,10%,X7R,A"
					( Origin gPackager )
				)
				( objectStatus "C3P2" )
				( pin "a"
					( attribute "PN" "1"
						( Origin gPackager )
					)
					( objectStatus "C3P2.1" )
				)
				( pin "b"
					( attribute "PN" "2"
						( Origin gPackager )
					)
					( objectStatus "C3P2.2" )
				)
			)
			( gate "@baseboard_fab2_lib.baseboard_fab2(sch_1):page211_i46"
				( attribute "CDS_LIB" "mstr_discrete"
					( Origin gPackager )
				)
				( attribute "CDS_LOCATION" "R3P24"
					( Origin gPackager )
				)
				( attribute "CDS_SEC" "1"
					( Origin gPackager )
				)
				( attribute "LOCATION" "R3P24"
					( Origin gFrontEnd )
				)
				( attribute "MATERIAL" "CHIP"
					( Origin gFrontEnd )
				)
				( attribute "PACK_TYPE" "0402"
					( Origin gFrontEnd )
				)
				( attribute "PART_NUMBER" "G21796-173"
					( Origin gFrontEnd )
				)
				( attribute "PHYS_PAGE" "211"
					( Origin gFrontEnd )
				)
				( attribute "ROOM" "PVCCIO_CPU0"
					( Origin gFrontEnd )
				)
				( attribute "ROT" "0"
					( Origin gFrontEnd )
				)
				( attribute "SEC" "1"
					( Origin gPackager )
				)
				( attribute "TOLERANCE" "1%"
					( Origin gFrontEnd )
				)
				( attribute "VALUE" "20.0"
					( Origin gFrontEnd )
				)
				( attribute "VER" "1"
					( Origin gFrontEnd )
				)
				( attribute "WATTAGE" "1/16W"
					( Origin gFrontEnd )
				)
				( attribute "XY" "(-1575,2400)"
					( Origin gFrontEnd )
				)
				( attribute "CHIPS_PART_NAME" "RES"
					( Origin gPackager )
				)
				( attribute "CDS_PART_NAME" "RES_0402-20.0,1%,1/16W,CHIP,G2A"
					( Origin gPackager )
				)
				( objectStatus "R3P24" )
				( pin "a"
					( attribute "PN" "1"
						( Origin gPackager )
					)
					( objectStatus "R3P24.1" )
				)
				( pin "b"
					( attribute "PN" "2"
						( Origin gPackager )
					)
					( objectStatus "R3P24.2" )
				)
			)
			( gate "@baseboard_fab2_lib.baseboard_fab2(sch_1):page211_i47"
				( attribute "CDS_LIB" "mstr_discrete"
					( Origin gPackager )
				)
				( attribute "CDS_LOCATION" "R3P23"
					( Origin gPackager )
				)
				( attribute "CDS_SEC" "1"
					( Origin gPackager )
				)
				( attribute "LOCATION" "R3P23"
					( Origin gFrontEnd )
				)
				( attribute "MATERIAL" "CHIP"
					( Origin gFrontEnd )
				)
				( attribute "PACK_TYPE" "0402"
					( Origin gFrontEnd )
				)
				( attribute "PART_NUMBER" "G21796-173"
					( Origin gFrontEnd )
				)
				( attribute "PHYS_PAGE" "211"
					( Origin gFrontEnd )
				)
				( attribute "ROOM" "PVCCIO_CPU0"
					( Origin gFrontEnd )
				)
				( attribute "ROT" "0"
					( Origin gFrontEnd )
				)
				( attribute "SEC" "1"
					( Origin gPackager )
				)
				( attribute "TOLERANCE" "1%"
					( Origin gFrontEnd )
				)
				( attribute "VALUE" "20.0"
					( Origin gFrontEnd )
				)
				( attribute "VER" "1"
					( Origin gFrontEnd )
				)
				( attribute "WATTAGE" "1/16W"
					( Origin gFrontEnd )
				)
				( attribute "XY" "(-1250,2450)"
					( Origin gFrontEnd )
				)
				( attribute "CHIPS_PART_NAME" "RES"
					( Origin gPackager )
				)
				( attribute "CDS_PART_NAME" "RES_0402-20.0,1%,1/16W,CHIP,G2A"
					( Origin gPackager )
				)
				( objectStatus "R3P23" )
				( pin "a"
					( attribute "PN" "1"
						( Origin gPackager )
					)
					( objectStatus "R3P23.1" )
				)
				( pin "b"
					( attribute "PN" "2"
						( Origin gPackager )
					)
					( objectStatus "R3P23.2" )
				)
			)
			( gate "@baseboard_fab2_lib.baseboard_fab2(sch_1):page211_i52"
				( attribute "CDS_LIB" "mstr_discrete"
					( Origin gPackager )
				)
				( attribute "CDS_LOCATION" "R3N31"
					( Origin gPackager )
				)
				( attribute "CDS_SEC" "1"
					( Origin gPackager )
				)
				( attribute "LOCATION" "R3N31"
					( Origin gFrontEnd )
				)
				( attribute "MATERIAL" "CHIP"
					( Origin gFrontEnd )
				)
				( attribute "PACK_TYPE" "0402"
					( Origin gFrontEnd )
				)
				( attribute "PART_NUMBER" "G21796-043"
					( Origin gFrontEnd )
				)
				( attribute "PHYS_PAGE" "211"
					( Origin gFrontEnd )
				)
				( attribute "ROOM" "PVCCIO_CPU0"
					( Origin gFrontEnd )
				)
				( attribute "ROT" "0"
					( Origin gFrontEnd )
				)
				( attribute "SEC" "1"
					( Origin gPackager )
				)
				( attribute "TOLERANCE" "1%"
					( Origin gFrontEnd )
				)
				( attribute "VALUE" "3.16K"
					( Origin gFrontEnd )
				)
				( attribute "VER" "2"
					( Origin gFrontEnd )
				)
				( attribute "WATTAGE" "1/16W"
					( Origin gFrontEnd )
				)
				( attribute "XY" "(-925,1350)"
					( Origin gFrontEnd )
				)
				( attribute "CHIPS_PART_NAME" "RES"
					( Origin gPackager )
				)
				( attribute "CDS_PART_NAME" "RES_0402-3.16K,1%,1/16W,CHIP,GA"
					( Origin gPackager )
				)
				( objectStatus "R3N31" )
				( pin "a"
					( attribute "PN" "1"
						( Origin gPackager )
					)
					( objectStatus "R3N31.1" )
				)
				( pin "b"
					( attribute "PN" "2"
						( Origin gPackager )
					)
					( objectStatus "R3N31.2" )
				)
			)
			( gate "@baseboard_fab2_lib.baseboard_fab2(sch_1):page211_i56"
				( attribute "CDS_LIB" "mstr_discrete"
					( Origin gPackager )
				)
				( attribute "CDS_LOCATION" "R3P25"
					( Origin gPackager )
				)
				( attribute "CDS_SEC" "1"
					( Origin gPackager )
				)
				( attribute "LOCATION" "R3P25"
					( Origin gFrontEnd )
				)
				( attribute "MATERIAL" "CHIP"
					( Origin gFrontEnd )
				)
				( attribute "PACK_TYPE" "0402"
					( Origin gFrontEnd )
				)
				( attribute "PART_NUMBER" "G21796-026"
					( Origin gFrontEnd )
				)
				( attribute "PHYS_PAGE" "211"
					( Origin gFrontEnd )
				)
				( attribute "ROOM" "PVCCIO_CPU0"
					( Origin gFrontEnd )
				)
				( attribute "ROT" "0"
					( Origin gFrontEnd )
				)
				( attribute "SEC" "1"
					( Origin gFrontEnd )
				)
				( attribute "SEC_TYPE" "0402"
					( Origin gFrontEnd )
				)
				( attribute "TOLERANCE" "1%"
					( Origin gFrontEnd )
				)
				( attribute "VALUE" "1.00K"
					( Origin gFrontEnd )
				)
				( attribute "VER" "2"
					( Origin gFrontEnd )
				)
				( attribute "WATTAGE" "1/16W"
					( Origin gFrontEnd )
				)
				( attribute "XY" "(775,4100)"
					( Origin gFrontEnd )
				)
				( attribute "CHIPS_PART_NAME" "RES"
					( Origin gPackager )
				)
				( attribute "CDS_PART_NAME" "RES_0402-1.00K,1%,1/16W,CHIP,GA"
					( Origin gPackager )
				)
				( objectStatus "R3P25" )
				( pin "a"
					( attribute "PN" "1"
						( Origin gPackager )
					)
					( objectStatus "R3P25.1" )
				)
				( pin "b"
					( attribute "PN" "2"
						( Origin gPackager )
					)
					( objectStatus "R3P25.2" )
				)
			)
			( gate "@baseboard_fab2_lib.baseboard_fab2(sch_1):page211_i58"
				( attribute "CDS_LIB" "mstr_discrete"
					( Origin gPackager )
				)
				( attribute "CDS_LOCATION" "R3P20"
					( Origin gPackager )
				)
				( attribute "CDS_SEC" "1"
					( Origin gPackager )
				)
				( attribute "LOCATION" "R3P20"
					( Origin gFrontEnd )
				)
				( attribute "MATERIAL" "CHIP"
					( Origin gFrontEnd )
				)
				( attribute "PACK_TYPE" "0402"
					( Origin gFrontEnd )
				)
				( attribute "PART_NUMBER" "G21796-250"
					( Origin gFrontEnd )
				)
				( attribute "PHYS_PAGE" "211"
					( Origin gFrontEnd )
				)
				( attribute "ROOM" "PVCCIO_CPU0"
					( Origin gFrontEnd )
				)
				( attribute "ROT" "0"
					( Origin gFrontEnd )
				)
				( attribute "SEC" "1"
					( Origin gFrontEnd )
				)
				( attribute "SEC_TYPE" "0402"
					( Origin gFrontEnd )
				)
				( attribute "TOLERANCE" "1.0%"
					( Origin gFrontEnd )
				)
				( attribute "VALUE" "22.1"
					( Origin gFrontEnd )
				)
				( attribute "VER" "1"
					( Origin gFrontEnd )
				)
				( attribute "WATTAGE" "1/16W"
					( Origin gFrontEnd )
				)
				( attribute "XY" "(1875,3600)"
					( Origin gFrontEnd )
				)
				( attribute "CHIPS_PART_NAME" "RES"
					( Origin gPackager )
				)
				( attribute "CDS_PART_NAME" "RES_0402-22.1,1.0%,1/16W,CHIP,A"
					( Origin gPackager )
				)
				( objectStatus "R3P20" )
				( pin "a"
					( attribute "PN" "1"
						( Origin gPackager )
					)
					( objectStatus "R3P20.1" )
				)
				( pin "b"
					( attribute "PN" "2"
						( Origin gPackager )
					)
					( objectStatus "R3P20.2" )
				)
			)
			( gate "@baseboard_fab2_lib.baseboard_fab2(sch_1):page211_i60"
				( attribute "CDS_LIB" "mstr_discrete"
					( Origin gPackager )
				)
				( attribute "CDS_LOCATION" "R3N23"
					( Origin gPackager )
				)
				( attribute "CDS_SEC" "1"
					( Origin gPackager )
				)
				( attribute "LOCATION" "R3N23"
					( Origin gFrontEnd )
				)
				( attribute "MATERIAL" "EMPTY"
					( Origin gFrontEnd )
				)
				( attribute "PACK_TYPE" "0402"
					( Origin gFrontEnd )
				)
				( attribute "PART_NUMBER" "G21796-311"
					( Origin gFrontEnd )
				)
				( attribute "PHYS_PAGE" "211"
					( Origin gFrontEnd )
				)
				( attribute "ROOM" "PVCCIO_CPU0"
					( Origin gFrontEnd )
				)
				( attribute "ROT" "0"
					( Origin gFrontEnd )
				)
				( attribute "SEC" "1"
					( Origin gFrontEnd )
				)
				( attribute "SEC_TYPE" "0402"
					( Origin gFrontEnd )
				)
				( attribute "TOLERANCE" "1.0%"
					( Origin gFrontEnd )
				)
				( attribute "VALUE" "2.26K"
					( Origin gFrontEnd )
				)
				( attribute "VER" "2"
					( Origin gFrontEnd )
				)
				( attribute "WATTAGE" "1/16W"
					( Origin gFrontEnd )
				)
				( attribute "XY" "(1525,4100)"
					( Origin gFrontEnd )
				)
				( attribute "CHIPS_PART_NAME" "RES"
					( Origin gPackager )
				)
				( attribute "CDS_PART_NAME" "RES_0402-2.26K,1.0%,1/16W,EMPTA"
					( Origin gPackager )
				)
				( objectStatus "R3N23" )
				( pin "a"
					( attribute "PN" "1"
						( Origin gPackager )
					)
					( objectStatus "R3N23.1" )
				)
				( pin "b"
					( attribute "PN" "2"
						( Origin gPackager )
					)
					( objectStatus "R3N23.2" )
				)
			)
			( gate "@baseboard_fab2_lib.baseboard_fab2(sch_1):page211_i61"
				( attribute "CDS_LIB" "mstr_discrete"
					( Origin gPackager )
				)
				( attribute "CDS_LOCATION" "R3P1"
					( Origin gPackager )
				)
				( attribute "CDS_SEC" "1"
					( Origin gPackager )
				)
				( attribute "LOCATION" "R3P1"
					( Origin gFrontEnd )
				)
				( attribute "MATERIAL" "CHIP"
					( Origin gFrontEnd )
				)
				( attribute "PACK_TYPE" "0402"
					( Origin gFrontEnd )
				)
				( attribute "PART_NUMBER" "G21497-005"
					( Origin gFrontEnd )
				)
				( attribute "PHYS_PAGE" "211"
					( Origin gFrontEnd )
				)
				( attribute "ROOM" "PVCCIO_CPU0"
					( Origin gFrontEnd )
				)
				( attribute "ROT" "0"
					( Origin gFrontEnd )
				)
				( attribute "SEC" "1"
					( Origin gFrontEnd )
				)
				( attribute "SEC_TYPE" "0402"
					( Origin gFrontEnd )
				)
				( attribute "TOLERANCE" "5%"
					( Origin gFrontEnd )
				)
				( attribute "VALUE" "0.0"
					( Origin gFrontEnd )
				)
				( attribute "VER" "1"
					( Origin gFrontEnd )
				)
				( attribute "WATTAGE" "1/16W"
					( Origin gFrontEnd )
				)
				( attribute "XY" "(1300,3150)"
					( Origin gFrontEnd )
				)
				( attribute "CHIPS_PART_NAME" "RES"
					( Origin gPackager )
				)
				( attribute "CDS_PART_NAME" "RES_0402-0.0,5%,1/16W,CHIP,G21A"
					( Origin gPackager )
				)
				( objectStatus "R3P1" )
				( pin "a"
					( attribute "PN" "1"
						( Origin gPackager )
					)
					( objectStatus "R3P1.1" )
				)
				( pin "b"
					( attribute "PN" "2"
						( Origin gPackager )
					)
					( objectStatus "R3P1.2" )
				)
			)
			( gate "@baseboard_fab2_lib.baseboard_fab2(sch_1):page211_i64"
				( attribute "CDS_LIB" "mstr_discrete"
					( Origin gPackager )
				)
				( attribute "CDS_LOCATION" "R3P18"
					( Origin gPackager )
				)
				( attribute "CDS_SEC" "1"
					( Origin gPackager )
				)
				( attribute "LOCATION" "R3P18"
					( Origin gFrontEnd )
				)
				( attribute "MATERIAL" "CHIP"
					( Origin gFrontEnd )
				)
				( attribute "PACK_TYPE" "0402"
					( Origin gFrontEnd )
				)
				( attribute "PART_NUMBER" "G21796-026"
					( Origin gFrontEnd )
				)
				( attribute "PHYS_PAGE" "211"
					( Origin gFrontEnd )
				)
				( attribute "ROT" "0"
					( Origin gFrontEnd )
				)
				( attribute "SEC" "1"
					( Origin gFrontEnd )
				)
				( attribute "SEC_TYPE" "0402"
					( Origin gFrontEnd )
				)
				( attribute "TOLERANCE" "1%"
					( Origin gFrontEnd )
				)
				( attribute "VALUE" "1.00K"
					( Origin gFrontEnd )
				)
				( attribute "VER" "2"
					( Origin gFrontEnd )
				)
				( attribute "WATTAGE" "1/16W"
					( Origin gFrontEnd )
				)
				( attribute "XY" "(2075,4050)"
					( Origin gFrontEnd )
				)
				( attribute "CHIPS_PART_NAME" "RES"
					( Origin gPackager )
				)
				( attribute "CDS_PART_NAME" "RES_0402-1.00K,1%,1/16W,CHIP,GA"
					( Origin gPackager )
				)
				( objectStatus "R3P18" )
				( pin "a"
					( attribute "PN" "1"
						( Origin gPackager )
					)
					( objectStatus "R3P18.1" )
				)
				( pin "b"
					( attribute "PN" "2"
						( Origin gPackager )
					)
					( objectStatus "R3P18.2" )
				)
			)
			( gate "@baseboard_fab2_lib.baseboard_fab2(sch_1):page211_i65"
				( attribute "CDS_LIB" "mstr_discrete"
					( Origin gPackager )
				)
				( attribute "CDS_LOCATION" "R3N22"
					( Origin gPackager )
				)
				( attribute "CDS_SEC" "1"
					( Origin gPackager )
				)
				( attribute "LOCATION" "R3N22"
					( Origin gFrontEnd )
				)
				( attribute "MATERIAL" "CHIP"
					( Origin gFrontEnd )
				)
				( attribute "PACK_TYPE" "0402"
					( Origin gFrontEnd )
				)
				( attribute "PART_NUMBER" "G21796-082"
					( Origin gFrontEnd )
				)
				( attribute "PHYS_PAGE" "211"
					( Origin gFrontEnd )
				)
				( attribute "ROT" "0"
					( Origin gFrontEnd )
				)
				( attribute "SEC" "1"
					( Origin gPackager )
				)
				( attribute "TOLERANCE" "1%"
					( Origin gFrontEnd )
				)
				( attribute "VALUE" "4.02K"
					( Origin gFrontEnd )
				)
				( attribute "VER" "2"
					( Origin gFrontEnd )
				)
				( attribute "WATTAGE" "1/16W"
					( Origin gFrontEnd )
				)
				( attribute "XY" "(-575,1375)"
					( Origin gFrontEnd )
				)
				( attribute "CHIPS_PART_NAME" "RES"
					( Origin gPackager )
				)
				( attribute "CDS_PART_NAME" "RES_0402-4.02K,1%,1/16W,CHIP,GA"
					( Origin gPackager )
				)
				( objectStatus "R3N22" )
				( pin "a"
					( attribute "PN" "1"
						( Origin gPackager )
					)
					( objectStatus "R3N22.1" )
				)
				( pin "b"
					( attribute "PN" "2"
						( Origin gPackager )
					)
					( objectStatus "R3N22.2" )
				)
			)
			( gate "@baseboard_fab2_lib.baseboard_fab2(sch_1):page211_i71"
				( attribute "CDS_LIB" "mstr_discrete"
					( Origin gPackager )
				)
				( attribute "CDS_LOCATION" "C3P6"
					( Origin gPackager )
				)
				( attribute "CDS_SEC" "1"
					( Origin gPackager )
				)
				( attribute "LOCATION" "C3P6"
					( Origin gFrontEnd )
				)
				( attribute "MATERIAL" "X7R"
					( Origin gFrontEnd )
				)
				( attribute "PACK_TYPE" "0402LF"
					( Origin gFrontEnd )
				)
				( attribute "PART_NUMBER" "A36096-046"
					( Origin gFrontEnd )
				)
				( attribute "PHYS_PAGE" "211"
					( Origin gFrontEnd )
				)
				( attribute "ROOM" "PVCCIO_CPU0_VR"
					( Origin gFrontEnd )
				)
				( attribute "ROT" "0"
					( Origin gFrontEnd )
				)
				( attribute "SEC" "1"
					( Origin gFrontEnd )
				)
				( attribute "SEC_TYPE" "0402LF"
					( Origin gFrontEnd )
				)
				( attribute "TOLERANCE" "10%"
					( Origin gFrontEnd )
				)
				( attribute "VALUE" "1000PF"
					( Origin gFrontEnd )
				)
				( attribute "VER" "1"
					( Origin gFrontEnd )
				)
				( attribute "VOLTAGE" "50V"
					( Units "uVoltage" "V" 1.000000)
					( Origin gFrontEnd )
				)
				( attribute "XY" "(1650,2750)"
					( Origin gFrontEnd )
				)
				( attribute "CHIPS_PART_NAME" "CAP"
					( Origin gPackager )
				)
				( attribute "CDS_PART_NAME" "CAP_0402LF-1000PF,50V,10%,X7R,A"
					( Origin gPackager )
				)
				( objectStatus "C3P6" )
				( pin "a"
					( attribute "PN" "1"
						( Origin gPackager )
					)
					( objectStatus "C3P6.1" )
				)
				( pin "b"
					( attribute "PN" "2"
						( Origin gPackager )
					)
					( objectStatus "C3P6.2" )
				)
			)
			( gate "@baseboard_fab2_lib.baseboard_fab2(sch_1):page211_i81"
				( attribute "CDS_LIB" "mstr_discrete"
					( Origin gPackager )
				)
				( attribute "CDS_LOCATION" "R3N19"
					( Origin gPackager )
				)
				( attribute "CDS_SEC" "1"
					( Origin gPackager )
				)
				( attribute "LOCATION" "R3N19"
					( Origin gFrontEnd )
				)
				( attribute "MATERIAL" "CHIP"
					( Origin gFrontEnd )
				)
				( attribute "PACK_TYPE" "0402"
					( Origin gFrontEnd )
				)
				( attribute "PART_NUMBER" "G21796-066"
					( Origin gFrontEnd )
				)
				( attribute "PHYS_PAGE" "211"
					( Origin gFrontEnd )
				)
				( attribute "ROOM" "PVCCIO_CPU0"
					( Origin gFrontEnd )
				)
				( attribute "ROT" "0"
					( Origin gFrontEnd )
				)
				( attribute "SEC" "1"
					( Origin gPackager )
				)
				( attribute "TOLERANCE" "1%"
					( Origin gFrontEnd )
				)
				( attribute "VALUE" "10.0"
					( Origin gFrontEnd )
				)
				( attribute "VER" "1"
					( Origin gFrontEnd )
				)
				( attribute "WATTAGE" "1/16W"
					( Origin gFrontEnd )
				)
				( attribute "XY" "(-2600,2050)"
					( Origin gFrontEnd )
				)
				( attribute "CHIPS_PART_NAME" "RES"
					( Origin gPackager )
				)
				( attribute "CDS_PART_NAME" "RES_0402-10.0,1%,1/16W,CHIP,G2A"
					( Origin gPackager )
				)
				( objectStatus "R3N19" )
				( pin "a"
					( attribute "PN" "1"
						( Origin gPackager )
					)
					( objectStatus "R3N19.1" )
				)
				( pin "b"
					( attribute "PN" "2"
						( Origin gPackager )
					)
					( objectStatus "R3N19.2" )
				)
			)
			( gate "@baseboard_fab2_lib.baseboard_fab2(sch_1):page211_i83"
				( attribute "CDS_LIB" "mstr_discrete"
					( Origin gPackager )
				)
				( attribute "CDS_LOCATION" "C3N39"
					( Origin gPackager )
				)
				( attribute "CDS_SEC" "1"
					( Origin gPackager )
				)
				( attribute "LOCATION" "C3N39"
					( Origin gFrontEnd )
				)
				( attribute "MATERIAL" "X7R"
					( Origin gFrontEnd )
				)
				( attribute "PACK_TYPE" "0402LF"
					( Origin gFrontEnd )
				)
				( attribute "PART_NUMBER" "A36096-050"
					( Origin gFrontEnd )
				)
				( attribute "PHYS_PAGE" "211"
					( Origin gFrontEnd )
				)
				( attribute "ROOM" "PVCCIO_CPU0"
					( Origin gFrontEnd )
				)
				( attribute "ROT" "0"
					( Origin gFrontEnd )
				)
				( attribute "SEC" "1"
					( Origin gFrontEnd )
				)
				( attribute "SEC_TYPE" "0402LF"
					( Origin gFrontEnd )
				)
				( attribute "TOLERANCE" "10%"
					( Origin gFrontEnd )
				)
				( attribute "VALUE" "220PF"
					( Origin gFrontEnd )
				)
				( attribute "VER" "1"
					( Origin gFrontEnd )
				)
				( attribute "VOLTAGE" "50V"
					( Units "uVoltage" "V" 1.000000)
					( Origin gFrontEnd )
				)
				( attribute "XY" "(-2400,1850)"
					( Origin gFrontEnd )
				)
				( attribute "CHIPS_PART_NAME" "CAP"
					( Origin gPackager )
				)
				( attribute "CDS_PART_NAME" "CAP_0402LF-220PF,50V,10%,X7R,AA"
					( Origin gPackager )
				)
				( objectStatus "C3N39" )
				( pin "a"
					( attribute "PN" "1"
						( Origin gPackager )
					)
					( objectStatus "C3N39.1" )
				)
				( pin "b"
					( attribute "PN" "2"
						( Origin gPackager )
					)
					( objectStatus "C3N39.2" )
				)
			)
			( gate "@baseboard_fab2_lib.baseboard_fab2(sch_1):page211_i87"
				( attribute "CDS_LIB" "mstr_discrete"
					( Origin gPackager )
				)
				( attribute "CDS_LOCATION" "R3P26"
					( Origin gPackager )
				)
				( attribute "CDS_SEC" "1"
					( Origin gPackager )
				)
				( attribute "LOCATION" "R3P26"
					( Origin gFrontEnd )
				)
				( attribute "MATERIAL" "CHIP"
					( Origin gFrontEnd )
				)
				( attribute "PACK_TYPE" "0402"
					( Origin gFrontEnd )
				)
				( attribute "PART_NUMBER" "G21497-005"
					( Origin gFrontEnd )
				)
				( attribute "PHYS_PAGE" "211"
					( Origin gFrontEnd )
				)
				( attribute "ROOM" "PVCCIN_CPU0_VR"
					( Origin gFrontEnd )
				)
				( attribute "ROT" "0"
					( Origin gFrontEnd )
				)
				( attribute "SEC" "1"
					( Origin gPackager )
				)
				( attribute "TOLERANCE" "5%"
					( Origin gFrontEnd )
				)
				( attribute "VALUE" "0.0"
					( Origin gFrontEnd )
				)
				( attribute "VER" "1"
					( Origin gFrontEnd )
				)
				( attribute "WATTAGE" "1/16W"
					( Origin gFrontEnd )
				)
				( attribute "XY" "(-1950,3250)"
					( Origin gFrontEnd )
				)
				( attribute "CHIPS_PART_NAME" "RES"
					( Origin gPackager )
				)
				( attribute "CDS_PART_NAME" "RES_0402-0.0,5%,1/16W,CHIP,G21A"
					( Origin gPackager )
				)
				( objectStatus "R3P26" )
				( pin "a"
					( attribute "PN" "1"
						( Origin gPackager )
					)
					( objectStatus "R3P26.1" )
				)
				( pin "b"
					( attribute "PN" "2"
						( Origin gPackager )
					)
					( objectStatus "R3P26.2" )
				)
			)
			( gate "@baseboard_fab2_lib.baseboard_fab2(sch_1):page211_i88"
				( attribute "BOM_COST" "SM_CONTROLLER"
					( Origin gFrontEnd )
				)
				( attribute "CDS_LIB" "mstr_discrete"
					( Origin gPackager )
				)
				( attribute "CDS_LOCATION" "R3P21"
					( Origin gPackager )
				)
				( attribute "CDS_SEC" "1"
					( Origin gPackager )
				)
				( attribute "LOCATION" "R3P21"
					( Origin gFrontEnd )
				)
				( attribute "MATERIAL" "EMPTY"
					( Origin gFrontEnd )
				)
				( attribute "PACK_TYPE" "0402"
					( Origin gFrontEnd )
				)
				( attribute "PART_NUMBER" "G21796-010"
					( Origin gFrontEnd )
				)
				( attribute "PHYS_PAGE" "211"
					( Origin gFrontEnd )
				)
				( attribute "ROOM" "BMC"
					( Origin gFrontEnd )
				)
				( attribute "ROT" "0"
					( Origin gFrontEnd )
				)
				( attribute "SEC" "1"
					( Origin gPackager )
				)
				( attribute "TOLERANCE" "1%"
					( Origin gFrontEnd )
				)
				( attribute "VALUE" "100.0K"
					( Origin gFrontEnd )
				)
				( attribute "VER" "2"
					( Origin gFrontEnd )
				)
				( attribute "WATTAGE" "1/16W"
					( Origin gFrontEnd )
				)
				( attribute "XY" "(-1125,4300)"
					( Origin gFrontEnd )
				)
				( attribute "CHIPS_PART_NAME" "RES"
					( Origin gPackager )
				)
				( attribute "CDS_PART_NAME" "RES_0402-100.0K,1%,1/16W,EMPTYA"
					( Origin gPackager )
				)
				( objectStatus "R3P21" )
				( pin "a"
					( attribute "PN" "1"
						( Origin gPackager )
					)
					( objectStatus "R3P21.1" )
				)
				( pin "b"
					( attribute "PN" "2"
						( Origin gPackager )
					)
					( objectStatus "R3P21.2" )
				)
			)
			( gate "@baseboard_fab2_lib.baseboard_fab2(sch_1):page211_i91"
				( attribute "CDS_LIB" "mstr_discrete"
					( Origin gPackager )
				)
				( attribute "CDS_LOCATION" "R3P57"
					( Origin gPackager )
				)
				( attribute "CDS_SEC" "1"
					( Origin gPackager )
				)
				( attribute "LOCATION" "R3P57"
					( Origin gFrontEnd )
				)
				( attribute "MATERIAL" "CHIP"
					( Origin gFrontEnd )
				)
				( attribute "PACK_TYPE" "0402"
					( Origin gFrontEnd )
				)
				( attribute "PART_NUMBER" "G21497-005"
					( Origin gFrontEnd )
				)
				( attribute "PHYS_PAGE" "211"
					( Origin gFrontEnd )
				)
				( attribute "ROOM" "PVCCIN_CPU0_VR"
					( Origin gFrontEnd )
				)
				( attribute "ROT" "0"
					( Origin gFrontEnd )
				)
				( attribute "SEC" "1"
					( Origin gPackager )
				)
				( attribute "TOLERANCE" "5%"
					( Origin gFrontEnd )
				)
				( attribute "VALUE" "0.0"
					( Origin gFrontEnd )
				)
				( attribute "VER" "1"
					( Origin gFrontEnd )
				)
				( attribute "WATTAGE" "1/16W"
					( Origin gFrontEnd )
				)
				( attribute "XY" "(-2450,3750)"
					( Origin gFrontEnd )
				)
				( attribute "CHIPS_PART_NAME" "RES"
					( Origin gPackager )
				)
				( attribute "CDS_PART_NAME" "RES_0402-0.0,5%,1/16W,CHIP,G21A"
					( Origin gPackager )
				)
				( objectStatus "R3P57" )
				( pin "a"
					( attribute "PN" "1"
						( Origin gPackager )
					)
					( objectStatus "R3P57.1" )
				)
				( pin "b"
					( attribute "PN" "2"
						( Origin gPackager )
					)
					( objectStatus "R3P57.2" )
				)
			)
			( gate "@baseboard_fab2_lib.baseboard_fab2(sch_1):page211_i93"
				( attribute "CDS_LIB" "mstr_controller"
					( Origin gPackager )
				)
				( attribute "CDS_LMAN_SYM_OUTLINE" "-400,850,400,-850"
					( Origin gPackager )
				)
				( attribute "CDS_LOCATION" "EU3P1"
					( Origin gPackager )
				)
				( attribute "CDS_SEC" "1"
					( Origin gPackager )
				)
				( attribute "LOCATION" "EU3P1"
					( Origin gFrontEnd )
				)
				( attribute "MATERIAL" "IC"
					( Origin gFrontEnd )
				)
				( attribute "PACK_TYPE" "QFN"
					( Origin gFrontEnd )
				)
				( attribute "PART_NUMBER" "H89187-001"
					( Origin gFrontEnd )
				)
				( attribute "PHYS_PAGE" "211"
					( Origin gFrontEnd )
				)
				( attribute "ROT" "0"
					( Origin gFrontEnd )
				)
				( attribute "SEC" "1"
					( Origin gFrontEnd )
				)
				( attribute "SEC_TYPE" "QFN"
					( Origin gFrontEnd )
				)
				( attribute "VER" "1"
					( Origin gFrontEnd )
				)
				( attribute "XY" "(100,2850)"
					( Origin gFrontEnd )
				)
				( attribute "CHIPS_PART_NAME" "PXE1110B"
					( Origin gPackager )
				)
				( attribute "CDS_PART_NAME" "PXE1110B_QFN-IC,H89187-001"
					( Origin gPackager )
				)
				( objectStatus "EU3P1" )
				( pin "airef1"
					( attribute "PN" "21"
						( Origin gPackager )
					)
					( objectStatus "EU3P1.21" )
				)
				( pin "aisen1"
					( attribute "PN" "22"
						( Origin gPackager )
					)
					( objectStatus "EU3P1.22" )
				)
				( pin "apwm1"
					( attribute "PN" "5"
						( Origin gPackager )
					)
					( objectStatus "EU3P1.5" )
				)
				( pin "atsen"
					( attribute "PN" "35"
						( Origin gPackager )
					)
					( objectStatus "EU3P1.35" )
				)
				( pin "avref"
					( attribute "PN" "20"
						( Origin gPackager )
					)
					( objectStatus "EU3P1.20" )
				)
				( pin "avren"
					( attribute "PN" "10"
						( Origin gPackager )
					)
					( objectStatus "EU3P1.10" )
				)
				( pin "avrrdy"
					( attribute "PN" "9"
						( Origin gPackager )
					)
					( objectStatus "EU3P1.9" )
				)
				( pin "avsen"
					( attribute "PN" "19"
						( Origin gPackager )
					)
					( objectStatus "EU3P1.19" )
				)
				( pin "biref1"
					( attribute "PN" "25"
						( Origin gPackager )
					)
					( objectStatus "EU3P1.25" )
				)
				( pin "bisen1"
					( attribute "PN" "26"
						( Origin gPackager )
					)
					( objectStatus "EU3P1.26" )
				)
				( pin "bpwm1"
					( attribute "PN" "3"
						( Origin gPackager )
					)
					( objectStatus "EU3P1.3" )
				)
				( pin "btsen"
					( attribute "PN" "34"
						( Origin gPackager )
					)
					( objectStatus "EU3P1.34" )
				)
				( pin "bvref"
					( attribute "PN" "30"
						( Origin gPackager )
					)
					( objectStatus "EU3P1.30" )
				)
				( pin "bvsen"
					( attribute "PN" "29"
						( Origin gPackager )
					)
					( objectStatus "EU3P1.29" )
				)
				( pin "dnc(0)"
					( attribute "PN" "1"
						( Origin gPackager )
					)
					( objectStatus "EU3P1.1" )
				)
				( pin "dnc(1)"
					( attribute "PN" "2"
						( Origin gPackager )
					)
					( objectStatus "EU3P1.2" )
				)
				( pin "dnc(2)"
					( attribute "PN" "4"
						( Origin gPackager )
					)
					( objectStatus "EU3P1.4" )
				)
				( pin "dnc(3)"
					( attribute "PN" "24"
						( Origin gPackager )
					)
					( objectStatus "EU3P1.24" )
				)
				( pin "dnc(4)"
					( attribute "PN" "28"
						( Origin gPackager )
					)
					( objectStatus "EU3P1.28" )
				)
				( pin "gnd(0)"
					( attribute "PN" "27"
						( Origin gPackager )
					)
					( objectStatus "EU3P1.27" )
				)
				( pin "gnd(1)"
					( attribute "PN" "23"
						( Origin gPackager )
					)
					( objectStatus "EU3P1.23" )
				)
				( pin "iinsen"
					( attribute "PN" "38"
						( Origin gPackager )
					)
					( objectStatus "EU3P1.38" )
				)
				( pin "mp0"
					( attribute "PN" "13"
						( Origin gPackager )
					)
					( objectStatus "EU3P1.13" )
				)
				( pin "mp1"
					( attribute "PN" "14"
						( Origin gPackager )
					)
					( objectStatus "EU3P1.14" )
				)
				( pin "mp2"
					( attribute "PN" "18"
						( Origin gPackager )
					)
					( objectStatus "EU3P1.18" )
				)
				( pin "mp3"
					( attribute "PN" "31"
						( Origin gPackager )
					)
					( objectStatus "EU3P1.31" )
				)
				( pin "mp4"
					( attribute "PN" "32"
						( Origin gPackager )
					)
					( objectStatus "EU3P1.32" )
				)
				( pin "pinalrt_n"
					( attribute "PN" "12"
						( Origin gPackager )
					)
					( objectStatus "EU3P1.12" )
				)
				( pin "reset_n"
					( attribute "PN" "8"
						( Origin gPackager )
					)
					( objectStatus "EU3P1.8" )
				)
				( pin "scl"
					( attribute "PN" "7"
						( Origin gPackager )
					)
					( objectStatus "EU3P1.7" )
				)
				( pin "sda"
					( attribute "PN" "6"
						( Origin gPackager )
					)
					( objectStatus "EU3P1.6" )
				)
				( pin "thpad"
					( attribute "PN" "41"
						( Origin gPackager )
					)
					( objectStatus "EU3P1.41" )
				)
				( pin "valrt_n"
					( attribute "PN" "17"
						( Origin gPackager )
					)
					( objectStatus "EU3P1.17" )
				)
				( pin "vclk"
					( attribute "PN" "15"
						( Origin gPackager )
					)
					( objectStatus "EU3P1.15" )
				)
				( pin "vd12"
					( attribute "PN" "40"
						( Origin gPackager )
					)
					( objectStatus "EU3P1.40" )
				)
				( pin "vdd"
					( attribute "PN" "39"
						( Origin gPackager )
					)
					( objectStatus "EU3P1.39" )
				)
				( pin "vdio"
					( attribute "PN" "16"
						( Origin gPackager )
					)
					( objectStatus "EU3P1.16" )
				)
				( pin "vinsen"
					( attribute "PN" "37"
						( Origin gPackager )
					)
					( objectStatus "EU3P1.37" )
				)
				( pin "vrhot_n"
					( attribute "PN" "11"
						( Origin gPackager )
					)
					( objectStatus "EU3P1.11" )
				)
				( pin "xaddr1"
					( attribute "PN" "36"
						( Origin gPackager )
					)
					( objectStatus "EU3P1.36" )
				)
				( pin "xaddr2"
					( attribute "PN" "33"
						( Origin gPackager )
					)
					( objectStatus "EU3P1.33" )
				)
			)
			( gate "@baseboard_fab2_lib.baseboard_fab2(sch_1):page212_i16"
				( attribute "BOM_COST" "PROC_VRD_PVCCIO_CPU0"
					( Origin gFrontEnd )
				)
				( attribute "CDS_LIB" "mstr_discrete"
					( Origin gPackager )
				)
				( attribute "CDS_LOCATION" "C3N38"
					( Origin gPackager )
				)
				( attribute "CDS_SEC" "1"
					( Origin gPackager )
				)
				( attribute "LOCATION" "C3N38"
					( Origin gFrontEnd )
				)
				( attribute "MATERIAL" "ALUM"
					( Origin gFrontEnd )
				)
				( attribute "PACK_TYPE" "3018"
					( Origin gFrontEnd )
				)
				( attribute "PART_NUMBER" "699013-049"
					( Origin gFrontEnd )
				)
				( attribute "PHYS_PAGE" "212"
					( Origin gFrontEnd )
				)
				( attribute "ROOM" "PVCCIO_CPU0"
					( Origin gFrontEnd )
				)
				( attribute "ROT" "2"
					( Origin gFrontEnd )
				)
				( attribute "SEC" "1"
					( Origin gPackager )
				)
				( attribute "TOLERANCE" "20%"
					( Origin gFrontEnd )
				)
				( attribute "VALUE" "470UF"
					( Origin gFrontEnd )
				)
				( attribute "VER" "1"
					( Origin gFrontEnd )
				)
				( attribute "VOLTAGE" "2.5V"
					( Units "uVoltage" "V" 1.000000)
					( Origin gFrontEnd )
				)
				( attribute "XY" "(3375,2400)"
					( Origin gFrontEnd )
				)
				( attribute "CHIPS_PART_NAME" "CAPP"
					( Origin gPackager )
				)
				( attribute "CDS_PART_NAME" "CAPP_3018-470UF,2.5V,20%,ALUM,A"
					( Origin gPackager )
				)
				( objectStatus "C3N38" )
				( pin "a"
					( attribute "PN" "1"
						( Origin gPackager )
					)
					( objectStatus "C3N38.1" )
				)
				( pin "b"
					( attribute "PN" "2"
						( Origin gPackager )
					)
					( objectStatus "C3N38.2" )
				)
			)
			( gate "@baseboard_fab2_lib.baseboard_fab2(sch_1):page212_i17"
				( attribute "BOM_COST" "PROC_VRD_PVCCIO_CPU0"
					( Origin gFrontEnd )
				)
				( attribute "CDS_LIB" "mstr_discrete"
					( Origin gPackager )
				)
				( attribute "CDS_LOCATION" "C3N26"
					( Origin gPackager )
				)
				( attribute "CDS_SEC" "1"
					( Origin gPackager )
				)
				( attribute "LOCATION" "C3N26"
					( Origin gFrontEnd )
				)
				( attribute "MATERIAL" "ALUM"
					( Origin gFrontEnd )
				)
				( attribute "PACK_TYPE" "3018"
					( Origin gFrontEnd )
				)
				( attribute "PART_NUMBER" "699013-049"
					( Origin gFrontEnd )
				)
				( attribute "PHYS_PAGE" "212"
					( Origin gFrontEnd )
				)
				( attribute "ROOM" "PVCCIO_CPU0"
					( Origin gFrontEnd )
				)
				( attribute "ROT" "2"
					( Origin gFrontEnd )
				)
				( attribute "SEC" "1"
					( Origin gPackager )
				)
				( attribute "TOLERANCE" "20%"
					( Origin gFrontEnd )
				)
				( attribute "VALUE" "470UF"
					( Origin gFrontEnd )
				)
				( attribute "VER" "1"
					( Origin gFrontEnd )
				)
				( attribute "VOLTAGE" "2.5V"
					( Units "uVoltage" "V" 1.000000)
					( Origin gFrontEnd )
				)
				( attribute "XY" "(2950,2400)"
					( Origin gFrontEnd )
				)
				( attribute "CHIPS_PART_NAME" "CAPP"
					( Origin gPackager )
				)
				( attribute "CDS_PART_NAME" "CAPP_3018-470UF,2.5V,20%,ALUM,A"
					( Origin gPackager )
				)
				( objectStatus "C3N26" )
				( pin "a"
					( attribute "PN" "1"
						( Origin gPackager )
					)
					( objectStatus "C3N26.1" )
				)
				( pin "b"
					( attribute "PN" "2"
						( Origin gPackager )
					)
					( objectStatus "C3N26.2" )
				)
			)
			( gate "@baseboard_fab2_lib.baseboard_fab2(sch_1):page212_i18"
				( attribute "BOM_COST" "PROC_VRD_PVCCIO_CPU0"
					( Origin gFrontEnd )
				)
				( attribute "CDS_LIB" "mstr_discrete"
					( Origin gPackager )
				)
				( attribute "CDS_LOCATION" "C3N35"
					( Origin gPackager )
				)
				( attribute "CDS_SEC" "1"
					( Origin gPackager )
				)
				( attribute "LOCATION" "C3N35"
					( Origin gFrontEnd )
				)
				( attribute "MATERIAL" "ALUM"
					( Origin gFrontEnd )
				)
				( attribute "PACK_TYPE" "3018"
					( Origin gFrontEnd )
				)
				( attribute "PART_NUMBER" "699013-049"
					( Origin gFrontEnd )
				)
				( attribute "PHYS_PAGE" "212"
					( Origin gFrontEnd )
				)
				( attribute "ROOM" "PVCCIO_CPU0"
					( Origin gFrontEnd )
				)
				( attribute "ROT" "2"
					( Origin gFrontEnd )
				)
				( attribute "SEC" "1"
					( Origin gPackager )
				)
				( attribute "TOLERANCE" "20%"
					( Origin gFrontEnd )
				)
				( attribute "VALUE" "470UF"
					( Origin gFrontEnd )
				)
				( attribute "VER" "1"
					( Origin gFrontEnd )
				)
				( attribute "VOLTAGE" "2.5V"
					( Units "uVoltage" "V" 1.000000)
					( Origin gFrontEnd )
				)
				( attribute "XY" "(2550,2400)"
					( Origin gFrontEnd )
				)
				( attribute "CHIPS_PART_NAME" "CAPP"
					( Origin gPackager )
				)
				( attribute "CDS_PART_NAME" "CAPP_3018-470UF,2.5V,20%,ALUM,A"
					( Origin gPackager )
				)
				( objectStatus "C3N35" )
				( pin "a"
					( attribute "PN" "1"
						( Origin gPackager )
					)
					( objectStatus "C3N35.1" )
				)
				( pin "b"
					( attribute "PN" "2"
						( Origin gPackager )
					)
					( objectStatus "C3N35.2" )
				)
			)
			( gate "@baseboard_fab2_lib.baseboard_fab2(sch_1):page212_i23"
				( attribute "BOM_COST" "PROC_VRD_PVCCIO_CPU0"
					( Origin gFrontEnd )
				)
				( attribute "CDS_LIB" "dev_discrete"
					( Origin gPackager )
				)
				( attribute "CDS_LOCATION" "C7C6"
					( Origin gPackager )
				)
				( attribute "CDS_SEC" "1"
					( Origin gPackager )
				)
				( attribute "LOCATION" "C7C6"
					( Origin gFrontEnd )
				)
				( attribute "MATERIAL" "X6S"
					( Origin gFrontEnd )
				)
				( attribute "PACK_TYPE" "0603V"
					( Origin gFrontEnd )
				)
				( attribute "PART_NUMBER" "E15431-004"
					( Origin gFrontEnd )
				)
				( attribute "PHYS_PAGE" "212"
					( Origin gFrontEnd )
				)
				( attribute "ROOM" "PVCCIO_CPU0"
					( Origin gFrontEnd )
				)
				( attribute "ROT" "0"
					( Origin gFrontEnd )
				)
				( attribute "SEC" "1"
					( Origin gFrontEnd )
				)
				( attribute "SEC_TYPE" "0603V"
					( Origin gFrontEnd )
				)
				( attribute "TOLERANCE" "20%"
					( Origin gFrontEnd )
				)
				( attribute "VALUE" "22.0UF"
					( Origin gFrontEnd )
				)
				( attribute "VER" "1"
					( Origin gFrontEnd )
				)
				( attribute "VOLTAGE" "4V"
					( Units "uVoltage" "V" 1.000000)
					( Origin gFrontEnd )
				)
				( attribute "XY" "(2925,3275)"
					( Origin gFrontEnd )
				)
				( attribute "CHIPS_PART_NAME" "CAP_A"
					( Origin gPackager )
				)
				( attribute "CDS_PART_NAME" "CAP_A_0603V-22.0UF,4V,20%,X6S,A"
					( Origin gPackager )
				)
				( objectStatus "C7C6" )
				( pin "a"
					( attribute "PN" "1"
						( Origin gPackager )
					)
					( objectStatus "C7C6.1" )
				)
				( pin "b"
					( attribute "PN" "2"
						( Origin gPackager )
					)
					( objectStatus "C7C6.2" )
				)
			)
			( gate "@baseboard_fab2_lib.baseboard_fab2(sch_1):page212_i25"
				( attribute "CDS_LIB" "mstr_discrete"
					( Origin gPackager )
				)
				( attribute "CDS_LOCATION" "L7C2"
					( Origin gPackager )
				)
				( attribute "CDS_SEC" "1"
					( Origin gPackager )
				)
				( attribute "LOCATION" "L7C2"
					( Origin gFrontEnd )
				)
				( attribute "MATERIAL" "IND"
					( Origin gFrontEnd )
				)
				( attribute "PACK_TYPE" "SM"
					( Origin gFrontEnd )
				)
				( attribute "PART_NUMBER" "D92183-021"
					( Origin gFrontEnd )
				)
				( attribute "PHYS_PAGE" "212"
					( Origin gFrontEnd )
				)
				( attribute "ROOM" "PVCCIO_CPU0"
					( Origin gFrontEnd )
				)
				( attribute "ROT" "0"
					( Origin gFrontEnd )
				)
				( attribute "SEC" "1"
					( Origin gPackager )
				)
				( attribute "VALUE" "150NH"
					( Origin gFrontEnd )
				)
				( attribute "VER" "1"
					( Origin gFrontEnd )
				)
				( attribute "XY" "(2475,3475)"
					( Origin gFrontEnd )
				)
				( attribute "CHIPS_PART_NAME" "INDUCTOR"
					( Origin gPackager )
				)
				( attribute "CDS_PART_NAME" "INDUCTOR_SM-150NH,IND,D92183-0A"
					( Origin gPackager )
				)
				( objectStatus "L7C2" )
				( pin "ina"
					( attribute "PN" "1"
						( Origin gPackager )
					)
					( objectStatus "L7C2.1" )
				)
				( pin "inb"
					( attribute "PN" "2"
						( Origin gPackager )
					)
					( objectStatus "L7C2.2" )
				)
			)
			( gate "@baseboard_fab2_lib.baseboard_fab2(sch_1):page212_i32"
				( attribute "CDS_LIB" "mstr_discrete"
					( Origin gPackager )
				)
				( attribute "CDS_LOCATION" "R3N7"
					( Origin gPackager )
				)
				( attribute "CDS_SEC" "1"
					( Origin gPackager )
				)
				( attribute "LOCATION" "R3N7"
					( Origin gFrontEnd )
				)
				( attribute "MATERIAL" "CHIP"
					( Origin gFrontEnd )
				)
				( attribute "PACK_TYPE" "0402"
					( Origin gFrontEnd )
				)
				( attribute "PART_NUMBER" "G21796-090"
					( Origin gFrontEnd )
				)
				( attribute "PHYS_PAGE" "212"
					( Origin gFrontEnd )
				)
				( attribute "ROOM" "PVCCIO_CPU0"
					( Origin gFrontEnd )
				)
				( attribute "ROT" "0"
					( Origin gFrontEnd )
				)
				( attribute "SEC" "1"
					( Origin gFrontEnd )
				)
				( attribute "SEC_TYPE" "0402"
					( Origin gFrontEnd )
				)
				( attribute "TOLERANCE" "1%"
					( Origin gFrontEnd )
				)
				( attribute "VALUE" "1.0"
					( Origin gFrontEnd )
				)
				( attribute "VER" "1"
					( Origin gFrontEnd )
				)
				( attribute "WATTAGE" "1/16W"
					( Origin gFrontEnd )
				)
				( attribute "XY" "(-1725,4575)"
					( Origin gFrontEnd )
				)
				( attribute "CHIPS_PART_NAME" "RES"
					( Origin gPackager )
				)
				( attribute "CDS_PART_NAME" "RES_0402-1.0,1%,1/16W,CHIP,G21A"
					( Origin gPackager )
				)
				( objectStatus "R3N7" )
				( pin "a"
					( attribute "PN" "1"
						( Origin gPackager )
					)
					( objectStatus "R3N7.1" )
				)
				( pin "b"
					( attribute "PN" "2"
						( Origin gPackager )
					)
					( objectStatus "R3N7.2" )
				)
			)
			( gate "@baseboard_fab2_lib.baseboard_fab2(sch_1):page212_i33"
				( attribute "CDS_LIB" "mstr_discrete"
					( Origin gPackager )
				)
				( attribute "CDS_LOCATION" "C7C18"
					( Origin gPackager )
				)
				( attribute "CDS_SEC" "1"
					( Origin gPackager )
				)
				( attribute "LOCATION" "C7C18"
					( Origin gFrontEnd )
				)
				( attribute "MATERIAL" "X7R"
					( Origin gFrontEnd )
				)
				( attribute "PACK_TYPE" "0402"
					( Origin gFrontEnd )
				)
				( attribute "PART_NUMBER" "A36096-155"
					( Origin gFrontEnd )
				)
				( attribute "PHYS_PAGE" "212"
					( Origin gFrontEnd )
				)
				( attribute "ROOM" "PVCCIO_CPU0"
					( Origin gFrontEnd )
				)
				( attribute "ROT" "0"
					( Origin gFrontEnd )
				)
				( attribute "SEC" "1"
					( Origin gFrontEnd )
				)
				( attribute "SEC_TYPE" "0402"
					( Origin gFrontEnd )
				)
				( attribute "TOLERANCE" "10%"
					( Origin gFrontEnd )
				)
				( attribute "VALUE" "0.22UF"
					( Origin gFrontEnd )
				)
				( attribute "VER" "1"
					( Origin gFrontEnd )
				)
				( attribute "VOLTAGE" "16V"
					( Units "uVoltage" "V" 1.000000)
					( Origin gFrontEnd )
				)
				( attribute "XY" "(-1275,4050)"
					( Origin gFrontEnd )
				)
				( attribute "CHIPS_PART_NAME" "CAP"
					( Origin gPackager )
				)
				( attribute "CDS_PART_NAME" "CAP_0402-0.22UF,16V,10%,X7R,A3A"
					( Origin gPackager )
				)
				( objectStatus "C7C18" )
				( pin "a"
					( attribute "PN" "1"
						( Origin gPackager )
					)
					( objectStatus "C7C18.1" )
				)
				( pin "b"
					( attribute "PN" "2"
						( Origin gPackager )
					)
					( objectStatus "C7C18.2" )
				)
			)
			( gate "@baseboard_fab2_lib.baseboard_fab2(sch_1):page212_i34"
				( attribute "CDS_LIB" "dev_discrete"
					( Origin gPackager )
				)
				( attribute "CDS_LOCATION" "C7C20"
					( Origin gPackager )
				)
				( attribute "CDS_SEC" "1"
					( Origin gPackager )
				)
				( attribute "LOCATION" "C7C20"
					( Origin gFrontEnd )
				)
				( attribute "MATERIAL" "X6S"
					( Origin gFrontEnd )
				)
				( attribute "PACK_TYPE" "0402V"
					( Origin gFrontEnd )
				)
				( attribute "PART_NUMBER" "D97712-004"
					( Origin gFrontEnd )
				)
				( attribute "PHYS_PAGE" "212"
					( Origin gFrontEnd )
				)
				( attribute "ROOM" "PVCCIO_CPU0"
					( Origin gFrontEnd )
				)
				( attribute "ROT" "2"
					( Origin gFrontEnd )
				)
				( attribute "SEC" "1"
					( Origin gFrontEnd )
				)
				( attribute "SEC_TYPE" "0402V"
					( Origin gFrontEnd )
				)
				( attribute "TOLERANCE" "10%"
					( Origin gFrontEnd )
				)
				( attribute "VALUE" "1.0UF"
					( Origin gFrontEnd )
				)
				( attribute "VER" "1"
					( Origin gFrontEnd )
				)
				( attribute "VOLTAGE" "6.3V"
					( Units "uVoltage" "V" 1.000000)
					( Origin gFrontEnd )
				)
				( attribute "XY" "(-1425,4050)"
					( Origin gFrontEnd )
				)
				( attribute "CHIPS_PART_NAME" "CAP_A"
					( Origin gPackager )
				)
				( attribute "CDS_PART_NAME" "CAP_A_0402V-1.0UF,6.3V,10%,X6SA"
					( Origin gPackager )
				)
				( objectStatus "C7C20" )
				( pin "a"
					( attribute "PN" "1"
						( Origin gPackager )
					)
					( objectStatus "C7C20.1" )
				)
				( pin "b"
					( attribute "PN" "2"
						( Origin gPackager )
					)
					( objectStatus "C7C20.2" )
				)
			)
			( gate "@baseboard_fab2_lib.baseboard_fab2(sch_1):page212_i36"
				( attribute "CDS_LIB" "mstr_discrete"
					( Origin gPackager )
				)
				( attribute "CDS_LOCATION" "C7C17"
					( Origin gPackager )
				)
				( attribute "CDS_SEC" "1"
					( Origin gPackager )
				)
				( attribute "LOCATION" "C7C17"
					( Origin gFrontEnd )
				)
				( attribute "MATERIAL" "X6S"
					( Origin gFrontEnd )
				)
				( attribute "PACK_TYPE" "0402"
					( Origin gFrontEnd )
				)
				( attribute "PART_NUMBER" "D97712-011"
					( Origin gFrontEnd )
				)
				( attribute "PHYS_PAGE" "212"
					( Origin gFrontEnd )
				)
				( attribute "ROOM" "PVCCIO_CPU0"
					( Origin gFrontEnd )
				)
				( attribute "ROT" "0"
					( Origin gFrontEnd )
				)
				( attribute "SEC" "1"
					( Origin gFrontEnd )
				)
				( attribute "SEC_TYPE" "0402"
					( Origin gFrontEnd )
				)
				( attribute "TOLERANCE" "10%"
					( Origin gFrontEnd )
				)
				( attribute "VALUE" "1.0UF"
					( Origin gFrontEnd )
				)
				( attribute "VER" "1"
					( Origin gFrontEnd )
				)
				( attribute "VOLTAGE" "16V"
					( Units "uVoltage" "V" 1.000000)
					( Origin gFrontEnd )
				)
				( attribute "XY" "(-1975,4000)"
					( Origin gFrontEnd )
				)
				( attribute "CHIPS_PART_NAME" "CAP"
					( Origin gPackager )
				)
				( attribute "CDS_PART_NAME" "CAP_0402-1.0UF,16V,10%,X6S,D97A"
					( Origin gPackager )
				)
				( objectStatus "C7C17" )
				( pin "a"
					( attribute "PN" "1"
						( Origin gPackager )
					)
					( objectStatus "C7C17.1" )
				)
				( pin "b"
					( attribute "PN" "2"
						( Origin gPackager )
					)
					( objectStatus "C7C17.2" )
				)
			)
			( gate "@baseboard_fab2_lib.baseboard_fab2(sch_1):page212_i37"
				( attribute "CDS_LIB" "mstr_discrete"
					( Origin gPackager )
				)
				( attribute "CDS_LOCATION" "C7C14"
					( Origin gPackager )
				)
				( attribute "CDS_SEC" "1"
					( Origin gPackager )
				)
				( attribute "LOCATION" "C7C14"
					( Origin gFrontEnd )
				)
				( attribute "MATERIAL" "X7R"
					( Origin gFrontEnd )
				)
				( attribute "PACK_TYPE" "0402"
					( Origin gFrontEnd )
				)
				( attribute "PART_NUMBER" "A36096-104"
					( Origin gFrontEnd )
				)
				( attribute "PHYS_PAGE" "212"
					( Origin gFrontEnd )
				)
				( attribute "ROOM" "PVCCIO_CPU0"
					( Origin gFrontEnd )
				)
				( attribute "ROT" "2"
					( Origin gFrontEnd )
				)
				( attribute "SEC" "1"
					( Origin gFrontEnd )
				)
				( attribute "SEC_TYPE" "0402"
					( Origin gFrontEnd )
				)
				( attribute "SPOF" "TRUE"
					( Origin gFrontEnd )
				)
				( attribute "TOLERANCE" "10%"
					( Origin gFrontEnd )
				)
				( attribute "VALUE" "0.220UF"
					( Origin gFrontEnd )
				)
				( attribute "VER" "1"
					( Origin gFrontEnd )
				)
				( attribute "VOLTAGE" "16V"
					( Units "uVoltage" "V" 1.000000)
					( Origin gFrontEnd )
				)
				( attribute "XY" "(-2025,3425)"
					( Origin gFrontEnd )
				)
				( attribute "CHIPS_PART_NAME" "CAP"
					( Origin gPackager )
				)
				( attribute "CDS_PART_NAME" "CAP_0402-0.220UF,16V,10%,X7R,AA"
					( Origin gPackager )
				)
				( objectStatus "C7C14" )
				( pin "a"
					( attribute "PN" "1"
						( Origin gPackager )
					)
					( objectStatus "C7C14.1" )
				)
				( pin "b"
					( attribute "PN" "2"
						( Origin gPackager )
					)
					( objectStatus "C7C14.2" )
				)
			)
			( gate "@baseboard_fab2_lib.baseboard_fab2(sch_1):page212_i38"
				( attribute "CDS_LIB" "dev_discrete"
					( Origin gPackager )
				)
				( attribute "CDS_LOCATION" "C7C11"
					( Origin gPackager )
				)
				( attribute "CDS_SEC" "1"
					( Origin gPackager )
				)
				( attribute "LOCATION" "C7C11"
					( Origin gFrontEnd )
				)
				( attribute "MATERIAL" "X7R"
					( Origin gFrontEnd )
				)
				( attribute "PACK_TYPE" "0402V"
					( Origin gFrontEnd )
				)
				( attribute "PART_NUMBER" "A36096-030"
					( Origin gFrontEnd )
				)
				( attribute "PHYS_PAGE" "212"
					( Origin gFrontEnd )
				)
				( attribute "ROOM" "PVCCIO_CPU0"
					( Origin gFrontEnd )
				)
				( attribute "ROT" "0"
					( Origin gFrontEnd )
				)
				( attribute "SEC" "1"
					( Origin gFrontEnd )
				)
				( attribute "SEC_TYPE" "0402V"
					( Origin gFrontEnd )
				)
				( attribute "TOLERANCE" "10%"
					( Origin gFrontEnd )
				)
				( attribute "VALUE" "0.1UF"
					( Origin gFrontEnd )
				)
				( attribute "VER" "1"
					( Origin gFrontEnd )
				)
				( attribute "VOLTAGE" "16V"
					( Units "uVoltage" "V" 1.000000)
					( Origin gFrontEnd )
				)
				( attribute "XY" "(-2200,4000)"
					( Origin gFrontEnd )
				)
				( attribute "CHIPS_PART_NAME" "CAP_A"
					( Origin gPackager )
				)
				( attribute "CDS_PART_NAME" "CAP_A_0402V-0.1UF,16V,10%,X7R,A"
					( Origin gPackager )
				)
				( objectStatus "C7C11" )
				( pin "a"
					( attribute "PN" "1"
						( Origin gPackager )
					)
					( objectStatus "C7C11.1" )
				)
				( pin "b"
					( attribute "PN" "2"
						( Origin gPackager )
					)
					( objectStatus "C7C11.2" )
				)
			)
			( gate "@baseboard_fab2_lib.baseboard_fab2(sch_1):page212_i39"
				( attribute "CDS_LIB" "mstr_discrete"
					( Origin gPackager )
				)
				( attribute "CDS_LOCATION" "C7C12"
					( Origin gPackager )
				)
				( attribute "CDS_SEC" "1"
					( Origin gPackager )
				)
				( attribute "LOCATION" "C7C12"
					( Origin gFrontEnd )
				)
				( attribute "MATERIAL" "X6S"
					( Origin gFrontEnd )
				)
				( attribute "PACK_TYPE" "0402"
					( Origin gFrontEnd )
				)
				( attribute "PART_NUMBER" "D97712-011"
					( Origin gFrontEnd )
				)
				( attribute "PHYS_PAGE" "212"
					( Origin gFrontEnd )
				)
				( attribute "ROOM" "PVCCIO_CPU0"
					( Origin gFrontEnd )
				)
				( attribute "ROT" "0"
					( Origin gFrontEnd )
				)
				( attribute "SEC" "1"
					( Origin gFrontEnd )
				)
				( attribute "SEC_TYPE" "0402"
					( Origin gFrontEnd )
				)
				( attribute "TOLERANCE" "10%"
					( Origin gFrontEnd )
				)
				( attribute "VALUE" "1.0UF"
					( Origin gFrontEnd )
				)
				( attribute "VER" "1"
					( Origin gFrontEnd )
				)
				( attribute "VOLTAGE" "16V"
					( Units "uVoltage" "V" 1.000000)
					( Origin gFrontEnd )
				)
				( attribute "XY" "(-2450,4025)"
					( Origin gFrontEnd )
				)
				( attribute "CHIPS_PART_NAME" "CAP"
					( Origin gPackager )
				)
				( attribute "CDS_PART_NAME" "CAP_0402-1.0UF,16V,10%,X6S,D97A"
					( Origin gPackager )
				)
				( objectStatus "C7C12" )
				( pin "a"
					( attribute "PN" "1"
						( Origin gPackager )
					)
					( objectStatus "C7C12.1" )
				)
				( pin "b"
					( attribute "PN" "2"
						( Origin gPackager )
					)
					( objectStatus "C7C12.2" )
				)
			)
			( gate "@baseboard_fab2_lib.baseboard_fab2(sch_1):page212_i40"
				( attribute "CDS_LIB" "mstr_discrete"
					( Origin gPackager )
				)
				( attribute "CDS_LOCATION" "C3N36"
					( Origin gPackager )
				)
				( attribute "CDS_SEC" "1"
					( Origin gPackager )
				)
				( attribute "LOCATION" "C3N36"
					( Origin gFrontEnd )
				)
				( attribute "MATERIAL" "X6S"
					( Origin gFrontEnd )
				)
				( attribute "PACK_TYPE" "0805"
					( Origin gFrontEnd )
				)
				( attribute "PART_NUMBER" "C95333-007"
					( Origin gFrontEnd )
				)
				( attribute "PHYS_PAGE" "212"
					( Origin gFrontEnd )
				)
				( attribute "ROOM" "PVCCIO_CPU0"
					( Origin gFrontEnd )
				)
				( attribute "ROT" "0"
					( Origin gFrontEnd )
				)
				( attribute "SEC" "1"
					( Origin gFrontEnd )
				)
				( attribute "SEC_TYPE" "0805"
					( Origin gFrontEnd )
				)
				( attribute "TOLERANCE" "10%"
					( Origin gFrontEnd )
				)
				( attribute "VALUE" "10UF"
					( Origin gFrontEnd )
				)
				( attribute "VER" "1"
					( Origin gFrontEnd )
				)
				( attribute "VOLTAGE" "16V"
					( Units "uVoltage" "V" 1.000000)
					( Origin gFrontEnd )
				)
				( attribute "XY" "(-2675,4000)"
					( Origin gFrontEnd )
				)
				( attribute "CHIPS_PART_NAME" "CAP"
					( Origin gPackager )
				)
				( attribute "CDS_PART_NAME" "CAP_0805-10UF,16V,10%,X6S,C953A"
					( Origin gPackager )
				)
				( objectStatus "C3N36" )
				( pin "a"
					( attribute "PN" "1"
						( Origin gPackager )
					)
					( objectStatus "C3N36.1" )
				)
				( pin "b"
					( attribute "PN" "2"
						( Origin gPackager )
					)
					( objectStatus "C3N36.2" )
				)
			)
			( gate "@baseboard_fab2_lib.baseboard_fab2(sch_1):page212_i41"
				( attribute "CDS_LIB" "mstr_discrete"
					( Origin gPackager )
				)
				( attribute "CDS_LOCATION" "C3N33"
					( Origin gPackager )
				)
				( attribute "CDS_SEC" "1"
					( Origin gPackager )
				)
				( attribute "LOCATION" "C3N33"
					( Origin gFrontEnd )
				)
				( attribute "MATERIAL" "X6S"
					( Origin gFrontEnd )
				)
				( attribute "PACK_TYPE" "0805"
					( Origin gFrontEnd )
				)
				( attribute "PART_NUMBER" "C95333-007"
					( Origin gFrontEnd )
				)
				( attribute "PHYS_PAGE" "212"
					( Origin gFrontEnd )
				)
				( attribute "ROOM" "PVCCIO_CPU0"
					( Origin gFrontEnd )
				)
				( attribute "ROT" "0"
					( Origin gFrontEnd )
				)
				( attribute "SEC" "1"
					( Origin gFrontEnd )
				)
				( attribute "SEC_TYPE" "0805"
					( Origin gFrontEnd )
				)
				( attribute "TOLERANCE" "10%"
					( Origin gFrontEnd )
				)
				( attribute "VALUE" "10UF"
					( Origin gFrontEnd )
				)
				( attribute "VER" "1"
					( Origin gFrontEnd )
				)
				( attribute "VOLTAGE" "16V"
					( Units "uVoltage" "V" 1.000000)
					( Origin gFrontEnd )
				)
				( attribute "XY" "(-2900,4050)"
					( Origin gFrontEnd )
				)
				( attribute "CHIPS_PART_NAME" "CAP"
					( Origin gPackager )
				)
				( attribute "CDS_PART_NAME" "CAP_0805-10UF,16V,10%,X6S,C953A"
					( Origin gPackager )
				)
				( objectStatus "C3N33" )
				( pin "a"
					( attribute "PN" "1"
						( Origin gPackager )
					)
					( objectStatus "C3N33.1" )
				)
				( pin "b"
					( attribute "PN" "2"
						( Origin gPackager )
					)
					( objectStatus "C3N33.2" )
				)
			)
			( gate "@baseboard_fab2_lib.baseboard_fab2(sch_1):page212_i43"
				( attribute "CDS_LIB" "mstr_discrete"
					( Origin gPackager )
				)
				( attribute "CDS_LOCATION" "C3N34"
					( Origin gPackager )
				)
				( attribute "CDS_SEC" "1"
					( Origin gPackager )
				)
				( attribute "LOCATION" "C3N34"
					( Origin gFrontEnd )
				)
				( attribute "MATERIAL" "X6S"
					( Origin gFrontEnd )
				)
				( attribute "PACK_TYPE" "0805"
					( Origin gFrontEnd )
				)
				( attribute "PART_NUMBER" "C95333-007"
					( Origin gFrontEnd )
				)
				( attribute "PHYS_PAGE" "212"
					( Origin gFrontEnd )
				)
				( attribute "ROOM" "PVCCIO_CPU0"
					( Origin gFrontEnd )
				)
				( attribute "ROT" "0"
					( Origin gFrontEnd )
				)
				( attribute "SEC" "1"
					( Origin gFrontEnd )
				)
				( attribute "SEC_TYPE" "0805"
					( Origin gFrontEnd )
				)
				( attribute "TOLERANCE" "10%"
					( Origin gFrontEnd )
				)
				( attribute "VALUE" "10UF"
					( Origin gFrontEnd )
				)
				( attribute "VER" "1"
					( Origin gFrontEnd )
				)
				( attribute "VOLTAGE" "16V"
					( Units "uVoltage" "V" 1.000000)
					( Origin gFrontEnd )
				)
				( attribute "XY" "(-3150,4050)"
					( Origin gFrontEnd )
				)
				( attribute "CHIPS_PART_NAME" "CAP"
					( Origin gPackager )
				)
				( attribute "CDS_PART_NAME" "CAP_0805-10UF,16V,10%,X6S,C953A"
					( Origin gPackager )
				)
				( objectStatus "C3N34" )
				( pin "a"
					( attribute "PN" "1"
						( Origin gPackager )
					)
					( objectStatus "C3N34.1" )
				)
				( pin "b"
					( attribute "PN" "2"
						( Origin gPackager )
					)
					( objectStatus "C3N34.2" )
				)
			)
			( gate "@baseboard_fab2_lib.baseboard_fab2(sch_1):page212_i51"
				( attribute "BOM_COST" "PROC_VRD_VCCIO_CPU1"
					( Origin gFrontEnd )
				)
				( attribute "CDS_LIB" "mstr_discrete"
					( Origin gPackager )
				)
				( attribute "CDS_LOCATION" "C7C8"
					( Origin gPackager )
				)
				( attribute "LOCATION" "C7C8"
					( Origin gFrontEnd )
				)
				( attribute "MATERIAL" "X5R"
					( Origin gFrontEnd )
				)
				( attribute "PACK_TYPE" "1210"
					( Origin gFrontEnd )
				)
				( attribute "PART_NUMBER" "644066-127"
					( Origin gFrontEnd )
				)
				( attribute "PHYS_PAGE" "212"
					( Origin gFrontEnd )
				)
				( attribute "ROOM" "PVCCIO_CPU1"
					( Origin gFrontEnd )
				)
				( attribute "ROT" "2"
					( Origin gFrontEnd )
				)
				( attribute "SEC" "1"
					( Origin gFrontEnd )
				)
				( attribute "SEC_TYPE" "1210"
					( Origin gFrontEnd )
				)
				( attribute "TOLERANCE" "20%"
					( Origin gFrontEnd )
				)
				( attribute "VALUE" "100UF"
					( Origin gFrontEnd )
				)
				( attribute "VER" "1"
					( Origin gFrontEnd )
				)
				( attribute "VOLTAGE" "16V"
					( Units "uVoltage" "V" 1.000000)
					( Origin gFrontEnd )
				)
				( attribute "XY" "(1400,2225)"
					( Origin gFrontEnd )
				)
				( attribute "CHIPS_PART_NAME" "CAP"
					( Origin gPackager )
				)
				( attribute "CDS_PART_NAME" "CAP_1210-100UF,16V,20%,X5R,644A"
					( Origin gPackager )
				)
				( attribute "CDS_SEC" "1"
					( Origin gPackager )
				)
				( objectStatus "C7C8" )
				( pin "a"
					( attribute "PN" "1"
						( Origin gPackager )
					)
					( objectStatus "C7C8.1" )
				)
				( pin "b"
					( attribute "PN" "2"
						( Origin gPackager )
					)
					( objectStatus "C7C8.2" )
				)
			)
			( gate "@baseboard_fab2_lib.baseboard_fab2(sch_1):page212_i54"
				( attribute "BOM_COST" "PROC_VRD_VCCIO_CPU1"
					( Origin gFrontEnd )
				)
				( attribute "CDS_LIB" "mstr_discrete"
					( Origin gPackager )
				)
				( attribute "CDS_LOCATION" "C7C7"
					( Origin gPackager )
				)
				( attribute "LOCATION" "C7C7"
					( Origin gFrontEnd )
				)
				( attribute "MATERIAL" "X5R"
					( Origin gFrontEnd )
				)
				( attribute "PACK_TYPE" "1210"
					( Origin gFrontEnd )
				)
				( attribute "PART_NUMBER" "644066-127"
					( Origin gFrontEnd )
				)
				( attribute "PHYS_PAGE" "212"
					( Origin gFrontEnd )
				)
				( attribute "ROOM" "PVCCIO_CPU1"
					( Origin gFrontEnd )
				)
				( attribute "ROT" "0"
					( Origin gFrontEnd )
				)
				( attribute "SEC" "1"
					( Origin gFrontEnd )
				)
				( attribute "SEC_TYPE" "1210"
					( Origin gFrontEnd )
				)
				( attribute "TOLERANCE" "20%"
					( Origin gFrontEnd )
				)
				( attribute "VALUE" "100UF"
					( Origin gFrontEnd )
				)
				( attribute "VER" "1"
					( Origin gFrontEnd )
				)
				( attribute "VOLTAGE" "16V"
					( Units "uVoltage" "V" 1.000000)
					( Origin gFrontEnd )
				)
				( attribute "XY" "(825,2200)"
					( Origin gFrontEnd )
				)
				( attribute "CHIPS_PART_NAME" "CAP"
					( Origin gPackager )
				)
				( attribute "CDS_PART_NAME" "CAP_1210-100UF,16V,20%,X5R,644A"
					( Origin gPackager )
				)
				( attribute "CDS_SEC" "1"
					( Origin gPackager )
				)
				( objectStatus "C7C7" )
				( pin "a"
					( attribute "PN" "1"
						( Origin gPackager )
					)
					( objectStatus "C7C7.1" )
				)
				( pin "b"
					( attribute "PN" "2"
						( Origin gPackager )
					)
					( objectStatus "C7C7.2" )
				)
			)
			( gate "@baseboard_fab2_lib.baseboard_fab2(sch_1):page212_i56"
				( attribute "BOM_COST" "PROC_VRD_VCCIO_CPU1"
					( Origin gFrontEnd )
				)
				( attribute "CDS_LIB" "mstr_discrete"
					( Origin gPackager )
				)
				( attribute "CDS_LOCATION" "L7C1"
					( Origin gPackager )
				)
				( attribute "LOCATION" "L7C1"
					( Origin gFrontEnd )
				)
				( attribute "MATERIAL" "IND"
					( Origin gFrontEnd )
				)
				( attribute "PACK_TYPE" "SM"
					( Origin gFrontEnd )
				)
				( attribute "PART_NUMBER" "D92183-020"
					( Origin gFrontEnd )
				)
				( attribute "PHYS_PAGE" "212"
					( Origin gFrontEnd )
				)
				( attribute "ROOM" "PVCCIO_CPU1"
					( Origin gFrontEnd )
				)
				( attribute "ROT" "0"
					( Origin gFrontEnd )
				)
				( attribute "SEC" "1"
					( Origin gFrontEnd )
				)
				( attribute "SEC_TYPE" "SM"
					( Origin gFrontEnd )
				)
				( attribute "VALUE" "100NH"
					( Origin gFrontEnd )
				)
				( attribute "VER" "1"
					( Origin gFrontEnd )
				)
				( attribute "XY" "(325,2450)"
					( Origin gFrontEnd )
				)
				( attribute "CHIPS_PART_NAME" "INDUCTOR"
					( Origin gPackager )
				)
				( attribute "CDS_PART_NAME" "INDUCTOR_SM-100NH,IND,D92183-0B"
					( Origin gPackager )
				)
				( attribute "CDS_SEC" "1"
					( Origin gPackager )
				)
				( objectStatus "L7C1" )
				( pin "ina"
					( attribute "PN" "1"
						( Origin gPackager )
					)
					( objectStatus "L7C1.1" )
				)
				( pin "inb"
					( attribute "PN" "2"
						( Origin gPackager )
					)
					( objectStatus "L7C1.2" )
				)
			)
			( gate "@baseboard_fab2_lib.baseboard_fab2(sch_1):page212_i60"
				( attribute "BOM_COST" "PROC_VRD_PVCCIO_CPU0"
					( Origin gFrontEnd )
				)
				( attribute "CDS_LIB" "dev_discrete"
					( Origin gPackager )
				)
				( attribute "CDS_LOCATION" "C3P1"
					( Origin gPackager )
				)
				( attribute "CDS_SEC" "1"
					( Origin gPackager )
				)
				( attribute "LOCATION" "C3P1"
					( Origin gFrontEnd )
				)
				( attribute "MATERIAL" "EMPTY"
					( Origin gFrontEnd )
				)
				( attribute "PACK_TYPE" "0402V"
					( Origin gFrontEnd )
				)
				( attribute "PART_NUMBER" "A36096-030"
					( Origin gFrontEnd )
				)
				( attribute "PHYS_PAGE" "212"
					( Origin gFrontEnd )
				)
				( attribute "ROOM" "PVCCIO_CPU0"
					( Origin gFrontEnd )
				)
				( attribute "ROT" "0"
					( Origin gFrontEnd )
				)
				( attribute "SEC" "1"
					( Origin gPackager )
				)
				( attribute "TOLERANCE" "10%"
					( Origin gFrontEnd )
				)
				( attribute "VALUE" "0.1UF"
					( Origin gFrontEnd )
				)
				( attribute "VER" "1"
					( Origin gFrontEnd )
				)
				( attribute "VOLTAGE" "16V"
					( Units "uVoltage" "V" 1.000000)
					( Origin gFrontEnd )
				)
				( attribute "XY" "(-1925,1675)"
					( Origin gFrontEnd )
				)
				( attribute "CHIPS_PART_NAME" "CAP_A"
					( Origin gPackager )
				)
				( attribute "CDS_PART_NAME" "CAP_A_0402V-0.1UF,16V,10%,EMPTA"
					( Origin gPackager )
				)
				( objectStatus "C3P1" )
				( pin "a"
					( attribute "PN" "1"
						( Origin gPackager )
					)
					( objectStatus "C3P1.1" )
				)
				( pin "b"
					( attribute "PN" "2"
						( Origin gPackager )
					)
					( objectStatus "C3P1.2" )
				)
			)
			( gate "@baseboard_fab2_lib.baseboard_fab2(sch_1):page212_i68"
				( attribute "BOM_COST" "PROC_VRD_PVCCIO_CPU0"
					( Origin gFrontEnd )
				)
				( attribute "CDS_LIB" "mstr_discrete"
					( Origin gPackager )
				)
				( attribute "CDS_LOCATION" "R3N20"
					( Origin gPackager )
				)
				( attribute "CDS_SEC" "1"
					( Origin gPackager )
				)
				( attribute "LOCATION" "R3N20"
					( Origin gFrontEnd )
				)
				( attribute "MATERIAL" "CHIP"
					( Origin gFrontEnd )
				)
				( attribute "PACK_TYPE" "0402"
					( Origin gFrontEnd )
				)
				( attribute "PART_NUMBER" "G21796-017"
					( Origin gFrontEnd )
				)
				( attribute "PHYS_PAGE" "212"
					( Origin gFrontEnd )
				)
				( attribute "ROOM" "PVCCIO_CPU0"
					( Origin gFrontEnd )
				)
				( attribute "ROT" "0"
					( Origin gFrontEnd )
				)
				( attribute "SEC" "1"
					( Origin gPackager )
				)
				( attribute "TOLERANCE" "1%"
					( Origin gFrontEnd )
				)
				( attribute "VALUE" "100.0"
					( Origin gFrontEnd )
				)
				( attribute "VER" "1"
					( Origin gFrontEnd )
				)
				( attribute "WATTAGE" "1/16W"
					( Origin gFrontEnd )
				)
				( attribute "XY" "(-725,1150)"
					( Origin gFrontEnd )
				)
				( attribute "CHIPS_PART_NAME" "RES"
					( Origin gPackager )
				)
				( attribute "CDS_PART_NAME" "RES_0402-100.0,1%,1/16W,CHIP,GA"
					( Origin gPackager )
				)
				( objectStatus "R3N20" )
				( pin "a"
					( attribute "PN" "1"
						( Origin gPackager )
					)
					( objectStatus "R3N20.1" )
				)
				( pin "b"
					( attribute "PN" "2"
						( Origin gPackager )
					)
					( objectStatus "R3N20.2" )
				)
			)
			( gate "@baseboard_fab2_lib.baseboard_fab2(sch_1):page212_i74"
				( attribute "BOM_COST" "PROC_VRD_PVCCIO_CPU0"
					( Origin gFrontEnd )
				)
				( attribute "CDS_LIB" "mstr_discrete"
					( Origin gPackager )
				)
				( attribute "CDS_LOCATION" "R3N21"
					( Origin gPackager )
				)
				( attribute "CDS_SEC" "1"
					( Origin gPackager )
				)
				( attribute "LOCATION" "R3N21"
					( Origin gFrontEnd )
				)
				( attribute "MATERIAL" "CHIP"
					( Origin gFrontEnd )
				)
				( attribute "PACK_TYPE" "0402"
					( Origin gFrontEnd )
				)
				( attribute "PART_NUMBER" "G21796-017"
					( Origin gFrontEnd )
				)
				( attribute "PHYS_PAGE" "212"
					( Origin gFrontEnd )
				)
				( attribute "ROOM" "PVCCIO_CPU0"
					( Origin gFrontEnd )
				)
				( attribute "ROT" "0"
					( Origin gFrontEnd )
				)
				( attribute "SEC" "1"
					( Origin gPackager )
				)
				( attribute "TOLERANCE" "1%"
					( Origin gFrontEnd )
				)
				( attribute "VALUE" "100.0"
					( Origin gFrontEnd )
				)
				( attribute "VER" "1"
					( Origin gFrontEnd )
				)
				( attribute "WATTAGE" "1/16W"
					( Origin gFrontEnd )
				)
				( attribute "XY" "(-725,2325)"
					( Origin gFrontEnd )
				)
				( attribute "CHIPS_PART_NAME" "RES"
					( Origin gPackager )
				)
				( attribute "CDS_PART_NAME" "RES_0402-100.0,1%,1/16W,CHIP,GA"
					( Origin gPackager )
				)
				( objectStatus "R3N21" )
				( pin "a"
					( attribute "PN" "1"
						( Origin gPackager )
					)
					( objectStatus "R3N21.1" )
				)
				( pin "b"
					( attribute "PN" "2"
						( Origin gPackager )
					)
					( objectStatus "R3N21.2" )
				)
			)
			( gate "@baseboard_fab2_lib.baseboard_fab2(sch_1):page212_i77"
				( attribute "CDS_LIB" "dev_discrete"
					( Origin gPackager )
				)
				( attribute "CDS_LOCATION" "C7C10"
					( Origin gPackager )
				)
				( attribute "CDS_SEC" "1"
					( Origin gPackager )
				)
				( attribute "LOCATION" "C7C10"
					( Origin gFrontEnd )
				)
				( attribute "MATERIAL" "X6S"
					( Origin gFrontEnd )
				)
				( attribute "PACK_TYPE" "0603V"
					( Origin gFrontEnd )
				)
				( attribute "PART_NUMBER" "E15431-004"
					( Origin gFrontEnd )
				)
				( attribute "PHYS_PAGE" "212"
					( Origin gFrontEnd )
				)
				( attribute "ROT" "0"
					( Origin gFrontEnd )
				)
				( attribute "SEC" "1"
					( Origin gFrontEnd )
				)
				( attribute "SEC_TYPE" "0603V"
					( Origin gFrontEnd )
				)
				( attribute "TOLERANCE" "20%"
					( Origin gFrontEnd )
				)
				( attribute "VALUE" "22.0UF"
					( Origin gFrontEnd )
				)
				( attribute "VER" "1"
					( Origin gFrontEnd )
				)
				( attribute "VOLTAGE" "4V"
					( Units "uVoltage" "V" 1.000000)
					( Origin gFrontEnd )
				)
				( attribute "XY" "(3225,3275)"
					( Origin gFrontEnd )
				)
				( attribute "CHIPS_PART_NAME" "CAP_A"
					( Origin gPackager )
				)
				( attribute "CDS_PART_NAME" "CAP_A_0603V-22.0UF,4V,20%,X6S,A"
					( Origin gPackager )
				)
				( objectStatus "C7C10" )
				( pin "a"
					( attribute "PN" "1"
						( Origin gPackager )
					)
					( objectStatus "C7C10.1" )
				)
				( pin "b"
					( attribute "PN" "2"
						( Origin gPackager )
					)
					( objectStatus "C7C10.2" )
				)
			)
			( gate "@baseboard_fab2_lib.baseboard_fab2(sch_1):page212_i78"
				( attribute "CDS_LIB" "mstr_discrete"
					( Origin gPackager )
				)
				( attribute "CDS_LOCATION" "R7C3"
					( Origin gPackager )
				)
				( attribute "CDS_SEC" "1"
					( Origin gPackager )
				)
				( attribute "LOCATION" "R7C3"
					( Origin gFrontEnd )
				)
				( attribute "MATERIAL" "CHIP"
					( Origin gFrontEnd )
				)
				( attribute "PACK_TYPE" "0402"
					( Origin gFrontEnd )
				)
				( attribute "PART_NUMBER" "G21796-208"
					( Origin gFrontEnd )
				)
				( attribute "PHYS_PAGE" "212"
					( Origin gFrontEnd )
				)
				( attribute "ROT" "0"
					( Origin gFrontEnd )
				)
				( attribute "SEC" "1"
					( Origin gFrontEnd )
				)
				( attribute "SEC_TYPE" "0402"
					( Origin gFrontEnd )
				)
				( attribute "TOLERANCE" "1.0%"
					( Origin gFrontEnd )
				)
				( attribute "VALUE" "51.1"
					( Origin gFrontEnd )
				)
				( attribute "VER" "2"
					( Origin gFrontEnd )
				)
				( attribute "WATTAGE" "1/16W"
					( Origin gFrontEnd )
				)
				( attribute "XY" "(3600,3275)"
					( Origin gFrontEnd )
				)
				( attribute "CHIPS_PART_NAME" "RES"
					( Origin gPackager )
				)
				( attribute "CDS_PART_NAME" "RES_0402-51.1,1.0%,1/16W,CHIP,A"
					( Origin gPackager )
				)
				( objectStatus "R7C3" )
				( pin "a"
					( attribute "PN" "1"
						( Origin gPackager )
					)
					( objectStatus "R7C3.1" )
				)
				( pin "b"
					( attribute "PN" "2"
						( Origin gPackager )
					)
					( objectStatus "R7C3.2" )
				)
			)
			( gate "@baseboard_fab2_lib.baseboard_fab2(sch_1):page212_i101"
				( attribute "CDS_LIB" "mstr_discrete"
					( Origin gPackager )
				)
				( attribute "CDS_LOCATION" "EU7C1"
					( Origin gPackager )
				)
				( attribute "CDS_SEC" "1"
					( Origin gPackager )
				)
				( attribute "LOCATION" "EU7C1"
					( Origin gFrontEnd )
				)
				( attribute "MATERIAL" "IC"
					( Origin gFrontEnd )
				)
				( attribute "NO_XNET_CONNECTION" "1"
					( Origin gFrontEnd )
				)
				( attribute "PACK_TYPE" "SM"
					( Origin gFrontEnd )
				)
				( attribute "PART_NUMBER" "H73684-001"
					( Origin gFrontEnd )
				)
				( attribute "PHYS_PAGE" "212"
					( Origin gFrontEnd )
				)
				( attribute "ROT" "0"
					( Origin gFrontEnd )
				)
				( attribute "SEC" "1"
					( Origin gPackager )
				)
				( attribute "VALUE" "IR35412"
					( Origin gFrontEnd )
				)
				( attribute "VER" "1"
					( Origin gFrontEnd )
				)
				( attribute "XY" "(825,3775)"
					( Origin gFrontEnd )
				)
				( attribute "CHIPS_PART_NAME" "IR354XX"
					( Origin gPackager )
				)
				( attribute "CDS_PART_NAME" "IR354XX_SM-IR35412,IC,H73684-0A"
					( Origin gPackager )
				)
				( objectStatus "EU7C1" )
				( pin "boost"
					( attribute "PN" "33"
						( Origin gPackager )
					)
					( objectStatus "EU7C1.33" )
				)
				( pin "en"
					( attribute "PN" "35"
						( Origin gPackager )
					)
					( objectStatus "EU7C1.35" )
				)
				( pin "gl(0)"
					( attribute "PN" "6"
						( Origin gPackager )
					)
					( objectStatus "EU7C1.6" )
				)
				( pin "gl(1)"
					( attribute "PN" "41"
						( Origin gPackager )
					)
					( objectStatus "EU7C1.41" )
				)
				( pin "iout"
					( attribute "PN" "38"
						( Origin gPackager )
					)
					( objectStatus "EU7C1.38" )
				)
				( pin "lgnd"
					( attribute "PN" "2"
						( Origin gPackager )
					)
					( objectStatus "EU7C1.2" )
				)
				( pin "nc"
					( attribute "PN" "31"
						( Origin gPackager )
					)
					( objectStatus "EU7C1.31" )
				)
				( pin "ocset"
					( attribute "PN" "37"
						( Origin gPackager )
					)
					( objectStatus "EU7C1.37" )
				)
				( pin "pgnd(0)"
					( attribute "PN" "5"
						( Origin gPackager )
					)
					( objectStatus "EU7C1.5" )
				)
				( pin "pgnd(1)"
					( attribute "PN" "7"
						( Origin gPackager )
					)
					( objectStatus "EU7C1.7" )
				)
				( pin "pgnd(2)"
					( attribute "PN" "40"
						( Origin gPackager )
					)
					( objectStatus "EU7C1.40" )
				)
				( pin "phase"
					( attribute "PN" "32"
						( Origin gPackager )
					)
					( objectStatus "EU7C1.32" )
				)
				( pin "pwm"
					( attribute "PN" "34"
						( Origin gPackager )
					)
					( objectStatus "EU7C1.34" )
				)
				( pin "refin"
					( attribute "PN" "39"
						( Origin gPackager )
					)
					( objectStatus "EU7C1.39" )
				)
				( pin "sw"
					( attribute "PN" "10"
						( Origin gPackager )
					)
					( objectStatus "EU7C1.10" )
				)
				( pin "tout_flt"
					( attribute "PN" "36"
						( Origin gPackager )
					)
					( objectStatus "EU7C1.36" )
				)
				( pin "vcc"
					( attribute "PN" "3"
						( Origin gPackager )
					)
					( objectStatus "EU7C1.3" )
				)
				( pin "vdrv"
					( attribute "PN" "4"
						( Origin gPackager )
					)
					( objectStatus "EU7C1.4" )
				)
				( pin "vin(0)"
					( attribute "PN" "25"
						( Origin gPackager )
					)
					( objectStatus "EU7C1.25" )
				)
				( pin "vin(1)"
					( attribute "PN" "30"
						( Origin gPackager )
					)
					( objectStatus "EU7C1.30" )
				)
				( pin "vos"
					( attribute "PN" "1"
						( Origin gPackager )
					)
					( objectStatus "EU7C1.1" )
				)
			)
			( gate "@baseboard_fab2_lib.baseboard_fab2(sch_1):page212_i103"
				( attribute "CDS_LIB" "mstr_discrete"
					( Origin gPackager )
				)
				( attribute "CDS_LOCATION" "R7C25"
					( Origin gPackager )
				)
				( attribute "CDS_SEC" "1"
					( Origin gPackager )
				)
				( attribute "LOCATION" "R7C25"
					( Origin gFrontEnd )
				)
				( attribute "MATERIAL" "EMPTY"
					( Origin gFrontEnd )
				)
				( attribute "PACK_TYPE" "0402"
					( Origin gFrontEnd )
				)
				( attribute "PART_NUMBER" "G21796-187"
					( Origin gFrontEnd )
				)
				( attribute "PHYS_PAGE" "212"
					( Origin gFrontEnd )
				)
				( attribute "ROT" "0"
					( Origin gFrontEnd )
				)
				( attribute "SEC" "1"
					( Origin gPackager )
				)
				( attribute "TOLERANCE" "1%"
					( Origin gFrontEnd )
				)
				( attribute "VALUE" "68.1K"
					( Origin gFrontEnd )
				)
				( attribute "VER" "2"
					( Origin gFrontEnd )
				)
				( attribute "WATTAGE" "1/16W"
					( Origin gFrontEnd )
				)
				( attribute "XY" "(3100,3950)"
					( Origin gFrontEnd )
				)
				( attribute "CHIPS_PART_NAME" "RES"
					( Origin gPackager )
				)
				( attribute "CDS_PART_NAME" "RES_0402-68.1K,1%,1/16W,EMPTY,A"
					( Origin gPackager )
				)
				( objectStatus "R7C25" )
				( pin "a"
					( attribute "PN" "1"
						( Origin gPackager )
					)
					( objectStatus "R7C25.1" )
				)
				( pin "b"
					( attribute "PN" "2"
						( Origin gPackager )
					)
					( objectStatus "R7C25.2" )
				)
			)
			( gate "@baseboard_fab2_lib.baseboard_fab2(sch_1):page212_i104"
				( attribute "CDS_LIB" "mstr_misc"
					( Origin gPackager )
				)
				( attribute "CDS_LOCATION" "SH3P1"
					( Origin gPackager )
				)
				( attribute "CDS_SEC" "1"
					( Origin gPackager )
				)
				( attribute "LOCATION" "SH3P1"
					( Origin gFrontEnd )
				)
				( attribute "MATERIAL" "EMPTY"
					( Origin gFrontEnd )
				)
				( attribute "PACK_TYPE" "SH0201"
					( Origin gFrontEnd )
				)
				( attribute "PART_NUMBER" "N_A"
					( Origin gFrontEnd )
				)
				( attribute "PHYS_PAGE" "212"
					( Origin gFrontEnd )
				)
				( attribute "PIN_SHORT" "A:B"
					( Origin gFrontEnd )
				)
				( attribute "ROT" "0"
					( Origin gFrontEnd )
				)
				( attribute "SEC" "1"
					( Origin gFrontEnd )
				)
				( attribute "SEC_TYPE" "SH0201"
					( Origin gFrontEnd )
				)
				( attribute "VER" "1"
					( Origin gFrontEnd )
				)
				( attribute "XY" "(-1300,1850)"
					( Origin gFrontEnd )
				)
				( attribute "CHIPS_PART_NAME" "SHUNT"
					( Origin gPackager )
				)
				( attribute "CDS_PART_NAME" "SHUNT_SH0201-EMPTY,N_A"
					( Origin gPackager )
				)
				( objectStatus "SH3P1" )
				( pin "a"
					( attribute "PN" "1"
						( Origin gPackager )
					)
					( objectStatus "SH3P1.1" )
				)
				( pin "b"
					( attribute "PN" "2"
						( Origin gPackager )
					)
					( objectStatus "SH3P1.2" )
				)
			)
			( gate "@baseboard_fab2_lib.baseboard_fab2(sch_1):page212_i105"
				( attribute "CDS_LIB" "mstr_misc"
					( Origin gPackager )
				)
				( attribute "CDS_LOCATION" "SH3P2"
					( Origin gPackager )
				)
				( attribute "CDS_SEC" "1"
					( Origin gPackager )
				)
				( attribute "LOCATION" "SH3P2"
					( Origin gFrontEnd )
				)
				( attribute "MATERIAL" "EMPTY"
					( Origin gFrontEnd )
				)
				( attribute "PACK_TYPE" "SH0201"
					( Origin gFrontEnd )
				)
				( attribute "PART_NUMBER" "N_A"
					( Origin gFrontEnd )
				)
				( attribute "PHYS_PAGE" "212"
					( Origin gFrontEnd )
				)
				( attribute "PIN_SHORT" "A:B"
					( Origin gFrontEnd )
				)
				( attribute "ROT" "0"
					( Origin gFrontEnd )
				)
				( attribute "SEC" "1"
					( Origin gFrontEnd )
				)
				( attribute "SEC_TYPE" "SH0201"
					( Origin gFrontEnd )
				)
				( attribute "VER" "1"
					( Origin gFrontEnd )
				)
				( attribute "XY" "(-1300,1400)"
					( Origin gFrontEnd )
				)
				( attribute "CHIPS_PART_NAME" "SHUNT"
					( Origin gPackager )
				)
				( attribute "CDS_PART_NAME" "SHUNT_SH0201-EMPTY,N_A"
					( Origin gPackager )
				)
				( objectStatus "SH3P2" )
				( pin "a"
					( attribute "PN" "1"
						( Origin gPackager )
					)
					( objectStatus "SH3P2.1" )
				)
				( pin "b"
					( attribute "PN" "2"
						( Origin gPackager )
					)
					( objectStatus "SH3P2.2" )
				)
			)
			( gate "@baseboard_fab2_lib.baseboard_fab2(sch_1):page213_i9"
				( attribute "CDS_LIB" "dev_discrete"
					( Origin gPackager )
				)
				( attribute "CDS_LOCATION" "C4D31"
					( Origin gPackager )
				)
				( attribute "CDS_SEC" "1"
					( Origin gPackager )
				)
				( attribute "LOCATION" "C4D31"
					( Origin gFrontEnd )
				)
				( attribute "MATERIAL" "X6S"
					( Origin gFrontEnd )
				)
				( attribute "PACK_TYPE" "0402V"
					( Origin gFrontEnd )
				)
				( attribute "PART_NUMBER" "D97712-004"
					( Origin gFrontEnd )
				)
				( attribute "PHYS_PAGE" "213"
					( Origin gFrontEnd )
				)
				( attribute "ROOM" "PVCCIO_CPU1"
					( Origin gFrontEnd )
				)
				( attribute "ROT" "0"
					( Origin gFrontEnd )
				)
				( attribute "SEC" "1"
					( Origin gFrontEnd )
				)
				( attribute "SEC_TYPE" "0402V"
					( Origin gFrontEnd )
				)
				( attribute "TOLERANCE" "10%"
					( Origin gFrontEnd )
				)
				( attribute "VALUE" "1.0UF"
					( Origin gFrontEnd )
				)
				( attribute "VER" "1"
					( Origin gFrontEnd )
				)
				( attribute "VOLTAGE" "6.3V"
					( Units "uVoltage" "V" 1.000000)
					( Origin gFrontEnd )
				)
				( attribute "XY" "(2425,1575)"
					( Origin gFrontEnd )
				)
				( attribute "CHIPS_PART_NAME" "CAP_A"
					( Origin gPackager )
				)
				( attribute "CDS_PART_NAME" "CAP_A_0402V-1.0UF,6.3V,10%,X6SA"
					( Origin gPackager )
				)
				( objectStatus "C4D31" )
				( pin "a"
					( attribute "PN" "1"
						( Origin gPackager )
					)
					( objectStatus "C4D31.1" )
				)
				( pin "b"
					( attribute "PN" "2"
						( Origin gPackager )
					)
					( objectStatus "C4D31.2" )
				)
			)
			( gate "@baseboard_fab2_lib.baseboard_fab2(sch_1):page213_i11"
				( attribute "CDS_LIB" "dev_discrete"
					( Origin gPackager )
				)
				( attribute "CDS_LOCATION" "C4D32"
					( Origin gPackager )
				)
				( attribute "CDS_SEC" "1"
					( Origin gPackager )
				)
				( attribute "LOCATION" "C4D32"
					( Origin gFrontEnd )
				)
				( attribute "MATERIAL" "X7R"
					( Origin gFrontEnd )
				)
				( attribute "PACK_TYPE" "0402V"
					( Origin gFrontEnd )
				)
				( attribute "PART_NUMBER" "A36096-030"
					( Origin gFrontEnd )
				)
				( attribute "PHYS_PAGE" "213"
					( Origin gFrontEnd )
				)
				( attribute "ROOM" "PVCCIO_CPU1"
					( Origin gFrontEnd )
				)
				( attribute "ROT" "0"
					( Origin gFrontEnd )
				)
				( attribute "SEC" "1"
					( Origin gFrontEnd )
				)
				( attribute "SEC_TYPE" "0402V"
					( Origin gFrontEnd )
				)
				( attribute "TOLERANCE" "10%"
					( Origin gFrontEnd )
				)
				( attribute "VALUE" "0.1UF"
					( Origin gFrontEnd )
				)
				( attribute "VER" "1"
					( Origin gFrontEnd )
				)
				( attribute "VOLTAGE" "16V"
					( Units "uVoltage" "V" 1.000000)
					( Origin gFrontEnd )
				)
				( attribute "XY" "(2025,1575)"
					( Origin gFrontEnd )
				)
				( attribute "CHIPS_PART_NAME" "CAP_A"
					( Origin gPackager )
				)
				( attribute "CDS_PART_NAME" "CAP_A_0402V-0.1UF,16V,10%,X7R,A"
					( Origin gPackager )
				)
				( objectStatus "C4D32" )
				( pin "a"
					( attribute "PN" "1"
						( Origin gPackager )
					)
					( objectStatus "C4D32.1" )
				)
				( pin "b"
					( attribute "PN" "2"
						( Origin gPackager )
					)
					( objectStatus "C4D32.2" )
				)
			)
			( gate "@baseboard_fab2_lib.baseboard_fab2(sch_1):page213_i13"
				( attribute "CDS_LIB" "mstr_discrete"
					( Origin gPackager )
				)
				( attribute "CDS_LOCATION" "R4D46"
					( Origin gPackager )
				)
				( attribute "CDS_SEC" "1"
					( Origin gPackager )
				)
				( attribute "LOCATION" "R4D46"
					( Origin gFrontEnd )
				)
				( attribute "MATERIAL" "CHIP"
					( Origin gFrontEnd )
				)
				( attribute "PACK_TYPE" "0402"
					( Origin gFrontEnd )
				)
				( attribute "PART_NUMBER" "G21796-250"
					( Origin gFrontEnd )
				)
				( attribute "PHYS_PAGE" "213"
					( Origin gFrontEnd )
				)
				( attribute "ROOM" "PVCCIO_CPU1"
					( Origin gFrontEnd )
				)
				( attribute "ROT" "0"
					( Origin gFrontEnd )
				)
				( attribute "SEC" "1"
					( Origin gFrontEnd )
				)
				( attribute "SEC_TYPE" "0402"
					( Origin gFrontEnd )
				)
				( attribute "TOLERANCE" "1.0%"
					( Origin gFrontEnd )
				)
				( attribute "VALUE" "22.1"
					( Origin gFrontEnd )
				)
				( attribute "VER" "1"
					( Origin gFrontEnd )
				)
				( attribute "WATTAGE" "1/16W"
					( Origin gFrontEnd )
				)
				( attribute "XY" "(1950,3575)"
					( Origin gFrontEnd )
				)
				( attribute "CHIPS_PART_NAME" "RES"
					( Origin gPackager )
				)
				( attribute "CDS_PART_NAME" "RES_0402-22.1,1.0%,1/16W,CHIP,A"
					( Origin gPackager )
				)
				( objectStatus "R4D46" )
				( pin "a"
					( attribute "PN" "1"
						( Origin gPackager )
					)
					( objectStatus "R4D46.1" )
				)
				( pin "b"
					( attribute "PN" "2"
						( Origin gPackager )
					)
					( objectStatus "R4D46.2" )
				)
			)
			( gate "@baseboard_fab2_lib.baseboard_fab2(sch_1):page213_i14"
				( attribute "CDS_LIB" "mstr_discrete"
					( Origin gPackager )
				)
				( attribute "CDS_LOCATION" "R6P49"
					( Origin gPackager )
				)
				( attribute "CDS_SEC" "1"
					( Origin gPackager )
				)
				( attribute "LOCATION" "R6P49"
					( Origin gFrontEnd )
				)
				( attribute "MATERIAL" "EMPTY"
					( Origin gFrontEnd )
				)
				( attribute "PACK_TYPE" "0402"
					( Origin gFrontEnd )
				)
				( attribute "PART_NUMBER" "G21796-311"
					( Origin gFrontEnd )
				)
				( attribute "PHYS_PAGE" "213"
					( Origin gFrontEnd )
				)
				( attribute "ROOM" "PVCCIO_CPU1"
					( Origin gFrontEnd )
				)
				( attribute "ROT" "0"
					( Origin gFrontEnd )
				)
				( attribute "SEC" "1"
					( Origin gFrontEnd )
				)
				( attribute "SEC_TYPE" "0402"
					( Origin gFrontEnd )
				)
				( attribute "TOLERANCE" "1.0%"
					( Origin gFrontEnd )
				)
				( attribute "VALUE" "2.26K"
					( Origin gFrontEnd )
				)
				( attribute "VER" "2"
					( Origin gFrontEnd )
				)
				( attribute "WATTAGE" "1/16W"
					( Origin gFrontEnd )
				)
				( attribute "XY" "(1600,4075)"
					( Origin gFrontEnd )
				)
				( attribute "CHIPS_PART_NAME" "RES"
					( Origin gPackager )
				)
				( attribute "CDS_PART_NAME" "RES_0402-2.26K,1.0%,1/16W,EMPTA"
					( Origin gPackager )
				)
				( objectStatus "R6P49" )
				( pin "a"
					( attribute "PN" "1"
						( Origin gPackager )
					)
					( objectStatus "R6P49.1" )
				)
				( pin "b"
					( attribute "PN" "2"
						( Origin gPackager )
					)
					( objectStatus "R6P49.2" )
				)
			)
			( gate "@baseboard_fab2_lib.baseboard_fab2(sch_1):page213_i15"
				( attribute "CDS_LIB" "mstr_discrete"
					( Origin gPackager )
				)
				( attribute "CDS_LOCATION" "R4D42"
					( Origin gPackager )
				)
				( attribute "CDS_SEC" "1"
					( Origin gPackager )
				)
				( attribute "LOCATION" "R4D42"
					( Origin gFrontEnd )
				)
				( attribute "MATERIAL" "CHIP"
					( Origin gFrontEnd )
				)
				( attribute "PACK_TYPE" "0402"
					( Origin gFrontEnd )
				)
				( attribute "PART_NUMBER" "G21796-026"
					( Origin gFrontEnd )
				)
				( attribute "PHYS_PAGE" "213"
					( Origin gFrontEnd )
				)
				( attribute "ROOM" "PVCCIO_CPU1"
					( Origin gFrontEnd )
				)
				( attribute "ROT" "0"
					( Origin gFrontEnd )
				)
				( attribute "SEC" "1"
					( Origin gPackager )
				)
				( attribute "TOLERANCE" "1%"
					( Origin gFrontEnd )
				)
				( attribute "VALUE" "1.00K"
					( Origin gFrontEnd )
				)
				( attribute "VER" "2"
					( Origin gFrontEnd )
				)
				( attribute "WATTAGE" "1/16W"
					( Origin gFrontEnd )
				)
				( attribute "XY" "(950,4050)"
					( Origin gFrontEnd )
				)
				( attribute "CHIPS_PART_NAME" "RES"
					( Origin gPackager )
				)
				( attribute "CDS_PART_NAME" "RES_0402-1.00K,1%,1/16W,CHIP,GA"
					( Origin gPackager )
				)
				( objectStatus "R4D42" )
				( pin "a"
					( attribute "PN" "1"
						( Origin gPackager )
					)
					( objectStatus "R4D42.1" )
				)
				( pin "b"
					( attribute "PN" "2"
						( Origin gPackager )
					)
					( objectStatus "R4D42.2" )
				)
			)
			( gate "@baseboard_fab2_lib.baseboard_fab2(sch_1):page213_i16"
				( attribute "CDS_LIB" "mstr_discrete"
					( Origin gPackager )
				)
				( attribute "CDS_LOCATION" "R4D56"
					( Origin gPackager )
				)
				( attribute "CDS_SEC" "1"
					( Origin gPackager )
				)
				( attribute "LOCATION" "R4D56"
					( Origin gFrontEnd )
				)
				( attribute "MATERIAL" "CHIP"
					( Origin gFrontEnd )
				)
				( attribute "PACK_TYPE" "0402"
					( Origin gFrontEnd )
				)
				( attribute "PART_NUMBER" "G21497-005"
					( Origin gFrontEnd )
				)
				( attribute "PHYS_PAGE" "213"
					( Origin gFrontEnd )
				)
				( attribute "ROOM" "PVCCIO_CPU1"
					( Origin gFrontEnd )
				)
				( attribute "ROT" "0"
					( Origin gFrontEnd )
				)
				( attribute "SEC" "1"
					( Origin gFrontEnd )
				)
				( attribute "SEC_TYPE" "0402"
					( Origin gFrontEnd )
				)
				( attribute "TOLERANCE" "5%"
					( Origin gFrontEnd )
				)
				( attribute "VALUE" "0.0"
					( Origin gFrontEnd )
				)
				( attribute "VER" "1"
					( Origin gFrontEnd )
				)
				( attribute "WATTAGE" "1/16W"
					( Origin gFrontEnd )
				)
				( attribute "XY" "(1375,3125)"
					( Origin gFrontEnd )
				)
				( attribute "CHIPS_PART_NAME" "RES"
					( Origin gPackager )
				)
				( attribute "CDS_PART_NAME" "RES_0402-0.0,5%,1/16W,CHIP,G21A"
					( Origin gPackager )
				)
				( objectStatus "R4D56" )
				( pin "a"
					( attribute "PN" "1"
						( Origin gPackager )
					)
					( objectStatus "R4D56.1" )
				)
				( pin "b"
					( attribute "PN" "2"
						( Origin gPackager )
					)
					( objectStatus "R4D56.2" )
				)
			)
			( gate "@baseboard_fab2_lib.baseboard_fab2(sch_1):page213_i17"
				( attribute "CDS_LIB" "dev_discrete"
					( Origin gPackager )
				)
				( attribute "CDS_LOCATION" "C4D36"
					( Origin gPackager )
				)
				( attribute "CDS_SEC" "1"
					( Origin gPackager )
				)
				( attribute "LOCATION" "C4D36"
					( Origin gFrontEnd )
				)
				( attribute "MATERIAL" "X6S"
					( Origin gFrontEnd )
				)
				( attribute "PACK_TYPE" "0402V"
					( Origin gFrontEnd )
				)
				( attribute "PART_NUMBER" "D97712-004"
					( Origin gFrontEnd )
				)
				( attribute "PHYS_PAGE" "213"
					( Origin gFrontEnd )
				)
				( attribute "ROOM" "PVCCIO_CPU1"
					( Origin gFrontEnd )
				)
				( attribute "ROT" "0"
					( Origin gFrontEnd )
				)
				( attribute "SEC" "1"
					( Origin gPackager )
				)
				( attribute "TOLERANCE" "10%"
					( Origin gFrontEnd )
				)
				( attribute "VALUE" "1.0UF"
					( Origin gFrontEnd )
				)
				( attribute "VER" "1"
					( Origin gFrontEnd )
				)
				( attribute "VOLTAGE" "6.3V"
					( Units "uVoltage" "V" 1.000000)
					( Origin gFrontEnd )
				)
				( attribute "XY" "(150,4150)"
					( Origin gFrontEnd )
				)
				( attribute "CHIPS_PART_NAME" "CAP_A"
					( Origin gPackager )
				)
				( attribute "CDS_PART_NAME" "CAP_A_0402V-1.0UF,6.3V,10%,X6SA"
					( Origin gPackager )
				)
				( objectStatus "C4D36" )
				( pin "a"
					( attribute "PN" "1"
						( Origin gPackager )
					)
					( objectStatus "C4D36.1" )
				)
				( pin "b"
					( attribute "PN" "2"
						( Origin gPackager )
					)
					( objectStatus "C4D36.2" )
				)
			)
			( gate "@baseboard_fab2_lib.baseboard_fab2(sch_1):page213_i25"
				( attribute "CDS_LIB" "mstr_discrete"
					( Origin gPackager )
				)
				( attribute "CDS_LOCATION" "R4D47"
					( Origin gPackager )
				)
				( attribute "CDS_SEC" "1"
					( Origin gPackager )
				)
				( attribute "LOCATION" "R4D47"
					( Origin gFrontEnd )
				)
				( attribute "MATERIAL" "CHIP"
					( Origin gFrontEnd )
				)
				( attribute "PACK_TYPE" "0402"
					( Origin gFrontEnd )
				)
				( attribute "PART_NUMBER" "G21497-005"
					( Origin gFrontEnd )
				)
				( attribute "PHYS_PAGE" "213"
					( Origin gFrontEnd )
				)
				( attribute "ROOM" "PVCCIO_CPU1"
					( Origin gFrontEnd )
				)
				( attribute "ROT" "0"
					( Origin gFrontEnd )
				)
				( attribute "SEC" "1"
					( Origin gPackager )
				)
				( attribute "TOLERANCE" "5%"
					( Origin gFrontEnd )
				)
				( attribute "VALUE" "0.0"
					( Origin gFrontEnd )
				)
				( attribute "VER" "2"
					( Origin gFrontEnd )
				)
				( attribute "WATTAGE" "1/16W"
					( Origin gFrontEnd )
				)
				( attribute "XY" "(-550,4500)"
					( Origin gFrontEnd )
				)
				( attribute "CHIPS_PART_NAME" "RES"
					( Origin gPackager )
				)
				( attribute "CDS_PART_NAME" "RES_0402-0.0,5%,1/16W,CHIP,G21A"
					( Origin gPackager )
				)
				( objectStatus "R4D47" )
				( pin "a"
					( attribute "PN" "1"
						( Origin gPackager )
					)
					( objectStatus "R4D47.1" )
				)
				( pin "b"
					( attribute "PN" "2"
						( Origin gPackager )
					)
					( objectStatus "R4D47.2" )
				)
			)
			( gate "@baseboard_fab2_lib.baseboard_fab2(sch_1):page213_i27"
				( attribute "CDS_LIB" "mstr_discrete"
					( Origin gPackager )
				)
				( attribute "CDS_LOCATION" "R6P35"
					( Origin gPackager )
				)
				( attribute "CDS_SEC" "1"
					( Origin gPackager )
				)
				( attribute "LOCATION" "R6P35"
					( Origin gFrontEnd )
				)
				( attribute "MATERIAL" "EMPTY"
					( Origin gFrontEnd )
				)
				( attribute "PACK_TYPE" "0402"
					( Origin gFrontEnd )
				)
				( attribute "PART_NUMBER" "G21796-017"
					( Origin gFrontEnd )
				)
				( attribute "PHYS_PAGE" "213"
					( Origin gFrontEnd )
				)
				( attribute "ROOM" "PVCCIO_CPU1"
					( Origin gFrontEnd )
				)
				( attribute "ROT" "0"
					( Origin gFrontEnd )
				)
				( attribute "SEC" "1"
					( Origin gPackager )
				)
				( attribute "TOLERANCE" "1%"
					( Origin gFrontEnd )
				)
				( attribute "VALUE" "100.0"
					( Origin gFrontEnd )
				)
				( attribute "VER" "2"
					( Origin gFrontEnd )
				)
				( attribute "WATTAGE" "1/16W"
					( Origin gFrontEnd )
				)
				( attribute "XY" "(-1375,4475)"
					( Origin gFrontEnd )
				)
				( attribute "CHIPS_PART_NAME" "RES"
					( Origin gPackager )
				)
				( attribute "CDS_PART_NAME" "RES_0402-100.0,1%,1/16W,EMPTY,A"
					( Origin gPackager )
				)
				( objectStatus "R6P35" )
				( pin "a"
					( attribute "PN" "1"
						( Origin gPackager )
					)
					( objectStatus "R6P35.1" )
				)
				( pin "b"
					( attribute "PN" "2"
						( Origin gPackager )
					)
					( objectStatus "R6P35.2" )
				)
			)
			( gate "@baseboard_fab2_lib.baseboard_fab2(sch_1):page213_i30"
				( attribute "CDS_LIB" "mstr_discrete"
					( Origin gPackager )
				)
				( attribute "CDS_LOCATION" "R6P33"
					( Origin gPackager )
				)
				( attribute "CDS_SEC" "1"
					( Origin gPackager )
				)
				( attribute "LOCATION" "R6P33"
					( Origin gFrontEnd )
				)
				( attribute "MATERIAL" "EMPTY"
					( Origin gFrontEnd )
				)
				( attribute "PACK_TYPE" "0402"
					( Origin gFrontEnd )
				)
				( attribute "PART_NUMBER" "G21796-203"
					( Origin gFrontEnd )
				)
				( attribute "PHYS_PAGE" "213"
					( Origin gFrontEnd )
				)
				( attribute "ROOM" "PVCCIO_CPU1"
					( Origin gFrontEnd )
				)
				( attribute "ROT" "0"
					( Origin gFrontEnd )
				)
				( attribute "SEC" "1"
					( Origin gFrontEnd )
				)
				( attribute "SEC_TYPE" "0402"
					( Origin gFrontEnd )
				)
				( attribute "TOLERANCE" "1%"
					( Origin gFrontEnd )
				)
				( attribute "VALUE" "110"
					( Origin gFrontEnd )
				)
				( attribute "VER" "2"
					( Origin gFrontEnd )
				)
				( attribute "WATTAGE" "1/16W"
					( Origin gFrontEnd )
				)
				( attribute "XY" "(-2050,4425)"
					( Origin gFrontEnd )
				)
				( attribute "CHIPS_PART_NAME" "RES"
					( Origin gPackager )
				)
				( attribute "CDS_PART_NAME" "RES_0402-110,1%,1/16W,EMPTY,G2A"
					( Origin gPackager )
				)
				( objectStatus "R6P33" )
				( pin "a"
					( attribute "PN" "1"
						( Origin gPackager )
					)
					( objectStatus "R6P33.1" )
				)
				( pin "b"
					( attribute "PN" "2"
						( Origin gPackager )
					)
					( objectStatus "R6P33.2" )
				)
			)
			( gate "@baseboard_fab2_lib.baseboard_fab2(sch_1):page213_i31"
				( attribute "CDS_LIB" "mstr_discrete"
					( Origin gPackager )
				)
				( attribute "CDS_LOCATION" "R4D60"
					( Origin gPackager )
				)
				( attribute "CDS_SEC" "1"
					( Origin gPackager )
				)
				( attribute "LOCATION" "R4D60"
					( Origin gFrontEnd )
				)
				( attribute "MATERIAL" "CHIP"
					( Origin gFrontEnd )
				)
				( attribute "PACK_TYPE" "0402"
					( Origin gFrontEnd )
				)
				( attribute "PART_NUMBER" "G21796-160"
					( Origin gFrontEnd )
				)
				( attribute "PHYS_PAGE" "213"
					( Origin gFrontEnd )
				)
				( attribute "ROOM" "PVCCIO_CPU1"
					( Origin gFrontEnd )
				)
				( attribute "ROT" "0"
					( Origin gFrontEnd )
				)
				( attribute "SEC" "1"
					( Origin gFrontEnd )
				)
				( attribute "SEC_TYPE" "0402"
					( Origin gFrontEnd )
				)
				( attribute "TOLERANCE" "1%"
					( Origin gFrontEnd )
				)
				( attribute "VALUE" "100.0K"
					( Origin gFrontEnd )
				)
				( attribute "VER" "2"
					( Origin gFrontEnd )
				)
				( attribute "WATTAGE" "1/16W"
					( Origin gFrontEnd )
				)
				( attribute "XY" "(-2425,4700)"
					( Origin gFrontEnd )
				)
				( attribute "CHIPS_PART_NAME" "RES"
					( Origin gPackager )
				)
				( attribute "CDS_PART_NAME" "RES_0402-100.0K,1%,1/16W,CHIP,B"
					( Origin gPackager )
				)
				( objectStatus "R4D60" )
				( pin "a"
					( attribute "PN" "1"
						( Origin gPackager )
					)
					( objectStatus "R4D60.1" )
				)
				( pin "b"
					( attribute "PN" "2"
						( Origin gPackager )
					)
					( objectStatus "R4D60.2" )
				)
			)
			( gate "@baseboard_fab2_lib.baseboard_fab2(sch_1):page213_i32"
				( attribute "CDS_LIB" "mstr_discrete"
					( Origin gPackager )
				)
				( attribute "CDS_LOCATION" "R4D57"
					( Origin gPackager )
				)
				( attribute "CDS_SEC" "1"
					( Origin gPackager )
				)
				( attribute "LOCATION" "R4D57"
					( Origin gFrontEnd )
				)
				( attribute "MATERIAL" "CHIP"
					( Origin gFrontEnd )
				)
				( attribute "PACK_TYPE" "0402"
					( Origin gFrontEnd )
				)
				( attribute "PART_NUMBER" "G21796-003"
					( Origin gFrontEnd )
				)
				( attribute "PHYS_PAGE" "213"
					( Origin gFrontEnd )
				)
				( attribute "ROOM" "PVCCIO_CPU1"
					( Origin gFrontEnd )
				)
				( attribute "ROT" "0"
					( Origin gFrontEnd )
				)
				( attribute "SEC" "1"
					( Origin gFrontEnd )
				)
				( attribute "SEC_TYPE" "0402"
					( Origin gFrontEnd )
				)
				( attribute "TOLERANCE" "1%"
					( Origin gFrontEnd )
				)
				( attribute "VALUE" "1.5K"
					( Origin gFrontEnd )
				)
				( attribute "VER" "2"
					( Origin gFrontEnd )
				)
				( attribute "WATTAGE" "1/16W"
					( Origin gFrontEnd )
				)
				( attribute "XY" "(-2425,4250)"
					( Origin gFrontEnd )
				)
				( attribute "CHIPS_PART_NAME" "RES"
					( Origin gPackager )
				)
				( attribute "CDS_PART_NAME" "RES_0402-1.5K,1%,1/16W,CHIP,G2A"
					( Origin gPackager )
				)
				( objectStatus "R4D57" )
				( pin "a"
					( attribute "PN" "1"
						( Origin gPackager )
					)
					( objectStatus "R4D57.1" )
				)
				( pin "b"
					( attribute "PN" "2"
						( Origin gPackager )
					)
					( objectStatus "R4D57.2" )
				)
			)
			( gate "@baseboard_fab2_lib.baseboard_fab2(sch_1):page213_i33"
				( attribute "CDS_LIB" "mstr_discrete"
					( Origin gPackager )
				)
				( attribute "CDS_LOCATION" "C4D40"
					( Origin gPackager )
				)
				( attribute "CDS_SEC" "1"
					( Origin gPackager )
				)
				( attribute "LOCATION" "C4D40"
					( Origin gFrontEnd )
				)
				( attribute "MATERIAL" "X7R"
					( Origin gFrontEnd )
				)
				( attribute "PACK_TYPE" "0402LF"
					( Origin gFrontEnd )
				)
				( attribute "PART_NUMBER" "A36096-046"
					( Origin gFrontEnd )
				)
				( attribute "PHYS_PAGE" "213"
					( Origin gFrontEnd )
				)
				( attribute "ROOM" "PVCCIO_CPU1"
					( Origin gFrontEnd )
				)
				( attribute "ROT" "2"
					( Origin gFrontEnd )
				)
				( attribute "SEC" "1"
					( Origin gFrontEnd )
				)
				( attribute "SEC_TYPE" "0402LF"
					( Origin gFrontEnd )
				)
				( attribute "TOLERANCE" "10%"
					( Origin gFrontEnd )
				)
				( attribute "VALUE" "1000PF"
					( Origin gFrontEnd )
				)
				( attribute "VER" "1"
					( Origin gFrontEnd )
				)
				( attribute "VOLTAGE" "50V"
					( Units "uVoltage" "V" 1.000000)
					( Origin gFrontEnd )
				)
				( attribute "XY" "(-2650,4250)"
					( Origin gFrontEnd )
				)
				( attribute "CHIPS_PART_NAME" "CAP"
					( Origin gPackager )
				)
				( attribute "CDS_PART_NAME" "CAP_0402LF-1000PF,50V,10%,X7R,A"
					( Origin gPackager )
				)
				( objectStatus "C4D40" )
				( pin "a"
					( attribute "PN" "1"
						( Origin gPackager )
					)
					( objectStatus "C4D40.1" )
				)
				( pin "b"
					( attribute "PN" "2"
						( Origin gPackager )
					)
					( objectStatus "C4D40.2" )
				)
			)
			( gate "@baseboard_fab2_lib.baseboard_fab2(sch_1):page213_i35"
				( attribute "CDS_LIB" "dev_discrete"
					( Origin gPackager )
				)
				( attribute "CDS_LOCATION" "C4D38"
					( Origin gPackager )
				)
				( attribute "CDS_SEC" "1"
					( Origin gPackager )
				)
				( attribute "LOCATION" "C4D38"
					( Origin gFrontEnd )
				)
				( attribute "MATERIAL" "X7R"
					( Origin gFrontEnd )
				)
				( attribute "PACK_TYPE" "0402V"
					( Origin gFrontEnd )
				)
				( attribute "PART_NUMBER" "A36096-030"
					( Origin gFrontEnd )
				)
				( attribute "PHYS_PAGE" "213"
					( Origin gFrontEnd )
				)
				( attribute "ROOM" "PVCCIO_CPU1"
					( Origin gFrontEnd )
				)
				( attribute "ROT" "0"
					( Origin gFrontEnd )
				)
				( attribute "SEC" "1"
					( Origin gPackager )
				)
				( attribute "TOLERANCE" "10%"
					( Origin gFrontEnd )
				)
				( attribute "VALUE" "0.1UF"
					( Origin gFrontEnd )
				)
				( attribute "VER" "1"
					( Origin gFrontEnd )
				)
				( attribute "VOLTAGE" "16V"
					( Units "uVoltage" "V" 1.000000)
					( Origin gFrontEnd )
				)
				( attribute "XY" "(-250,4150)"
					( Origin gFrontEnd )
				)
				( attribute "CHIPS_PART_NAME" "CAP_A"
					( Origin gPackager )
				)
				( attribute "CDS_PART_NAME" "CAP_A_0402V-0.1UF,16V,10%,X7R,A"
					( Origin gPackager )
				)
				( objectStatus "C4D38" )
				( pin "a"
					( attribute "PN" "1"
						( Origin gPackager )
					)
					( objectStatus "C4D38.1" )
				)
				( pin "b"
					( attribute "PN" "2"
						( Origin gPackager )
					)
					( objectStatus "C4D38.2" )
				)
			)
			( gate "@baseboard_fab2_lib.baseboard_fab2(sch_1):page213_i37"
				( attribute "CDS_LIB" "mstr_discrete"
					( Origin gPackager )
				)
				( attribute "CDS_LOCATION" "R4D54"
					( Origin gPackager )
				)
				( attribute "CDS_SEC" "1"
					( Origin gPackager )
				)
				( attribute "LOCATION" "R4D54"
					( Origin gFrontEnd )
				)
				( attribute "MATERIAL" "CHIP"
					( Origin gFrontEnd )
				)
				( attribute "PACK_TYPE" "0402"
					( Origin gFrontEnd )
				)
				( attribute "PART_NUMBER" "G21497-005"
					( Origin gFrontEnd )
				)
				( attribute "PHYS_PAGE" "213"
					( Origin gFrontEnd )
				)
				( attribute "ROOM" "PVCCIO_CPU1"
					( Origin gFrontEnd )
				)
				( attribute "ROT" "0"
					( Origin gFrontEnd )
				)
				( attribute "SEC" "1"
					( Origin gPackager )
				)
				( attribute "TOLERANCE" "5%"
					( Origin gFrontEnd )
				)
				( attribute "VALUE" "0.0"
					( Origin gFrontEnd )
				)
				( attribute "VER" "1"
					( Origin gFrontEnd )
				)
				( attribute "WATTAGE" "1/16W"
					( Origin gFrontEnd )
				)
				( attribute "XY" "(-1175,2925)"
					( Origin gFrontEnd )
				)
				( attribute "CHIPS_PART_NAME" "RES"
					( Origin gPackager )
				)
				( attribute "CDS_PART_NAME" "RES_0402-0.0,5%,1/16W,CHIP,G21A"
					( Origin gPackager )
				)
				( objectStatus "R4D54" )
				( pin "a"
					( attribute "PN" "1"
						( Origin gPackager )
					)
					( objectStatus "R4D54.1" )
				)
				( pin "b"
					( attribute "PN" "2"
						( Origin gPackager )
					)
					( objectStatus "R4D54.2" )
				)
			)
			( gate "@baseboard_fab2_lib.baseboard_fab2(sch_1):page213_i38"
				( attribute "CDS_LIB" "mstr_discrete"
					( Origin gPackager )
				)
				( attribute "CDS_LOCATION" "R4D44"
					( Origin gPackager )
				)
				( attribute "CDS_SEC" "1"
					( Origin gPackager )
				)
				( attribute "LOCATION" "R4D44"
					( Origin gFrontEnd )
				)
				( attribute "MATERIAL" "CHIP"
					( Origin gFrontEnd )
				)
				( attribute "PACK_TYPE" "0402"
					( Origin gFrontEnd )
				)
				( attribute "PART_NUMBER" "G21796-173"
					( Origin gFrontEnd )
				)
				( attribute "PHYS_PAGE" "213"
					( Origin gFrontEnd )
				)
				( attribute "ROOM" "PVCCIO_CPU1"
					( Origin gFrontEnd )
				)
				( attribute "ROT" "0"
					( Origin gFrontEnd )
				)
				( attribute "SEC" "1"
					( Origin gPackager )
				)
				( attribute "TOLERANCE" "1%"
					( Origin gFrontEnd )
				)
				( attribute "VALUE" "20.0"
					( Origin gFrontEnd )
				)
				( attribute "VER" "1"
					( Origin gFrontEnd )
				)
				( attribute "WATTAGE" "1/16W"
					( Origin gFrontEnd )
				)
				( attribute "XY" "(-1175,2425)"
					( Origin gFrontEnd )
				)
				( attribute "CHIPS_PART_NAME" "RES"
					( Origin gPackager )
				)
				( attribute "CDS_PART_NAME" "RES_0402-20.0,1%,1/16W,CHIP,G2A"
					( Origin gPackager )
				)
				( objectStatus "R4D44" )
				( pin "a"
					( attribute "PN" "1"
						( Origin gPackager )
					)
					( objectStatus "R4D44.1" )
				)
				( pin "b"
					( attribute "PN" "2"
						( Origin gPackager )
					)
					( objectStatus "R4D44.2" )
				)
			)
			( gate "@baseboard_fab2_lib.baseboard_fab2(sch_1):page213_i39"
				( attribute "CDS_LIB" "mstr_discrete"
					( Origin gPackager )
				)
				( attribute "CDS_LOCATION" "R4D43"
					( Origin gPackager )
				)
				( attribute "CDS_SEC" "1"
					( Origin gPackager )
				)
				( attribute "LOCATION" "R4D43"
					( Origin gFrontEnd )
				)
				( attribute "MATERIAL" "CHIP"
					( Origin gFrontEnd )
				)
				( attribute "PACK_TYPE" "0402"
					( Origin gFrontEnd )
				)
				( attribute "PART_NUMBER" "G21796-173"
					( Origin gFrontEnd )
				)
				( attribute "PHYS_PAGE" "213"
					( Origin gFrontEnd )
				)
				( attribute "ROOM" "PVCCIO_CPU1"
					( Origin gFrontEnd )
				)
				( attribute "ROT" "0"
					( Origin gFrontEnd )
				)
				( attribute "SEC" "1"
					( Origin gPackager )
				)
				( attribute "TOLERANCE" "1%"
					( Origin gFrontEnd )
				)
				( attribute "VALUE" "20.0"
					( Origin gFrontEnd )
				)
				( attribute "VER" "1"
					( Origin gFrontEnd )
				)
				( attribute "WATTAGE" "1/16W"
					( Origin gFrontEnd )
				)
				( attribute "XY" "(-1500,2375)"
					( Origin gFrontEnd )
				)
				( attribute "CHIPS_PART_NAME" "RES"
					( Origin gPackager )
				)
				( attribute "CDS_PART_NAME" "RES_0402-20.0,1%,1/16W,CHIP,G2A"
					( Origin gPackager )
				)
				( objectStatus "R4D43" )
				( pin "a"
					( attribute "PN" "1"
						( Origin gPackager )
					)
					( objectStatus "R4D43.1" )
				)
				( pin "b"
					( attribute "PN" "2"
						( Origin gPackager )
					)
					( objectStatus "R4D43.2" )
				)
			)
			( gate "@baseboard_fab2_lib.baseboard_fab2(sch_1):page213_i42"
				( attribute "BOM_COST" "PROC_VRD_PVCCIO_CPU1"
					( Origin gFrontEnd )
				)
				( attribute "CDS_LIB" "mstr_discrete"
					( Origin gPackager )
				)
				( attribute "CDS_LOCATION" "R4D64"
					( Origin gPackager )
				)
				( attribute "CDS_SEC" "1"
					( Origin gPackager )
				)
				( attribute "LOCATION" "R4D64"
					( Origin gFrontEnd )
				)
				( attribute "MATERIAL" "CHIP"
					( Origin gFrontEnd )
				)
				( attribute "PACK_TYPE" "0402"
					( Origin gFrontEnd )
				)
				( attribute "PART_NUMBER" "G21796-043"
					( Origin gFrontEnd )
				)
				( attribute "PHYS_PAGE" "213"
					( Origin gFrontEnd )
				)
				( attribute "ROOM" "PVCCIO_CPU1"
					( Origin gFrontEnd )
				)
				( attribute "ROT" "0"
					( Origin gFrontEnd )
				)
				( attribute "SEC" "1"
					( Origin gFrontEnd )
				)
				( attribute "SEC_TYPE" "0402"
					( Origin gFrontEnd )
				)
				( attribute "TOLERANCE" "1%"
					( Origin gFrontEnd )
				)
				( attribute "VALUE" "3.16K"
					( Origin gFrontEnd )
				)
				( attribute "VER" "2"
					( Origin gFrontEnd )
				)
				( attribute "WATTAGE" "1/16W"
					( Origin gFrontEnd )
				)
				( attribute "XY" "(-850,1325)"
					( Origin gFrontEnd )
				)
				( attribute "CHIPS_PART_NAME" "RES"
					( Origin gPackager )
				)
				( attribute "CDS_PART_NAME" "RES_0402-3.16K,1%,1/16W,CHIP,GA"
					( Origin gPackager )
				)
				( objectStatus "R4D64" )
				( pin "a"
					( attribute "PN" "1"
						( Origin gPackager )
					)
					( objectStatus "R4D64.1" )
				)
				( pin "b"
					( attribute "PN" "2"
						( Origin gPackager )
					)
					( objectStatus "R4D64.2" )
				)
			)
			( gate "@baseboard_fab2_lib.baseboard_fab2(sch_1):page213_i46"
				( attribute "CDS_LIB" "mstr_discrete"
					( Origin gPackager )
				)
				( attribute "CDS_LOCATION" "R4D51"
					( Origin gPackager )
				)
				( attribute "CDS_SEC" "1"
					( Origin gPackager )
				)
				( attribute "LOCATION" "R4D51"
					( Origin gFrontEnd )
				)
				( attribute "MATERIAL" "CHIP"
					( Origin gFrontEnd )
				)
				( attribute "PACK_TYPE" "0402"
					( Origin gFrontEnd )
				)
				( attribute "PART_NUMBER" "G21796-009"
					( Origin gFrontEnd )
				)
				( attribute "PHYS_PAGE" "213"
					( Origin gFrontEnd )
				)
				( attribute "ROOM" "PVCCIO_CPU1"
					( Origin gFrontEnd )
				)
				( attribute "ROT" "0"
					( Origin gFrontEnd )
				)
				( attribute "SEC" "1"
					( Origin gFrontEnd )
				)
				( attribute "SEC_TYPE" "0402"
					( Origin gFrontEnd )
				)
				( attribute "TOLERANCE" "1%"
					( Origin gFrontEnd )
				)
				( attribute "VALUE" "150.0"
					( Origin gFrontEnd )
				)
				( attribute "VER" "1"
					( Origin gFrontEnd )
				)
				( attribute "WATTAGE" "1/16W"
					( Origin gFrontEnd )
				)
				( attribute "XY" "(-1825,3925)"
					( Origin gFrontEnd )
				)
				( attribute "CHIPS_PART_NAME" "RES"
					( Origin gPackager )
				)
				( attribute "CDS_PART_NAME" "RES_0402-150.0,1%,1/16W,CHIP,GA"
					( Origin gPackager )
				)
				( objectStatus "R4D51" )
				( pin "a"
					( attribute "PN" "1"
						( Origin gPackager )
					)
					( objectStatus "R4D51.1" )
				)
				( pin "b"
					( attribute "PN" "2"
						( Origin gPackager )
					)
					( objectStatus "R4D51.2" )
				)
			)
			( gate "@baseboard_fab2_lib.baseboard_fab2(sch_1):page213_i63"
				( attribute "CDS_LIB" "mstr_discrete"
					( Origin gPackager )
				)
				( attribute "CDS_LOCATION" "R4D49"
					( Origin gPackager )
				)
				( attribute "CDS_SEC" "1"
					( Origin gPackager )
				)
				( attribute "LOCATION" "R4D49"
					( Origin gFrontEnd )
				)
				( attribute "MATERIAL" "CHIP"
					( Origin gFrontEnd )
				)
				( attribute "PACK_TYPE" "0402"
					( Origin gFrontEnd )
				)
				( attribute "PART_NUMBER" "G21796-026"
					( Origin gFrontEnd )
				)
				( attribute "PHYS_PAGE" "213"
					( Origin gFrontEnd )
				)
				( attribute "ROT" "0"
					( Origin gFrontEnd )
				)
				( attribute "SEC" "1"
					( Origin gPackager )
				)
				( attribute "TOLERANCE" "1%"
					( Origin gFrontEnd )
				)
				( attribute "VALUE" "1.00K"
					( Origin gFrontEnd )
				)
				( attribute "VER" "2"
					( Origin gFrontEnd )
				)
				( attribute "WATTAGE" "1/16W"
					( Origin gFrontEnd )
				)
				( attribute "XY" "(2175,4050)"
					( Origin gFrontEnd )
				)
				( attribute "CHIPS_PART_NAME" "RES"
					( Origin gPackager )
				)
				( attribute "CDS_PART_NAME" "RES_0402-1.00K,1%,1/16W,CHIP,GA"
					( Origin gPackager )
				)
				( objectStatus "R4D49" )
				( pin "a"
					( attribute "PN" "1"
						( Origin gPackager )
					)
					( objectStatus "R4D49.1" )
				)
				( pin "b"
					( attribute "PN" "2"
						( Origin gPackager )
					)
					( objectStatus "R4D49.2" )
				)
			)
			( gate "@baseboard_fab2_lib.baseboard_fab2(sch_1):page213_i65"
				( attribute "CDS_LIB" "mstr_discrete"
					( Origin gPackager )
				)
				( attribute "CDS_LOCATION" "R4E2"
					( Origin gPackager )
				)
				( attribute "CDS_SEC" "1"
					( Origin gPackager )
				)
				( attribute "LOCATION" "R4E2"
					( Origin gFrontEnd )
				)
				( attribute "MATERIAL" "CHIP"
					( Origin gFrontEnd )
				)
				( attribute "PACK_TYPE" "0402"
					( Origin gFrontEnd )
				)
				( attribute "PART_NUMBER" "G21796-043"
					( Origin gFrontEnd )
				)
				( attribute "PHYS_PAGE" "213"
					( Origin gFrontEnd )
				)
				( attribute "ROT" "0"
					( Origin gFrontEnd )
				)
				( attribute "SEC" "1"
					( Origin gPackager )
				)
				( attribute "TOLERANCE" "1%"
					( Origin gFrontEnd )
				)
				( attribute "VALUE" "3.16K"
					( Origin gFrontEnd )
				)
				( attribute "VER" "2"
					( Origin gFrontEnd )
				)
				( attribute "WATTAGE" "1/16W"
					( Origin gFrontEnd )
				)
				( attribute "XY" "(-525,1325)"
					( Origin gFrontEnd )
				)
				( attribute "CHIPS_PART_NAME" "RES"
					( Origin gPackager )
				)
				( attribute "CDS_PART_NAME" "RES_0402-3.16K,1%,1/16W,CHIP,GA"
					( Origin gPackager )
				)
				( objectStatus "R4E2" )
				( pin "a"
					( attribute "PN" "1"
						( Origin gPackager )
					)
					( objectStatus "R4E2.1" )
				)
				( pin "b"
					( attribute "PN" "2"
						( Origin gPackager )
					)
					( objectStatus "R4E2.2" )
				)
			)
			( gate "@baseboard_fab2_lib.baseboard_fab2(sch_1):page213_i73"
				( attribute "CDS_LIB" "mstr_discrete"
					( Origin gPackager )
				)
				( attribute "CDS_LOCATION" "C4D33"
					( Origin gPackager )
				)
				( attribute "CDS_SEC" "1"
					( Origin gPackager )
				)
				( attribute "LOCATION" "C4D33"
					( Origin gFrontEnd )
				)
				( attribute "MATERIAL" "X7R"
					( Origin gFrontEnd )
				)
				( attribute "PACK_TYPE" "0402LF"
					( Origin gFrontEnd )
				)
				( attribute "PART_NUMBER" "A36096-046"
					( Origin gFrontEnd )
				)
				( attribute "PHYS_PAGE" "213"
					( Origin gFrontEnd )
				)
				( attribute "ROOM" "PVCCIO_CPU1_VR"
					( Origin gFrontEnd )
				)
				( attribute "ROT" "0"
					( Origin gFrontEnd )
				)
				( attribute "SEC" "1"
					( Origin gFrontEnd )
				)
				( attribute "SEC_TYPE" "0402LF"
					( Origin gFrontEnd )
				)
				( attribute "TOLERANCE" "10%"
					( Origin gFrontEnd )
				)
				( attribute "VALUE" "1000PF"
					( Origin gFrontEnd )
				)
				( attribute "VER" "1"
					( Origin gFrontEnd )
				)
				( attribute "VOLTAGE" "50V"
					( Units "uVoltage" "V" 1.000000)
					( Origin gFrontEnd )
				)
				( attribute "XY" "(1750,2700)"
					( Origin gFrontEnd )
				)
				( attribute "CHIPS_PART_NAME" "CAP"
					( Origin gPackager )
				)
				( attribute "CDS_PART_NAME" "CAP_0402LF-1000PF,50V,10%,X7R,A"
					( Origin gPackager )
				)
				( objectStatus "C4D33" )
				( pin "a"
					( attribute "PN" "1"
						( Origin gPackager )
					)
					( objectStatus "C4D33.1" )
				)
				( pin "b"
					( attribute "PN" "2"
						( Origin gPackager )
					)
					( objectStatus "C4D33.2" )
				)
			)
			( gate "@baseboard_fab2_lib.baseboard_fab2(sch_1):page213_i83"
				( attribute "CDS_LIB" "mstr_discrete"
					( Origin gPackager )
				)
				( attribute "CDS_LOCATION" "C4D44"
					( Origin gPackager )
				)
				( attribute "CDS_SEC" "1"
					( Origin gPackager )
				)
				( attribute "LOCATION" "C4D44"
					( Origin gFrontEnd )
				)
				( attribute "MATERIAL" "X7R"
					( Origin gFrontEnd )
				)
				( attribute "PACK_TYPE" "0402LF"
					( Origin gFrontEnd )
				)
				( attribute "PART_NUMBER" "A36096-050"
					( Origin gFrontEnd )
				)
				( attribute "PHYS_PAGE" "213"
					( Origin gFrontEnd )
				)
				( attribute "ROOM" "PVCCIO_CPU1"
					( Origin gFrontEnd )
				)
				( attribute "ROT" "0"
					( Origin gFrontEnd )
				)
				( attribute "SEC" "1"
					( Origin gFrontEnd )
				)
				( attribute "SEC_TYPE" "0402LF"
					( Origin gFrontEnd )
				)
				( attribute "TOLERANCE" "10%"
					( Origin gFrontEnd )
				)
				( attribute "VALUE" "220PF"
					( Origin gFrontEnd )
				)
				( attribute "VER" "1"
					( Origin gFrontEnd )
				)
				( attribute "VOLTAGE" "50V"
					( Units "uVoltage" "V" 1.000000)
					( Origin gFrontEnd )
				)
				( attribute "XY" "(-2075,1725)"
					( Origin gFrontEnd )
				)
				( attribute "CHIPS_PART_NAME" "CAP"
					( Origin gPackager )
				)
				( attribute "CDS_PART_NAME" "CAP_0402LF-220PF,50V,10%,X7R,AA"
					( Origin gPackager )
				)
				( objectStatus "C4D44" )
				( pin "a"
					( attribute "PN" "1"
						( Origin gPackager )
					)
					( objectStatus "C4D44.1" )
				)
				( pin "b"
					( attribute "PN" "2"
						( Origin gPackager )
					)
					( objectStatus "C4D44.2" )
				)
			)
			( gate "@baseboard_fab2_lib.baseboard_fab2(sch_1):page213_i84"
				( attribute "CDS_LIB" "mstr_discrete"
					( Origin gPackager )
				)
				( attribute "CDS_LOCATION" "R4E7"
					( Origin gPackager )
				)
				( attribute "CDS_SEC" "1"
					( Origin gPackager )
				)
				( attribute "LOCATION" "R4E7"
					( Origin gFrontEnd )
				)
				( attribute "MATERIAL" "CHIP"
					( Origin gFrontEnd )
				)
				( attribute "PACK_TYPE" "0402"
					( Origin gFrontEnd )
				)
				( attribute "PART_NUMBER" "G21796-066"
					( Origin gFrontEnd )
				)
				( attribute "PHYS_PAGE" "213"
					( Origin gFrontEnd )
				)
				( attribute "ROOM" "PVCCIO_CPU1"
					( Origin gFrontEnd )
				)
				( attribute "ROT" "0"
					( Origin gFrontEnd )
				)
				( attribute "SEC" "1"
					( Origin gFrontEnd )
				)
				( attribute "SEC_TYPE" "0402"
					( Origin gFrontEnd )
				)
				( attribute "TOLERANCE" "1%"
					( Origin gFrontEnd )
				)
				( attribute "VALUE" "10.0"
					( Origin gFrontEnd )
				)
				( attribute "VER" "1"
					( Origin gFrontEnd )
				)
				( attribute "WATTAGE" "1/16W"
					( Origin gFrontEnd )
				)
				( attribute "XY" "(-2325,1925)"
					( Origin gFrontEnd )
				)
				( attribute "CHIPS_PART_NAME" "RES"
					( Origin gPackager )
				)
				( attribute "CDS_PART_NAME" "RES_0402-10.0,1%,1/16W,CHIP,G2A"
					( Origin gPackager )
				)
				( objectStatus "R4E7" )
				( pin "a"
					( attribute "PN" "1"
						( Origin gPackager )
					)
					( objectStatus "R4E7.1" )
				)
				( pin "b"
					( attribute "PN" "2"
						( Origin gPackager )
					)
					( objectStatus "R4E7.2" )
				)
			)
			( gate "@baseboard_fab2_lib.baseboard_fab2(sch_1):page213_i90"
				( attribute "CDS_LIB" "mstr_discrete"
					( Origin gPackager )
				)
				( attribute "CDS_LOCATION" "R6P41"
					( Origin gPackager )
				)
				( attribute "CDS_SEC" "1"
					( Origin gPackager )
				)
				( attribute "LOCATION" "R6P41"
					( Origin gFrontEnd )
				)
				( attribute "MATERIAL" "CHIP"
					( Origin gFrontEnd )
				)
				( attribute "PACK_TYPE" "0402"
					( Origin gFrontEnd )
				)
				( attribute "PART_NUMBER" "G21497-005"
					( Origin gFrontEnd )
				)
				( attribute "PHYS_PAGE" "213"
					( Origin gFrontEnd )
				)
				( attribute "ROOM" "PVCCIN_CPU0_VR"
					( Origin gFrontEnd )
				)
				( attribute "ROT" "0"
					( Origin gFrontEnd )
				)
				( attribute "SEC" "1"
					( Origin gPackager )
				)
				( attribute "TOLERANCE" "5%"
					( Origin gFrontEnd )
				)
				( attribute "VALUE" "0.0"
					( Origin gFrontEnd )
				)
				( attribute "VER" "1"
					( Origin gFrontEnd )
				)
				( attribute "WATTAGE" "1/16W"
					( Origin gFrontEnd )
				)
				( attribute "XY" "(-1925,3225)"
					( Origin gFrontEnd )
				)
				( attribute "CHIPS_PART_NAME" "RES"
					( Origin gPackager )
				)
				( attribute "CDS_PART_NAME" "RES_0402-0.0,5%,1/16W,CHIP,G21A"
					( Origin gPackager )
				)
				( objectStatus "R6P41" )
				( pin "a"
					( attribute "PN" "1"
						( Origin gPackager )
					)
					( objectStatus "R6P41.1" )
				)
				( pin "b"
					( attribute "PN" "2"
						( Origin gPackager )
					)
					( objectStatus "R6P41.2" )
				)
			)
			( gate "@baseboard_fab2_lib.baseboard_fab2(sch_1):page213_i91"
				( attribute "BOM_COST" "SM_CONTROLLER"
					( Origin gFrontEnd )
				)
				( attribute "CDS_LIB" "mstr_discrete"
					( Origin gPackager )
				)
				( attribute "CDS_LOCATION" "R6P40"
					( Origin gPackager )
				)
				( attribute "CDS_SEC" "1"
					( Origin gPackager )
				)
				( attribute "LOCATION" "R6P40"
					( Origin gFrontEnd )
				)
				( attribute "MATERIAL" "EMPTY"
					( Origin gFrontEnd )
				)
				( attribute "PACK_TYPE" "0402"
					( Origin gFrontEnd )
				)
				( attribute "PART_NUMBER" "G21796-010"
					( Origin gFrontEnd )
				)
				( attribute "PHYS_PAGE" "213"
					( Origin gFrontEnd )
				)
				( attribute "ROOM" "BMC"
					( Origin gFrontEnd )
				)
				( attribute "ROT" "0"
					( Origin gFrontEnd )
				)
				( attribute "SEC" "1"
					( Origin gPackager )
				)
				( attribute "TOLERANCE" "1%"
					( Origin gFrontEnd )
				)
				( attribute "VALUE" "100.0K"
					( Origin gFrontEnd )
				)
				( attribute "VER" "2"
					( Origin gFrontEnd )
				)
				( attribute "WATTAGE" "1/16W"
					( Origin gFrontEnd )
				)
				( attribute "XY" "(-1025,4275)"
					( Origin gFrontEnd )
				)
				( attribute "CHIPS_PART_NAME" "RES"
					( Origin gPackager )
				)
				( attribute "CDS_PART_NAME" "RES_0402-100.0K,1%,1/16W,EMPTYA"
					( Origin gPackager )
				)
				( objectStatus "R6P40" )
				( pin "a"
					( attribute "PN" "1"
						( Origin gPackager )
					)
					( objectStatus "R6P40.1" )
				)
				( pin "b"
					( attribute "PN" "2"
						( Origin gPackager )
					)
					( objectStatus "R6P40.2" )
				)
			)
			( gate "@baseboard_fab2_lib.baseboard_fab2(sch_1):page213_i94"
				( attribute "CDS_LIB" "mstr_discrete"
					( Origin gPackager )
				)
				( attribute "CDS_LOCATION" "R4D45"
					( Origin gPackager )
				)
				( attribute "CDS_SEC" "1"
					( Origin gPackager )
				)
				( attribute "LOCATION" "R4D45"
					( Origin gFrontEnd )
				)
				( attribute "MATERIAL" "CHIP"
					( Origin gFrontEnd )
				)
				( attribute "PACK_TYPE" "0402"
					( Origin gFrontEnd )
				)
				( attribute "PART_NUMBER" "G21497-005"
					( Origin gFrontEnd )
				)
				( attribute "PHYS_PAGE" "213"
					( Origin gFrontEnd )
				)
				( attribute "ROOM" "PVCCIN_CPU0_VR"
					( Origin gFrontEnd )
				)
				( attribute "ROT" "0"
					( Origin gFrontEnd )
				)
				( attribute "SEC" "1"
					( Origin gPackager )
				)
				( attribute "TOLERANCE" "5%"
					( Origin gFrontEnd )
				)
				( attribute "VALUE" "0.0"
					( Origin gFrontEnd )
				)
				( attribute "VER" "1"
					( Origin gFrontEnd )
				)
				( attribute "WATTAGE" "1/16W"
					( Origin gFrontEnd )
				)
				( attribute "XY" "(-2425,3675)"
					( Origin gFrontEnd )
				)
				( attribute "CHIPS_PART_NAME" "RES"
					( Origin gPackager )
				)
				( attribute "CDS_PART_NAME" "RES_0402-0.0,5%,1/16W,CHIP,G21A"
					( Origin gPackager )
				)
				( objectStatus "R4D45" )
				( pin "a"
					( attribute "PN" "1"
						( Origin gPackager )
					)
					( objectStatus "R4D45.1" )
				)
				( pin "b"
					( attribute "PN" "2"
						( Origin gPackager )
					)
					( objectStatus "R4D45.2" )
				)
			)
			( gate "@baseboard_fab2_lib.baseboard_fab2(sch_1):page213_i96"
				( attribute "CDS_LIB" "mstr_controller"
					( Origin gPackager )
				)
				( attribute "CDS_LMAN_SYM_OUTLINE" "-400,850,400,-850"
					( Origin gPackager )
				)
				( attribute "CDS_LOCATION" "EU4D5"
					( Origin gPackager )
				)
				( attribute "CDS_SEC" "1"
					( Origin gPackager )
				)
				( attribute "LOCATION" "EU4D5"
					( Origin gFrontEnd )
				)
				( attribute "MATERIAL" "IC"
					( Origin gFrontEnd )
				)
				( attribute "PACK_TYPE" "QFN"
					( Origin gFrontEnd )
				)
				( attribute "PART_NUMBER" "H89187-001"
					( Origin gFrontEnd )
				)
				( attribute "PHYS_PAGE" "213"
					( Origin gFrontEnd )
				)
				( attribute "ROT" "0"
					( Origin gFrontEnd )
				)
				( attribute "SEC" "1"
					( Origin gFrontEnd )
				)
				( attribute "SEC_TYPE" "QFN"
					( Origin gFrontEnd )
				)
				( attribute "VER" "1"
					( Origin gFrontEnd )
				)
				( attribute "XY" "(175,2825)"
					( Origin gFrontEnd )
				)
				( attribute "CHIPS_PART_NAME" "PXE1110B"
					( Origin gPackager )
				)
				( attribute "CDS_PART_NAME" "PXE1110B_QFN-IC,H89187-001"
					( Origin gPackager )
				)
				( objectStatus "EU4D5" )
				( pin "airef1"
					( attribute "PN" "21"
						( Origin gPackager )
					)
					( objectStatus "EU4D5.21" )
				)
				( pin "aisen1"
					( attribute "PN" "22"
						( Origin gPackager )
					)
					( objectStatus "EU4D5.22" )
				)
				( pin "apwm1"
					( attribute "PN" "5"
						( Origin gPackager )
					)
					( objectStatus "EU4D5.5" )
				)
				( pin "atsen"
					( attribute "PN" "35"
						( Origin gPackager )
					)
					( objectStatus "EU4D5.35" )
				)
				( pin "avref"
					( attribute "PN" "20"
						( Origin gPackager )
					)
					( objectStatus "EU4D5.20" )
				)
				( pin "avren"
					( attribute "PN" "10"
						( Origin gPackager )
					)
					( objectStatus "EU4D5.10" )
				)
				( pin "avrrdy"
					( attribute "PN" "9"
						( Origin gPackager )
					)
					( objectStatus "EU4D5.9" )
				)
				( pin "avsen"
					( attribute "PN" "19"
						( Origin gPackager )
					)
					( objectStatus "EU4D5.19" )
				)
				( pin "biref1"
					( attribute "PN" "25"
						( Origin gPackager )
					)
					( objectStatus "EU4D5.25" )
				)
				( pin "bisen1"
					( attribute "PN" "26"
						( Origin gPackager )
					)
					( objectStatus "EU4D5.26" )
				)
				( pin "bpwm1"
					( attribute "PN" "3"
						( Origin gPackager )
					)
					( objectStatus "EU4D5.3" )
				)
				( pin "btsen"
					( attribute "PN" "34"
						( Origin gPackager )
					)
					( objectStatus "EU4D5.34" )
				)
				( pin "bvref"
					( attribute "PN" "30"
						( Origin gPackager )
					)
					( objectStatus "EU4D5.30" )
				)
				( pin "bvsen"
					( attribute "PN" "29"
						( Origin gPackager )
					)
					( objectStatus "EU4D5.29" )
				)
				( pin "dnc(0)"
					( attribute "PN" "1"
						( Origin gPackager )
					)
					( objectStatus "EU4D5.1" )
				)
				( pin "dnc(1)"
					( attribute "PN" "2"
						( Origin gPackager )
					)
					( objectStatus "EU4D5.2" )
				)
				( pin "dnc(2)"
					( attribute "PN" "4"
						( Origin gPackager )
					)
					( objectStatus "EU4D5.4" )
				)
				( pin "dnc(3)"
					( attribute "PN" "24"
						( Origin gPackager )
					)
					( objectStatus "EU4D5.24" )
				)
				( pin "dnc(4)"
					( attribute "PN" "28"
						( Origin gPackager )
					)
					( objectStatus "EU4D5.28" )
				)
				( pin "gnd(0)"
					( attribute "PN" "27"
						( Origin gPackager )
					)
					( objectStatus "EU4D5.27" )
				)
				( pin "gnd(1)"
					( attribute "PN" "23"
						( Origin gPackager )
					)
					( objectStatus "EU4D5.23" )
				)
				( pin "iinsen"
					( attribute "PN" "38"
						( Origin gPackager )
					)
					( objectStatus "EU4D5.38" )
				)
				( pin "mp0"
					( attribute "PN" "13"
						( Origin gPackager )
					)
					( objectStatus "EU4D5.13" )
				)
				( pin "mp1"
					( attribute "PN" "14"
						( Origin gPackager )
					)
					( objectStatus "EU4D5.14" )
				)
				( pin "mp2"
					( attribute "PN" "18"
						( Origin gPackager )
					)
					( objectStatus "EU4D5.18" )
				)
				( pin "mp3"
					( attribute "PN" "31"
						( Origin gPackager )
					)
					( objectStatus "EU4D5.31" )
				)
				( pin "mp4"
					( attribute "PN" "32"
						( Origin gPackager )
					)
					( objectStatus "EU4D5.32" )
				)
				( pin "pinalrt_n"
					( attribute "PN" "12"
						( Origin gPackager )
					)
					( objectStatus "EU4D5.12" )
				)
				( pin "reset_n"
					( attribute "PN" "8"
						( Origin gPackager )
					)
					( objectStatus "EU4D5.8" )
				)
				( pin "scl"
					( attribute "PN" "7"
						( Origin gPackager )
					)
					( objectStatus "EU4D5.7" )
				)
				( pin "sda"
					( attribute "PN" "6"
						( Origin gPackager )
					)
					( objectStatus "EU4D5.6" )
				)
				( pin "thpad"
					( attribute "PN" "41"
						( Origin gPackager )
					)
					( objectStatus "EU4D5.41" )
				)
				( pin "valrt_n"
					( attribute "PN" "17"
						( Origin gPackager )
					)
					( objectStatus "EU4D5.17" )
				)
				( pin "vclk"
					( attribute "PN" "15"
						( Origin gPackager )
					)
					( objectStatus "EU4D5.15" )
				)
				( pin "vd12"
					( attribute "PN" "40"
						( Origin gPackager )
					)
					( objectStatus "EU4D5.40" )
				)
				( pin "vdd"
					( attribute "PN" "39"
						( Origin gPackager )
					)
					( objectStatus "EU4D5.39" )
				)
				( pin "vdio"
					( attribute "PN" "16"
						( Origin gPackager )
					)
					( objectStatus "EU4D5.16" )
				)
				( pin "vinsen"
					( attribute "PN" "37"
						( Origin gPackager )
					)
					( objectStatus "EU4D5.37" )
				)
				( pin "vrhot_n"
					( attribute "PN" "11"
						( Origin gPackager )
					)
					( objectStatus "EU4D5.11" )
				)
				( pin "xaddr1"
					( attribute "PN" "36"
						( Origin gPackager )
					)
					( objectStatus "EU4D5.36" )
				)
				( pin "xaddr2"
					( attribute "PN" "33"
						( Origin gPackager )
					)
					( objectStatus "EU4D5.33" )
				)
			)
			( gate "@baseboard_fab2_lib.baseboard_fab2(sch_1):page214_i8"
				( attribute "BOM_COST" "PROC_VRD_PVCCIO_CPU1"
					( Origin gFrontEnd )
				)
				( attribute "CDS_LIB" "mstr_discrete"
					( Origin gPackager )
				)
				( attribute "CDS_LOCATION" "C4E9"
					( Origin gPackager )
				)
				( attribute "CDS_SEC" "1"
					( Origin gPackager )
				)
				( attribute "LOCATION" "C4E9"
					( Origin gFrontEnd )
				)
				( attribute "MATERIAL" "X5R"
					( Origin gFrontEnd )
				)
				( attribute "PACK_TYPE" "1210"
					( Origin gFrontEnd )
				)
				( attribute "PART_NUMBER" "644066-127"
					( Origin gFrontEnd )
				)
				( attribute "PHYS_PAGE" "214"
					( Origin gFrontEnd )
				)
				( attribute "ROOM" "PVCCIO_CPU1"
					( Origin gFrontEnd )
				)
				( attribute "ROT" "2"
					( Origin gFrontEnd )
				)
				( attribute "SEC" "1"
					( Origin gPackager )
				)
				( attribute "TOLERANCE" "20%"
					( Origin gFrontEnd )
				)
				( attribute "VALUE" "100UF"
					( Origin gFrontEnd )
				)
				( attribute "VER" "1"
					( Origin gFrontEnd )
				)
				( attribute "VOLTAGE" "16V"
					( Units "uVoltage" "V" 1.000000)
					( Origin gFrontEnd )
				)
				( attribute "XY" "(1650,1900)"
					( Origin gFrontEnd )
				)
				( attribute "CHIPS_PART_NAME" "CAP"
					( Origin gPackager )
				)
				( attribute "CDS_PART_NAME" "CAP_1210-100UF,16V,20%,X5R,644A"
					( Origin gPackager )
				)
				( objectStatus "C4E9" )
				( pin "a"
					( attribute "PN" "1"
						( Origin gPackager )
					)
					( objectStatus "C4E9.1" )
				)
				( pin "b"
					( attribute "PN" "2"
						( Origin gPackager )
					)
					( objectStatus "C4E9.2" )
				)
			)
			( gate "@baseboard_fab2_lib.baseboard_fab2(sch_1):page214_i20"
				( attribute "BOM_COST" "PROC_VRD_PVCCIO_CPU1"
					( Origin gFrontEnd )
				)
				( attribute "CDS_LIB" "mstr_discrete"
					( Origin gPackager )
				)
				( attribute "CDS_LOCATION" "C4E7"
					( Origin gPackager )
				)
				( attribute "CDS_SEC" "1"
					( Origin gPackager )
				)
				( attribute "LOCATION" "C4E7"
					( Origin gFrontEnd )
				)
				( attribute "MATERIAL" "ALUM"
					( Origin gFrontEnd )
				)
				( attribute "PACK_TYPE" "3018"
					( Origin gFrontEnd )
				)
				( attribute "PART_NUMBER" "699013-049"
					( Origin gFrontEnd )
				)
				( attribute "PHYS_PAGE" "214"
					( Origin gFrontEnd )
				)
				( attribute "ROOM" "PVCCIO_CPU1"
					( Origin gFrontEnd )
				)
				( attribute "ROT" "2"
					( Origin gFrontEnd )
				)
				( attribute "SEC" "1"
					( Origin gFrontEnd )
				)
				( attribute "SEC_TYPE" "3018"
					( Origin gFrontEnd )
				)
				( attribute "TOLERANCE" "20%"
					( Origin gFrontEnd )
				)
				( attribute "VALUE" "470UF"
					( Origin gFrontEnd )
				)
				( attribute "VER" "1"
					( Origin gFrontEnd )
				)
				( attribute "VOLTAGE" "2.5V"
					( Units "uVoltage" "V" 1.000000)
					( Origin gFrontEnd )
				)
				( attribute "XY" "(3375,2200)"
					( Origin gFrontEnd )
				)
				( attribute "CHIPS_PART_NAME" "CAPP"
					( Origin gPackager )
				)
				( attribute "CDS_PART_NAME" "CAPP_3018-470UF,2.5V,20%,ALUM,A"
					( Origin gPackager )
				)
				( objectStatus "C4E7" )
				( pin "a"
					( attribute "PN" "1"
						( Origin gPackager )
					)
					( objectStatus "C4E7.1" )
				)
				( pin "b"
					( attribute "PN" "2"
						( Origin gPackager )
					)
					( objectStatus "C4E7.2" )
				)
			)
			( gate "@baseboard_fab2_lib.baseboard_fab2(sch_1):page214_i21"
				( attribute "BOM_COST" "PROC_VRD_PVCCIO_CPU1"
					( Origin gFrontEnd )
				)
				( attribute "CDS_LIB" "mstr_discrete"
					( Origin gPackager )
				)
				( attribute "CDS_LOCATION" "C6R12"
					( Origin gPackager )
				)
				( attribute "CDS_SEC" "1"
					( Origin gPackager )
				)
				( attribute "LOCATION" "C6R12"
					( Origin gFrontEnd )
				)
				( attribute "MATERIAL" "ALUM"
					( Origin gFrontEnd )
				)
				( attribute "PACK_TYPE" "3018"
					( Origin gFrontEnd )
				)
				( attribute "PART_NUMBER" "699013-049"
					( Origin gFrontEnd )
				)
				( attribute "PHYS_PAGE" "214"
					( Origin gFrontEnd )
				)
				( attribute "ROOM" "PVCCIO_CPU1"
					( Origin gFrontEnd )
				)
				( attribute "ROT" "2"
					( Origin gFrontEnd )
				)
				( attribute "SEC" "1"
					( Origin gFrontEnd )
				)
				( attribute "SEC_TYPE" "3018"
					( Origin gFrontEnd )
				)
				( attribute "TOLERANCE" "20%"
					( Origin gFrontEnd )
				)
				( attribute "VALUE" "470UF"
					( Origin gFrontEnd )
				)
				( attribute "VER" "1"
					( Origin gFrontEnd )
				)
				( attribute "VOLTAGE" "2.5V"
					( Units "uVoltage" "V" 1.000000)
					( Origin gFrontEnd )
				)
				( attribute "XY" "(2900,2200)"
					( Origin gFrontEnd )
				)
				( attribute "CHIPS_PART_NAME" "CAPP"
					( Origin gPackager )
				)
				( attribute "CDS_PART_NAME" "CAPP_3018-470UF,2.5V,20%,ALUM,A"
					( Origin gPackager )
				)
				( objectStatus "C6R12" )
				( pin "a"
					( attribute "PN" "1"
						( Origin gPackager )
					)
					( objectStatus "C6R12.1" )
				)
				( pin "b"
					( attribute "PN" "2"
						( Origin gPackager )
					)
					( objectStatus "C6R12.2" )
				)
			)
			( gate "@baseboard_fab2_lib.baseboard_fab2(sch_1):page214_i24"
				( attribute "BOM_COST" "PROC_VRD_PVCCIO_CPU1"
					( Origin gFrontEnd )
				)
				( attribute "CDS_LIB" "mstr_discrete"
					( Origin gPackager )
				)
				( attribute "CDS_LOCATION" "C6R5"
					( Origin gPackager )
				)
				( attribute "CDS_SEC" "1"
					( Origin gPackager )
				)
				( attribute "LOCATION" "C6R5"
					( Origin gFrontEnd )
				)
				( attribute "MATERIAL" "ALUM"
					( Origin gFrontEnd )
				)
				( attribute "PACK_TYPE" "3018"
					( Origin gFrontEnd )
				)
				( attribute "PART_NUMBER" "699013-049"
					( Origin gFrontEnd )
				)
				( attribute "PHYS_PAGE" "214"
					( Origin gFrontEnd )
				)
				( attribute "ROOM" "PVCCIO_CPU1"
					( Origin gFrontEnd )
				)
				( attribute "ROT" "2"
					( Origin gFrontEnd )
				)
				( attribute "SEC" "1"
					( Origin gFrontEnd )
				)
				( attribute "SEC_TYPE" "3018"
					( Origin gFrontEnd )
				)
				( attribute "TOLERANCE" "20%"
					( Origin gFrontEnd )
				)
				( attribute "VALUE" "470UF"
					( Origin gFrontEnd )
				)
				( attribute "VER" "1"
					( Origin gFrontEnd )
				)
				( attribute "VOLTAGE" "2.5V"
					( Units "uVoltage" "V" 1.000000)
					( Origin gFrontEnd )
				)
				( attribute "XY" "(2425,2200)"
					( Origin gFrontEnd )
				)
				( attribute "CHIPS_PART_NAME" "CAPP"
					( Origin gPackager )
				)
				( attribute "CDS_PART_NAME" "CAPP_3018-470UF,2.5V,20%,ALUM,A"
					( Origin gPackager )
				)
				( objectStatus "C6R5" )
				( pin "a"
					( attribute "PN" "1"
						( Origin gPackager )
					)
					( objectStatus "C6R5.1" )
				)
				( pin "b"
					( attribute "PN" "2"
						( Origin gPackager )
					)
					( objectStatus "C6R5.2" )
				)
			)
			( gate "@baseboard_fab2_lib.baseboard_fab2(sch_1):page214_i29"
				( attribute "BOM_COST" "PROC_VRD_PVCCIO_CPU1"
					( Origin gFrontEnd )
				)
				( attribute "CDS_LIB" "mstr_discrete"
					( Origin gPackager )
				)
				( attribute "CDS_LOCATION" "C4E8"
					( Origin gPackager )
				)
				( attribute "CDS_SEC" "1"
					( Origin gPackager )
				)
				( attribute "LOCATION" "C4E8"
					( Origin gFrontEnd )
				)
				( attribute "MATERIAL" "X5R"
					( Origin gFrontEnd )
				)
				( attribute "PACK_TYPE" "1210"
					( Origin gFrontEnd )
				)
				( attribute "PART_NUMBER" "644066-127"
					( Origin gFrontEnd )
				)
				( attribute "PHYS_PAGE" "214"
					( Origin gFrontEnd )
				)
				( attribute "ROOM" "PVCCIO_CPU1"
					( Origin gFrontEnd )
				)
				( attribute "ROT" "2"
					( Origin gFrontEnd )
				)
				( attribute "SEC" "1"
					( Origin gFrontEnd )
				)
				( attribute "SEC_TYPE" "1210"
					( Origin gFrontEnd )
				)
				( attribute "TOLERANCE" "20%"
					( Origin gFrontEnd )
				)
				( attribute "VALUE" "100UF"
					( Origin gFrontEnd )
				)
				( attribute "VER" "1"
					( Origin gFrontEnd )
				)
				( attribute "VOLTAGE" "16V"
					( Units "uVoltage" "V" 1.000000)
					( Origin gFrontEnd )
				)
				( attribute "XY" "(1275,1900)"
					( Origin gFrontEnd )
				)
				( attribute "CHIPS_PART_NAME" "CAP"
					( Origin gPackager )
				)
				( attribute "CDS_PART_NAME" "CAP_1210-100UF,16V,20%,X5R,644A"
					( Origin gPackager )
				)
				( objectStatus "C4E8" )
				( pin "a"
					( attribute "PN" "1"
						( Origin gPackager )
					)
					( objectStatus "C4E8.1" )
				)
				( pin "b"
					( attribute "PN" "2"
						( Origin gPackager )
					)
					( objectStatus "C4E8.2" )
				)
			)
			( gate "@baseboard_fab2_lib.baseboard_fab2(sch_1):page214_i31"
				( attribute "BOM_COST" "PROC_VRD_PVCCIO_CPU1"
					( Origin gFrontEnd )
				)
				( attribute "CDS_LIB" "mstr_discrete"
					( Origin gPackager )
				)
				( attribute "CDS_LOCATION" "C4E14"
					( Origin gPackager )
				)
				( attribute "CDS_SEC" "1"
					( Origin gPackager )
				)
				( attribute "LOCATION" "C4E14"
					( Origin gFrontEnd )
				)
				( attribute "MATERIAL" "X5R"
					( Origin gFrontEnd )
				)
				( attribute "PACK_TYPE" "1210"
					( Origin gFrontEnd )
				)
				( attribute "PART_NUMBER" "644066-127"
					( Origin gFrontEnd )
				)
				( attribute "PHYS_PAGE" "214"
					( Origin gFrontEnd )
				)
				( attribute "ROOM" "PVCCIO_CPU1"
					( Origin gFrontEnd )
				)
				( attribute "ROT" "0"
					( Origin gFrontEnd )
				)
				( attribute "SEC" "1"
					( Origin gFrontEnd )
				)
				( attribute "SEC_TYPE" "1210"
					( Origin gFrontEnd )
				)
				( attribute "TOLERANCE" "20%"
					( Origin gFrontEnd )
				)
				( attribute "VALUE" "100UF"
					( Origin gFrontEnd )
				)
				( attribute "VER" "1"
					( Origin gFrontEnd )
				)
				( attribute "VOLTAGE" "16V"
					( Units "uVoltage" "V" 1.000000)
					( Origin gFrontEnd )
				)
				( attribute "XY" "(700,1875)"
					( Origin gFrontEnd )
				)
				( attribute "CHIPS_PART_NAME" "CAP"
					( Origin gPackager )
				)
				( attribute "CDS_PART_NAME" "CAP_1210-100UF,16V,20%,X5R,644A"
					( Origin gPackager )
				)
				( objectStatus "C4E14" )
				( pin "a"
					( attribute "PN" "1"
						( Origin gPackager )
					)
					( objectStatus "C4E14.1" )
				)
				( pin "b"
					( attribute "PN" "2"
						( Origin gPackager )
					)
					( objectStatus "C4E14.2" )
				)
			)
			( gate "@baseboard_fab2_lib.baseboard_fab2(sch_1):page214_i65"
				( attribute "BOM_COST" "PROC_VRD_PVCCIO_CPU1"
					( Origin gFrontEnd )
				)
				( attribute "CDS_LIB" "dev_discrete"
					( Origin gPackager )
				)
				( attribute "CDS_LOCATION" "C7R1"
					( Origin gPackager )
				)
				( attribute "CDS_SEC" "1"
					( Origin gPackager )
				)
				( attribute "LOCATION" "C7R1"
					( Origin gFrontEnd )
				)
				( attribute "MATERIAL" "X6S"
					( Origin gFrontEnd )
				)
				( attribute "PACK_TYPE" "0603V"
					( Origin gFrontEnd )
				)
				( attribute "PART_NUMBER" "E15431-004"
					( Origin gFrontEnd )
				)
				( attribute "PHYS_PAGE" "214"
					( Origin gFrontEnd )
				)
				( attribute "ROOM" "PVCCIO_CPU1"
					( Origin gFrontEnd )
				)
				( attribute "ROT" "0"
					( Origin gFrontEnd )
				)
				( attribute "SEC" "1"
					( Origin gFrontEnd )
				)
				( attribute "SEC_TYPE" "0603V"
					( Origin gFrontEnd )
				)
				( attribute "TOLERANCE" "20%"
					( Origin gFrontEnd )
				)
				( attribute "VALUE" "22.0UF"
					( Origin gFrontEnd )
				)
				( attribute "VER" "1"
					( Origin gFrontEnd )
				)
				( attribute "VOLTAGE" "4V"
					( Units "uVoltage" "V" 1.000000)
					( Origin gFrontEnd )
				)
				( attribute "XY" "(3125,3000)"
					( Origin gFrontEnd )
				)
				( attribute "CHIPS_PART_NAME" "CAP_A"
					( Origin gPackager )
				)
				( attribute "CDS_PART_NAME" "CAP_A_0603V-22.0UF,4V,20%,X6S,A"
					( Origin gPackager )
				)
				( objectStatus "C7R1" )
				( pin "a"
					( attribute "PN" "1"
						( Origin gPackager )
					)
					( objectStatus "C7R1.1" )
				)
				( pin "b"
					( attribute "PN" "2"
						( Origin gPackager )
					)
					( objectStatus "C7R1.2" )
				)
			)
			( gate "@baseboard_fab2_lib.baseboard_fab2(sch_1):page214_i67"
				( attribute "CDS_LIB" "mstr_discrete"
					( Origin gPackager )
				)
				( attribute "CDS_LOCATION" "L4E2"
					( Origin gPackager )
				)
				( attribute "CDS_SEC" "1"
					( Origin gPackager )
				)
				( attribute "LOCATION" "L4E2"
					( Origin gFrontEnd )
				)
				( attribute "MATERIAL" "IND"
					( Origin gFrontEnd )
				)
				( attribute "PACK_TYPE" "SM"
					( Origin gFrontEnd )
				)
				( attribute "PART_NUMBER" "D92183-021"
					( Origin gFrontEnd )
				)
				( attribute "PHYS_PAGE" "214"
					( Origin gFrontEnd )
				)
				( attribute "ROOM" "PVCCIO_CPU1"
					( Origin gFrontEnd )
				)
				( attribute "ROT" "0"
					( Origin gFrontEnd )
				)
				( attribute "SEC" "1"
					( Origin gPackager )
				)
				( attribute "VALUE" "150NH"
					( Origin gFrontEnd )
				)
				( attribute "VER" "1"
					( Origin gFrontEnd )
				)
				( attribute "XY" "(2550,3175)"
					( Origin gFrontEnd )
				)
				( attribute "CHIPS_PART_NAME" "INDUCTOR"
					( Origin gPackager )
				)
				( attribute "CDS_PART_NAME" "INDUCTOR_SM-150NH,IND,D92183-0A"
					( Origin gPackager )
				)
				( objectStatus "L4E2" )
				( pin "ina"
					( attribute "PN" "1"
						( Origin gPackager )
					)
					( objectStatus "L4E2.1" )
				)
				( pin "inb"
					( attribute "PN" "2"
						( Origin gPackager )
					)
					( objectStatus "L4E2.2" )
				)
			)
			( gate "@baseboard_fab2_lib.baseboard_fab2(sch_1):page214_i71"
				( attribute "CDS_LIB" "mstr_discrete"
					( Origin gPackager )
				)
				( attribute "CDS_LOCATION" "R6R5"
					( Origin gPackager )
				)
				( attribute "CDS_SEC" "1"
					( Origin gPackager )
				)
				( attribute "LOCATION" "R6R5"
					( Origin gFrontEnd )
				)
				( attribute "MATERIAL" "CHIP"
					( Origin gFrontEnd )
				)
				( attribute "PACK_TYPE" "0402"
					( Origin gFrontEnd )
				)
				( attribute "PART_NUMBER" "G21796-090"
					( Origin gFrontEnd )
				)
				( attribute "PHYS_PAGE" "214"
					( Origin gFrontEnd )
				)
				( attribute "ROOM" "PVCCIO_CPU1"
					( Origin gFrontEnd )
				)
				( attribute "ROT" "0"
					( Origin gFrontEnd )
				)
				( attribute "SEC" "1"
					( Origin gFrontEnd )
				)
				( attribute "SEC_TYPE" "0402"
					( Origin gFrontEnd )
				)
				( attribute "TOLERANCE" "1%"
					( Origin gFrontEnd )
				)
				( attribute "VALUE" "1.0"
					( Origin gFrontEnd )
				)
				( attribute "VER" "1"
					( Origin gFrontEnd )
				)
				( attribute "WATTAGE" "1/16W"
					( Origin gFrontEnd )
				)
				( attribute "XY" "(-1875,4300)"
					( Origin gFrontEnd )
				)
				( attribute "CHIPS_PART_NAME" "RES"
					( Origin gPackager )
				)
				( attribute "CDS_PART_NAME" "RES_0402-1.0,1%,1/16W,CHIP,G21A"
					( Origin gPackager )
				)
				( objectStatus "R6R5" )
				( pin "a"
					( attribute "PN" "1"
						( Origin gPackager )
					)
					( objectStatus "R6R5.1" )
				)
				( pin "b"
					( attribute "PN" "2"
						( Origin gPackager )
					)
					( objectStatus "R6R5.2" )
				)
			)
			( gate "@baseboard_fab2_lib.baseboard_fab2(sch_1):page214_i73"
				( attribute "CDS_LIB" "mstr_discrete"
					( Origin gPackager )
				)
				( attribute "CDS_LOCATION" "C4E23"
					( Origin gPackager )
				)
				( attribute "CDS_SEC" "1"
					( Origin gPackager )
				)
				( attribute "LOCATION" "C4E23"
					( Origin gFrontEnd )
				)
				( attribute "MATERIAL" "X7R"
					( Origin gFrontEnd )
				)
				( attribute "PACK_TYPE" "0402"
					( Origin gFrontEnd )
				)
				( attribute "PART_NUMBER" "A36096-155"
					( Origin gFrontEnd )
				)
				( attribute "PHYS_PAGE" "214"
					( Origin gFrontEnd )
				)
				( attribute "ROOM" "PVCCIO_CPU1"
					( Origin gFrontEnd )
				)
				( attribute "ROT" "0"
					( Origin gFrontEnd )
				)
				( attribute "SEC" "1"
					( Origin gFrontEnd )
				)
				( attribute "SEC_TYPE" "0402"
					( Origin gFrontEnd )
				)
				( attribute "TOLERANCE" "10%"
					( Origin gFrontEnd )
				)
				( attribute "VALUE" "0.22UF"
					( Origin gFrontEnd )
				)
				( attribute "VER" "1"
					( Origin gFrontEnd )
				)
				( attribute "VOLTAGE" "16V"
					( Units "uVoltage" "V" 1.000000)
					( Origin gFrontEnd )
				)
				( attribute "XY" "(-1425,3750)"
					( Origin gFrontEnd )
				)
				( attribute "CHIPS_PART_NAME" "CAP"
					( Origin gPackager )
				)
				( attribute "CDS_PART_NAME" "CAP_0402-0.22UF,16V,10%,X7R,A3A"
					( Origin gPackager )
				)
				( objectStatus "C4E23" )
				( pin "a"
					( attribute "PN" "1"
						( Origin gPackager )
					)
					( objectStatus "C4E23.1" )
				)
				( pin "b"
					( attribute "PN" "2"
						( Origin gPackager )
					)
					( objectStatus "C4E23.2" )
				)
			)
			( gate "@baseboard_fab2_lib.baseboard_fab2(sch_1):page214_i74"
				( attribute "CDS_LIB" "dev_discrete"
					( Origin gPackager )
				)
				( attribute "CDS_LOCATION" "C4E28"
					( Origin gPackager )
				)
				( attribute "CDS_SEC" "1"
					( Origin gPackager )
				)
				( attribute "LOCATION" "C4E28"
					( Origin gFrontEnd )
				)
				( attribute "MATERIAL" "X6S"
					( Origin gFrontEnd )
				)
				( attribute "PACK_TYPE" "0402V"
					( Origin gFrontEnd )
				)
				( attribute "PART_NUMBER" "D97712-004"
					( Origin gFrontEnd )
				)
				( attribute "PHYS_PAGE" "214"
					( Origin gFrontEnd )
				)
				( attribute "ROOM" "PVCCIO_CPU1"
					( Origin gFrontEnd )
				)
				( attribute "ROT" "2"
					( Origin gFrontEnd )
				)
				( attribute "SEC" "1"
					( Origin gFrontEnd )
				)
				( attribute "SEC_TYPE" "0402V"
					( Origin gFrontEnd )
				)
				( attribute "TOLERANCE" "10%"
					( Origin gFrontEnd )
				)
				( attribute "VALUE" "1.0UF"
					( Origin gFrontEnd )
				)
				( attribute "VER" "1"
					( Origin gFrontEnd )
				)
				( attribute "VOLTAGE" "6.3V"
					( Units "uVoltage" "V" 1.000000)
					( Origin gFrontEnd )
				)
				( attribute "XY" "(-1575,3775)"
					( Origin gFrontEnd )
				)
				( attribute "CHIPS_PART_NAME" "CAP_A"
					( Origin gPackager )
				)
				( attribute "CDS_PART_NAME" "CAP_A_0402V-1.0UF,6.3V,10%,X6SA"
					( Origin gPackager )
				)
				( objectStatus "C4E28" )
				( pin "a"
					( attribute "PN" "1"
						( Origin gPackager )
					)
					( objectStatus "C4E28.1" )
				)
				( pin "b"
					( attribute "PN" "2"
						( Origin gPackager )
					)
					( objectStatus "C4E28.2" )
				)
			)
			( gate "@baseboard_fab2_lib.baseboard_fab2(sch_1):page214_i76"
				( attribute "CDS_LIB" "mstr_discrete"
					( Origin gPackager )
				)
				( attribute "CDS_LOCATION" "C4E22"
					( Origin gPackager )
				)
				( attribute "CDS_SEC" "1"
					( Origin gPackager )
				)
				( attribute "LOCATION" "C4E22"
					( Origin gFrontEnd )
				)
				( attribute "MATERIAL" "X6S"
					( Origin gFrontEnd )
				)
				( attribute "PACK_TYPE" "0402"
					( Origin gFrontEnd )
				)
				( attribute "PART_NUMBER" "D97712-011"
					( Origin gFrontEnd )
				)
				( attribute "PHYS_PAGE" "214"
					( Origin gFrontEnd )
				)
				( attribute "ROOM" "PVCCIO_CPU1"
					( Origin gFrontEnd )
				)
				( attribute "ROT" "0"
					( Origin gFrontEnd )
				)
				( attribute "SEC" "1"
					( Origin gFrontEnd )
				)
				( attribute "SEC_TYPE" "0402"
					( Origin gFrontEnd )
				)
				( attribute "TOLERANCE" "10%"
					( Origin gFrontEnd )
				)
				( attribute "VALUE" "1.0UF"
					( Origin gFrontEnd )
				)
				( attribute "VER" "1"
					( Origin gFrontEnd )
				)
				( attribute "VOLTAGE" "16V"
					( Units "uVoltage" "V" 1.000000)
					( Origin gFrontEnd )
				)
				( attribute "XY" "(-2125,3700)"
					( Origin gFrontEnd )
				)
				( attribute "CHIPS_PART_NAME" "CAP"
					( Origin gPackager )
				)
				( attribute "CDS_PART_NAME" "CAP_0402-1.0UF,16V,10%,X6S,D97A"
					( Origin gPackager )
				)
				( objectStatus "C4E22" )
				( pin "a"
					( attribute "PN" "1"
						( Origin gPackager )
					)
					( objectStatus "C4E22.1" )
				)
				( pin "b"
					( attribute "PN" "2"
						( Origin gPackager )
					)
					( objectStatus "C4E22.2" )
				)
			)
			( gate "@baseboard_fab2_lib.baseboard_fab2(sch_1):page214_i77"
				( attribute "CDS_LIB" "dev_discrete"
					( Origin gPackager )
				)
				( attribute "CDS_LOCATION" "C4E13"
					( Origin gPackager )
				)
				( attribute "CDS_SEC" "1"
					( Origin gPackager )
				)
				( attribute "LOCATION" "C4E13"
					( Origin gFrontEnd )
				)
				( attribute "MATERIAL" "X7R"
					( Origin gFrontEnd )
				)
				( attribute "PACK_TYPE" "0402V"
					( Origin gFrontEnd )
				)
				( attribute "PART_NUMBER" "A36096-030"
					( Origin gFrontEnd )
				)
				( attribute "PHYS_PAGE" "214"
					( Origin gFrontEnd )
				)
				( attribute "ROOM" "PVCCIO_CPU1"
					( Origin gFrontEnd )
				)
				( attribute "ROT" "0"
					( Origin gFrontEnd )
				)
				( attribute "SEC" "1"
					( Origin gFrontEnd )
				)
				( attribute "SEC_TYPE" "0402V"
					( Origin gFrontEnd )
				)
				( attribute "TOLERANCE" "10%"
					( Origin gFrontEnd )
				)
				( attribute "VALUE" "0.1UF"
					( Origin gFrontEnd )
				)
				( attribute "VER" "1"
					( Origin gFrontEnd )
				)
				( attribute "VOLTAGE" "16V"
					( Units "uVoltage" "V" 1.000000)
					( Origin gFrontEnd )
				)
				( attribute "XY" "(-2375,3725)"
					( Origin gFrontEnd )
				)
				( attribute "CHIPS_PART_NAME" "CAP_A"
					( Origin gPackager )
				)
				( attribute "CDS_PART_NAME" "CAP_A_0402V-0.1UF,16V,10%,X7R,A"
					( Origin gPackager )
				)
				( objectStatus "C4E13" )
				( pin "a"
					( attribute "PN" "1"
						( Origin gPackager )
					)
					( objectStatus "C4E13.1" )
				)
				( pin "b"
					( attribute "PN" "2"
						( Origin gPackager )
					)
					( objectStatus "C4E13.2" )
				)
			)
			( gate "@baseboard_fab2_lib.baseboard_fab2(sch_1):page214_i78"
				( attribute "CDS_LIB" "mstr_discrete"
					( Origin gPackager )
				)
				( attribute "CDS_LOCATION" "C4E18"
					( Origin gPackager )
				)
				( attribute "CDS_SEC" "1"
					( Origin gPackager )
				)
				( attribute "LOCATION" "C4E18"
					( Origin gFrontEnd )
				)
				( attribute "MATERIAL" "X7R"
					( Origin gFrontEnd )
				)
				( attribute "PACK_TYPE" "0402"
					( Origin gFrontEnd )
				)
				( attribute "PART_NUMBER" "A36096-104"
					( Origin gFrontEnd )
				)
				( attribute "PHYS_PAGE" "214"
					( Origin gFrontEnd )
				)
				( attribute "ROOM" "PVCCIO_CPU1"
					( Origin gFrontEnd )
				)
				( attribute "ROT" "2"
					( Origin gFrontEnd )
				)
				( attribute "SEC" "1"
					( Origin gFrontEnd )
				)
				( attribute "SEC_TYPE" "0402"
					( Origin gFrontEnd )
				)
				( attribute "SPOF" "TRUE"
					( Origin gFrontEnd )
				)
				( attribute "TOLERANCE" "10%"
					( Origin gFrontEnd )
				)
				( attribute "VALUE" "0.220UF"
					( Origin gFrontEnd )
				)
				( attribute "VER" "1"
					( Origin gFrontEnd )
				)
				( attribute "VOLTAGE" "16V"
					( Units "uVoltage" "V" 1.000000)
					( Origin gFrontEnd )
				)
				( attribute "XY" "(-1675,3125)"
					( Origin gFrontEnd )
				)
				( attribute "CHIPS_PART_NAME" "CAP"
					( Origin gPackager )
				)
				( attribute "CDS_PART_NAME" "CAP_0402-0.220UF,16V,10%,X7R,AA"
					( Origin gPackager )
				)
				( objectStatus "C4E18" )
				( pin "a"
					( attribute "PN" "1"
						( Origin gPackager )
					)
					( objectStatus "C4E18.1" )
				)
				( pin "b"
					( attribute "PN" "2"
						( Origin gPackager )
					)
					( objectStatus "C4E18.2" )
				)
			)
			( gate "@baseboard_fab2_lib.baseboard_fab2(sch_1):page214_i79"
				( attribute "CDS_LIB" "mstr_discrete"
					( Origin gPackager )
				)
				( attribute "CDS_LOCATION" "C4E15"
					( Origin gPackager )
				)
				( attribute "CDS_SEC" "1"
					( Origin gPackager )
				)
				( attribute "LOCATION" "C4E15"
					( Origin gFrontEnd )
				)
				( attribute "MATERIAL" "X6S"
					( Origin gFrontEnd )
				)
				( attribute "PACK_TYPE" "0402"
					( Origin gFrontEnd )
				)
				( attribute "PART_NUMBER" "D97712-011"
					( Origin gFrontEnd )
				)
				( attribute "PHYS_PAGE" "214"
					( Origin gFrontEnd )
				)
				( attribute "ROOM" "PVCCIO_CPU1"
					( Origin gFrontEnd )
				)
				( attribute "ROT" "0"
					( Origin gFrontEnd )
				)
				( attribute "SEC" "1"
					( Origin gFrontEnd )
				)
				( attribute "SEC_TYPE" "0402"
					( Origin gFrontEnd )
				)
				( attribute "TOLERANCE" "10%"
					( Origin gFrontEnd )
				)
				( attribute "VALUE" "1.0UF"
					( Origin gFrontEnd )
				)
				( attribute "VER" "1"
					( Origin gFrontEnd )
				)
				( attribute "VOLTAGE" "16V"
					( Units "uVoltage" "V" 1.000000)
					( Origin gFrontEnd )
				)
				( attribute "XY" "(-2600,3700)"
					( Origin gFrontEnd )
				)
				( attribute "CHIPS_PART_NAME" "CAP"
					( Origin gPackager )
				)
				( attribute "CDS_PART_NAME" "CAP_0402-1.0UF,16V,10%,X6S,D97A"
					( Origin gPackager )
				)
				( objectStatus "C4E15" )
				( pin "a"
					( attribute "PN" "1"
						( Origin gPackager )
					)
					( objectStatus "C4E15.1" )
				)
				( pin "b"
					( attribute "PN" "2"
						( Origin gPackager )
					)
					( objectStatus "C4E15.2" )
				)
			)
			( gate "@baseboard_fab2_lib.baseboard_fab2(sch_1):page214_i80"
				( attribute "CDS_LIB" "mstr_discrete"
					( Origin gPackager )
				)
				( attribute "CDS_LOCATION" "C6R14"
					( Origin gPackager )
				)
				( attribute "CDS_SEC" "1"
					( Origin gPackager )
				)
				( attribute "LOCATION" "C6R14"
					( Origin gFrontEnd )
				)
				( attribute "MATERIAL" "X6S"
					( Origin gFrontEnd )
				)
				( attribute "PACK_TYPE" "0805"
					( Origin gFrontEnd )
				)
				( attribute "PART_NUMBER" "C95333-007"
					( Origin gFrontEnd )
				)
				( attribute "PHYS_PAGE" "214"
					( Origin gFrontEnd )
				)
				( attribute "ROOM" "PVCCIO_CPU1"
					( Origin gFrontEnd )
				)
				( attribute "ROT" "0"
					( Origin gFrontEnd )
				)
				( attribute "SEC" "1"
					( Origin gFrontEnd )
				)
				( attribute "SEC_TYPE" "0805"
					( Origin gFrontEnd )
				)
				( attribute "TOLERANCE" "10%"
					( Origin gFrontEnd )
				)
				( attribute "VALUE" "10UF"
					( Origin gFrontEnd )
				)
				( attribute "VER" "1"
					( Origin gFrontEnd )
				)
				( attribute "VOLTAGE" "16V"
					( Units "uVoltage" "V" 1.000000)
					( Origin gFrontEnd )
				)
				( attribute "XY" "(-2825,3725)"
					( Origin gFrontEnd )
				)
				( attribute "CHIPS_PART_NAME" "CAP"
					( Origin gPackager )
				)
				( attribute "CDS_PART_NAME" "CAP_0805-10UF,16V,10%,X6S,C953A"
					( Origin gPackager )
				)
				( objectStatus "C6R14" )
				( pin "a"
					( attribute "PN" "1"
						( Origin gPackager )
					)
					( objectStatus "C6R14.1" )
				)
				( pin "b"
					( attribute "PN" "2"
						( Origin gPackager )
					)
					( objectStatus "C6R14.2" )
				)
			)
			( gate "@baseboard_fab2_lib.baseboard_fab2(sch_1):page214_i81"
				( attribute "CDS_LIB" "mstr_discrete"
					( Origin gPackager )
				)
				( attribute "CDS_LOCATION" "C6R10"
					( Origin gPackager )
				)
				( attribute "CDS_SEC" "1"
					( Origin gPackager )
				)
				( attribute "LOCATION" "C6R10"
					( Origin gFrontEnd )
				)
				( attribute "MATERIAL" "X6S"
					( Origin gFrontEnd )
				)
				( attribute "PACK_TYPE" "0805"
					( Origin gFrontEnd )
				)
				( attribute "PART_NUMBER" "C95333-007"
					( Origin gFrontEnd )
				)
				( attribute "PHYS_PAGE" "214"
					( Origin gFrontEnd )
				)
				( attribute "ROOM" "PVCCIO_CPU1"
					( Origin gFrontEnd )
				)
				( attribute "ROT" "0"
					( Origin gFrontEnd )
				)
				( attribute "SEC" "1"
					( Origin gFrontEnd )
				)
				( attribute "SEC_TYPE" "0805"
					( Origin gFrontEnd )
				)
				( attribute "TOLERANCE" "10%"
					( Origin gFrontEnd )
				)
				( attribute "VALUE" "10UF"
					( Origin gFrontEnd )
				)
				( attribute "VER" "1"
					( Origin gFrontEnd )
				)
				( attribute "VOLTAGE" "16V"
					( Units "uVoltage" "V" 1.000000)
					( Origin gFrontEnd )
				)
				( attribute "XY" "(-3050,3700)"
					( Origin gFrontEnd )
				)
				( attribute "CHIPS_PART_NAME" "CAP"
					( Origin gPackager )
				)
				( attribute "CDS_PART_NAME" "CAP_0805-10UF,16V,10%,X6S,C953A"
					( Origin gPackager )
				)
				( objectStatus "C6R10" )
				( pin "a"
					( attribute "PN" "1"
						( Origin gPackager )
					)
					( objectStatus "C6R10.1" )
				)
				( pin "b"
					( attribute "PN" "2"
						( Origin gPackager )
					)
					( objectStatus "C6R10.2" )
				)
			)
			( gate "@baseboard_fab2_lib.baseboard_fab2(sch_1):page214_i83"
				( attribute "CDS_LIB" "mstr_discrete"
					( Origin gPackager )
				)
				( attribute "CDS_LOCATION" "C6R8"
					( Origin gPackager )
				)
				( attribute "CDS_SEC" "1"
					( Origin gPackager )
				)
				( attribute "LOCATION" "C6R8"
					( Origin gFrontEnd )
				)
				( attribute "MATERIAL" "X6S"
					( Origin gFrontEnd )
				)
				( attribute "PACK_TYPE" "0805"
					( Origin gFrontEnd )
				)
				( attribute "PART_NUMBER" "C95333-007"
					( Origin gFrontEnd )
				)
				( attribute "PHYS_PAGE" "214"
					( Origin gFrontEnd )
				)
				( attribute "ROOM" "PVCCIO_CPU1"
					( Origin gFrontEnd )
				)
				( attribute "ROT" "0"
					( Origin gFrontEnd )
				)
				( attribute "SEC" "1"
					( Origin gFrontEnd )
				)
				( attribute "SEC_TYPE" "0805"
					( Origin gFrontEnd )
				)
				( attribute "TOLERANCE" "10%"
					( Origin gFrontEnd )
				)
				( attribute "VALUE" "10UF"
					( Origin gFrontEnd )
				)
				( attribute "VER" "1"
					( Origin gFrontEnd )
				)
				( attribute "VOLTAGE" "16V"
					( Units "uVoltage" "V" 1.000000)
					( Origin gFrontEnd )
				)
				( attribute "XY" "(-3275,3725)"
					( Origin gFrontEnd )
				)
				( attribute "CHIPS_PART_NAME" "CAP"
					( Origin gPackager )
				)
				( attribute "CDS_PART_NAME" "CAP_0805-10UF,16V,10%,X6S,C953A"
					( Origin gPackager )
				)
				( objectStatus "C6R8" )
				( pin "a"
					( attribute "PN" "1"
						( Origin gPackager )
					)
					( objectStatus "C6R8.1" )
				)
				( pin "b"
					( attribute "PN" "2"
						( Origin gPackager )
					)
					( objectStatus "C6R8.2" )
				)
			)
			( gate "@baseboard_fab2_lib.baseboard_fab2(sch_1):page214_i96"
				( attribute "BOM_COST" "PROC_VRD_VCCIO_CPU1"
					( Origin gFrontEnd )
				)
				( attribute "CDS_LIB" "dev_discrete"
					( Origin gPackager )
				)
				( attribute "CDS_LOCATION" "C3D27"
					( Origin gPackager )
				)
				( attribute "CDS_SEC" "1"
					( Origin gPackager )
				)
				( attribute "LOCATION" "C3D27"
					( Origin gFrontEnd )
				)
				( attribute "MATERIAL" "EMPTY"
					( Origin gFrontEnd )
				)
				( attribute "PACK_TYPE" "0402V"
					( Origin gFrontEnd )
				)
				( attribute "PART_NUMBER" "A36096-030"
					( Origin gFrontEnd )
				)
				( attribute "PHYS_PAGE" "214"
					( Origin gFrontEnd )
				)
				( attribute "ROOM" "PVCCIO_CPU1"
					( Origin gFrontEnd )
				)
				( attribute "ROT" "0"
					( Origin gFrontEnd )
				)
				( attribute "SEC" "1"
					( Origin gFrontEnd )
				)
				( attribute "SEC_TYPE" "0402V"
					( Origin gFrontEnd )
				)
				( attribute "TOLERANCE" "10%"
					( Origin gFrontEnd )
				)
				( attribute "VALUE" "0.1UF"
					( Origin gFrontEnd )
				)
				( attribute "VER" "1"
					( Origin gFrontEnd )
				)
				( attribute "VOLTAGE" "16V"
					( Units "uVoltage" "V" 1.000000)
					( Origin gFrontEnd )
				)
				( attribute "XY" "(-1725,1575)"
					( Origin gFrontEnd )
				)
				( attribute "CHIPS_PART_NAME" "CAP_A"
					( Origin gPackager )
				)
				( attribute "CDS_PART_NAME" "CAP_A_0402V-0.1UF,16V,10%,EMPTA"
					( Origin gPackager )
				)
				( objectStatus "C3D27" )
				( pin "a"
					( attribute "PN" "1"
						( Origin gPackager )
					)
					( objectStatus "C3D27.1" )
				)
				( pin "b"
					( attribute "PN" "2"
						( Origin gPackager )
					)
					( objectStatus "C3D27.2" )
				)
			)
			( gate "@baseboard_fab2_lib.baseboard_fab2(sch_1):page214_i101"
				( attribute "BOM_COST" "PROC_VRD_VCCIO_CPU1"
					( Origin gFrontEnd )
				)
				( attribute "CDS_LIB" "mstr_discrete"
					( Origin gPackager )
				)
				( attribute "CDS_LOCATION" "R3D28"
					( Origin gPackager )
				)
				( attribute "CDS_SEC" "1"
					( Origin gPackager )
				)
				( attribute "LOCATION" "R3D28"
					( Origin gFrontEnd )
				)
				( attribute "MATERIAL" "CHIP"
					( Origin gFrontEnd )
				)
				( attribute "PACK_TYPE" "0402"
					( Origin gFrontEnd )
				)
				( attribute "PART_NUMBER" "G21796-017"
					( Origin gFrontEnd )
				)
				( attribute "PHYS_PAGE" "214"
					( Origin gFrontEnd )
				)
				( attribute "ROOM" "PVCCIO_CPU1"
					( Origin gFrontEnd )
				)
				( attribute "ROT" "0"
					( Origin gFrontEnd )
				)
				( attribute "SEC" "1"
					( Origin gFrontEnd )
				)
				( attribute "SEC_TYPE" "0402"
					( Origin gFrontEnd )
				)
				( attribute "TOLERANCE" "1%"
					( Origin gFrontEnd )
				)
				( attribute "VALUE" "100.0"
					( Origin gFrontEnd )
				)
				( attribute "VER" "1"
					( Origin gFrontEnd )
				)
				( attribute "WATTAGE" "1/16W"
					( Origin gFrontEnd )
				)
				( attribute "XY" "(-500,1050)"
					( Origin gFrontEnd )
				)
				( attribute "CHIPS_PART_NAME" "RES"
					( Origin gPackager )
				)
				( attribute "CDS_PART_NAME" "RES_0402-100.0,1%,1/16W,CHIP,GA"
					( Origin gPackager )
				)
				( objectStatus "R3D28" )
				( pin "a"
					( attribute "PN" "1"
						( Origin gPackager )
					)
					( objectStatus "R3D28.1" )
				)
				( pin "b"
					( attribute "PN" "2"
						( Origin gPackager )
					)
					( objectStatus "R3D28.2" )
				)
			)
			( gate "@baseboard_fab2_lib.baseboard_fab2(sch_1):page214_i105"
				( attribute "BOM_COST" "PROC_VRD_VCCIO_CPU1"
					( Origin gFrontEnd )
				)
				( attribute "CDS_LIB" "mstr_discrete"
					( Origin gPackager )
				)
				( attribute "CDS_LOCATION" "R3E1"
					( Origin gPackager )
				)
				( attribute "CDS_SEC" "1"
					( Origin gPackager )
				)
				( attribute "LOCATION" "R3E1"
					( Origin gFrontEnd )
				)
				( attribute "MATERIAL" "CHIP"
					( Origin gFrontEnd )
				)
				( attribute "PACK_TYPE" "0402"
					( Origin gFrontEnd )
				)
				( attribute "PART_NUMBER" "G21796-017"
					( Origin gFrontEnd )
				)
				( attribute "PHYS_PAGE" "214"
					( Origin gFrontEnd )
				)
				( attribute "ROOM" "PVCCIO_CPU1"
					( Origin gFrontEnd )
				)
				( attribute "ROT" "0"
					( Origin gFrontEnd )
				)
				( attribute "SEC" "1"
					( Origin gFrontEnd )
				)
				( attribute "SEC_TYPE" "0402"
					( Origin gFrontEnd )
				)
				( attribute "TOLERANCE" "1%"
					( Origin gFrontEnd )
				)
				( attribute "VALUE" "100.0"
					( Origin gFrontEnd )
				)
				( attribute "VER" "1"
					( Origin gFrontEnd )
				)
				( attribute "WATTAGE" "1/16W"
					( Origin gFrontEnd )
				)
				( attribute "XY" "(-500,2250)"
					( Origin gFrontEnd )
				)
				( attribute "CHIPS_PART_NAME" "RES"
					( Origin gPackager )
				)
				( attribute "CDS_PART_NAME" "RES_0402-100.0,1%,1/16W,CHIP,GA"
					( Origin gPackager )
				)
				( objectStatus "R3E1" )
				( pin "a"
					( attribute "PN" "1"
						( Origin gPackager )
					)
					( objectStatus "R3E1.1" )
				)
				( pin "b"
					( attribute "PN" "2"
						( Origin gPackager )
					)
					( objectStatus "R3E1.2" )
				)
			)
			( gate "@baseboard_fab2_lib.baseboard_fab2(sch_1):page214_i108"
				( attribute "BOM_COST" "PROC_VRD_PVCCIO_CPU1"
					( Origin gFrontEnd )
				)
				( attribute "CDS_LIB" "dev_discrete"
					( Origin gPackager )
				)
				( attribute "CDS_LOCATION" "C3E1"
					( Origin gPackager )
				)
				( attribute "CDS_SEC" "1"
					( Origin gPackager )
				)
				( attribute "LOCATION" "C3E1"
					( Origin gFrontEnd )
				)
				( attribute "MATERIAL" "X6S"
					( Origin gFrontEnd )
				)
				( attribute "PACK_TYPE" "0603V"
					( Origin gFrontEnd )
				)
				( attribute "PART_NUMBER" "E15431-004"
					( Origin gFrontEnd )
				)
				( attribute "PHYS_PAGE" "214"
					( Origin gFrontEnd )
				)
				( attribute "REUSE_ID" "281"
					( Origin gFrontEnd )
				)
				( attribute "ROOM" "PVCCIO_CPU1"
					( Origin gFrontEnd )
				)
				( attribute "ROT" "0"
					( Origin gFrontEnd )
				)
				( attribute "SEC" "1"
					( Origin gPackager )
				)
				( attribute "TOLERANCE" "20%"
					( Origin gFrontEnd )
				)
				( attribute "VALUE" "22.0UF"
					( Origin gFrontEnd )
				)
				( attribute "VER" "1"
					( Origin gFrontEnd )
				)
				( attribute "VOLTAGE" "4V"
					( Units "uVoltage" "V" 1.000000)
					( Origin gFrontEnd )
				)
				( attribute "XY" "(3575,3000)"
					( Origin gFrontEnd )
				)
				( attribute "CHIPS_PART_NAME" "CAP_A"
					( Origin gPackager )
				)
				( attribute "CDS_PART_NAME" "CAP_A_0603V-22.0UF,4V,20%,X6S,A"
					( Origin gPackager )
				)
				( objectStatus "C3E1" )
				( pin "a"
					( attribute "PN" "1"
						( Origin gPackager )
					)
					( objectStatus "C3E1.1" )
				)
				( pin "b"
					( attribute "PN" "2"
						( Origin gPackager )
					)
					( objectStatus "C3E1.2" )
				)
			)
			( gate "@baseboard_fab2_lib.baseboard_fab2(sch_1):page214_i109"
				( attribute "CDS_LIB" "mstr_discrete"
					( Origin gPackager )
				)
				( attribute "CDS_LOCATION" "R7R1"
					( Origin gPackager )
				)
				( attribute "CDS_SEC" "1"
					( Origin gPackager )
				)
				( attribute "LOCATION" "R7R1"
					( Origin gFrontEnd )
				)
				( attribute "MATERIAL" "CHIP"
					( Origin gFrontEnd )
				)
				( attribute "PACK_TYPE" "0402"
					( Origin gFrontEnd )
				)
				( attribute "PART_NUMBER" "G21796-208"
					( Origin gFrontEnd )
				)
				( attribute "PHYS_PAGE" "214"
					( Origin gFrontEnd )
				)
				( attribute "ROT" "0"
					( Origin gFrontEnd )
				)
				( attribute "SEC" "1"
					( Origin gPackager )
				)
				( attribute "TOLERANCE" "1.0%"
					( Origin gFrontEnd )
				)
				( attribute "VALUE" "51.1"
					( Origin gFrontEnd )
				)
				( attribute "VER" "2"
					( Origin gFrontEnd )
				)
				( attribute "WATTAGE" "1/16W"
					( Origin gFrontEnd )
				)
				( attribute "XY" "(3875,2975)"
					( Origin gFrontEnd )
				)
				( attribute "CHIPS_PART_NAME" "RES"
					( Origin gPackager )
				)
				( attribute "CDS_PART_NAME" "RES_0402-51.1,1.0%,1/16W,CHIP,A"
					( Origin gPackager )
				)
				( objectStatus "R7R1" )
				( pin "a"
					( attribute "PN" "1"
						( Origin gPackager )
					)
					( objectStatus "R7R1.1" )
				)
				( pin "b"
					( attribute "PN" "2"
						( Origin gPackager )
					)
					( objectStatus "R7R1.2" )
				)
			)
			( gate "@baseboard_fab2_lib.baseboard_fab2(sch_1):page214_i126"
				( attribute "CDS_LIB" "mstr_discrete"
					( Origin gPackager )
				)
				( attribute "CDS_LOCATION" "EU4E2"
					( Origin gPackager )
				)
				( attribute "CDS_SEC" "1"
					( Origin gPackager )
				)
				( attribute "LOCATION" "EU4E2"
					( Origin gFrontEnd )
				)
				( attribute "MATERIAL" "IC"
					( Origin gFrontEnd )
				)
				( attribute "NO_XNET_CONNECTION" "1"
					( Origin gFrontEnd )
				)
				( attribute "PACK_TYPE" "SM"
					( Origin gFrontEnd )
				)
				( attribute "PART_NUMBER" "H73684-001"
					( Origin gFrontEnd )
				)
				( attribute "PHYS_PAGE" "214"
					( Origin gFrontEnd )
				)
				( attribute "ROT" "0"
					( Origin gFrontEnd )
				)
				( attribute "SEC" "1"
					( Origin gFrontEnd )
				)
				( attribute "SEC_TYPE" "SM"
					( Origin gFrontEnd )
				)
				( attribute "VALUE" "IR35412"
					( Origin gFrontEnd )
				)
				( attribute "VER" "1"
					( Origin gFrontEnd )
				)
				( attribute "XY" "(850,3475)"
					( Origin gFrontEnd )
				)
				( attribute "CHIPS_PART_NAME" "IR354XX"
					( Origin gPackager )
				)
				( attribute "CDS_PART_NAME" "IR354XX_SM-IR35412,IC,H73684-0A"
					( Origin gPackager )
				)
				( objectStatus "EU4E2" )
				( pin "boost"
					( attribute "PN" "33"
						( Origin gPackager )
					)
					( objectStatus "EU4E2.33" )
				)
				( pin "en"
					( attribute "PN" "35"
						( Origin gPackager )
					)
					( objectStatus "EU4E2.35" )
				)
				( pin "gl(0)"
					( attribute "PN" "6"
						( Origin gPackager )
					)
					( objectStatus "EU4E2.6" )
				)
				( pin "gl(1)"
					( attribute "PN" "41"
						( Origin gPackager )
					)
					( objectStatus "EU4E2.41" )
				)
				( pin "iout"
					( attribute "PN" "38"
						( Origin gPackager )
					)
					( objectStatus "EU4E2.38" )
				)
				( pin "lgnd"
					( attribute "PN" "2"
						( Origin gPackager )
					)
					( objectStatus "EU4E2.2" )
				)
				( pin "nc"
					( attribute "PN" "31"
						( Origin gPackager )
					)
					( objectStatus "EU4E2.31" )
				)
				( pin "ocset"
					( attribute "PN" "37"
						( Origin gPackager )
					)
					( objectStatus "EU4E2.37" )
				)
				( pin "pgnd(0)"
					( attribute "PN" "5"
						( Origin gPackager )
					)
					( objectStatus "EU4E2.5" )
				)
				( pin "pgnd(1)"
					( attribute "PN" "7"
						( Origin gPackager )
					)
					( objectStatus "EU4E2.7" )
				)
				( pin "pgnd(2)"
					( attribute "PN" "40"
						( Origin gPackager )
					)
					( objectStatus "EU4E2.40" )
				)
				( pin "phase"
					( attribute "PN" "32"
						( Origin gPackager )
					)
					( objectStatus "EU4E2.32" )
				)
				( pin "pwm"
					( attribute "PN" "34"
						( Origin gPackager )
					)
					( objectStatus "EU4E2.34" )
				)
				( pin "refin"
					( attribute "PN" "39"
						( Origin gPackager )
					)
					( objectStatus "EU4E2.39" )
				)
				( pin "sw"
					( attribute "PN" "10"
						( Origin gPackager )
					)
					( objectStatus "EU4E2.10" )
				)
				( pin "tout_flt"
					( attribute "PN" "36"
						( Origin gPackager )
					)
					( objectStatus "EU4E2.36" )
				)
				( pin "vcc"
					( attribute "PN" "3"
						( Origin gPackager )
					)
					( objectStatus "EU4E2.3" )
				)
				( pin "vdrv"
					( attribute "PN" "4"
						( Origin gPackager )
					)
					( objectStatus "EU4E2.4" )
				)
				( pin "vin(0)"
					( attribute "PN" "25"
						( Origin gPackager )
					)
					( objectStatus "EU4E2.25" )
				)
				( pin "vin(1)"
					( attribute "PN" "30"
						( Origin gPackager )
					)
					( objectStatus "EU4E2.30" )
				)
				( pin "vos"
					( attribute "PN" "1"
						( Origin gPackager )
					)
					( objectStatus "EU4E2.1" )
				)
			)
			( gate "@baseboard_fab2_lib.baseboard_fab2(sch_1):page214_i127"
				( attribute "CDS_LIB" "mstr_discrete"
					( Origin gPackager )
				)
				( attribute "CDS_LOCATION" "R4E21"
					( Origin gPackager )
				)
				( attribute "CDS_SEC" "1"
					( Origin gPackager )
				)
				( attribute "LOCATION" "R4E21"
					( Origin gFrontEnd )
				)
				( attribute "MATERIAL" "EMPTY"
					( Origin gFrontEnd )
				)
				( attribute "PACK_TYPE" "0402"
					( Origin gFrontEnd )
				)
				( attribute "PART_NUMBER" "G21796-187"
					( Origin gFrontEnd )
				)
				( attribute "PHYS_PAGE" "214"
					( Origin gFrontEnd )
				)
				( attribute "ROT" "0"
					( Origin gFrontEnd )
				)
				( attribute "SEC" "1"
					( Origin gPackager )
				)
				( attribute "TOLERANCE" "1%"
					( Origin gFrontEnd )
				)
				( attribute "VALUE" "68.1K"
					( Origin gFrontEnd )
				)
				( attribute "VER" "2"
					( Origin gFrontEnd )
				)
				( attribute "WATTAGE" "1/16W"
					( Origin gFrontEnd )
				)
				( attribute "XY" "(3175,3625)"
					( Origin gFrontEnd )
				)
				( attribute "CHIPS_PART_NAME" "RES"
					( Origin gPackager )
				)
				( attribute "CDS_PART_NAME" "RES_0402-68.1K,1%,1/16W,EMPTY,A"
					( Origin gPackager )
				)
				( objectStatus "R4E21" )
				( pin "a"
					( attribute "PN" "1"
						( Origin gPackager )
					)
					( objectStatus "R4E21.1" )
				)
				( pin "b"
					( attribute "PN" "2"
						( Origin gPackager )
					)
					( objectStatus "R4E21.2" )
				)
			)
			( gate "@baseboard_fab2_lib.baseboard_fab2(sch_1):page214_i129"
				( attribute "CDS_LIB" "mstr_misc"
					( Origin gPackager )
				)
				( attribute "CDS_LOCATION" "SH3D2"
					( Origin gPackager )
				)
				( attribute "CDS_SEC" "1"
					( Origin gPackager )
				)
				( attribute "LOCATION" "SH3D2"
					( Origin gFrontEnd )
				)
				( attribute "MATERIAL" "EMPTY"
					( Origin gFrontEnd )
				)
				( attribute "PACK_TYPE" "SH0201"
					( Origin gFrontEnd )
				)
				( attribute "PART_NUMBER" "N_A"
					( Origin gFrontEnd )
				)
				( attribute "PHYS_PAGE" "214"
					( Origin gFrontEnd )
				)
				( attribute "PIN_SHORT" "A:B"
					( Origin gFrontEnd )
				)
				( attribute "ROT" "0"
					( Origin gFrontEnd )
				)
				( attribute "SEC" "1"
					( Origin gFrontEnd )
				)
				( attribute "SEC_TYPE" "SH0201"
					( Origin gFrontEnd )
				)
				( attribute "VER" "1"
					( Origin gFrontEnd )
				)
				( attribute "XY" "(-1125,1750)"
					( Origin gFrontEnd )
				)
				( attribute "CHIPS_PART_NAME" "SHUNT"
					( Origin gPackager )
				)
				( attribute "CDS_PART_NAME" "SHUNT_SH0201-EMPTY,N_A"
					( Origin gPackager )
				)
				( objectStatus "SH3D2" )
				( pin "a"
					( attribute "PN" "1"
						( Origin gPackager )
					)
					( objectStatus "SH3D2.1" )
				)
				( pin "b"
					( attribute "PN" "2"
						( Origin gPackager )
					)
					( objectStatus "SH3D2.2" )
				)
			)
			( gate "@baseboard_fab2_lib.baseboard_fab2(sch_1):page214_i130"
				( attribute "CDS_LIB" "mstr_misc"
					( Origin gPackager )
				)
				( attribute "CDS_LOCATION" "SH3D1"
					( Origin gPackager )
				)
				( attribute "CDS_SEC" "1"
					( Origin gPackager )
				)
				( attribute "LOCATION" "SH3D1"
					( Origin gFrontEnd )
				)
				( attribute "MATERIAL" "EMPTY"
					( Origin gFrontEnd )
				)
				( attribute "PACK_TYPE" "SH0201"
					( Origin gFrontEnd )
				)
				( attribute "PART_NUMBER" "N_A"
					( Origin gFrontEnd )
				)
				( attribute "PHYS_PAGE" "214"
					( Origin gFrontEnd )
				)
				( attribute "PIN_SHORT" "A:B"
					( Origin gFrontEnd )
				)
				( attribute "ROT" "0"
					( Origin gFrontEnd )
				)
				( attribute "SEC" "1"
					( Origin gFrontEnd )
				)
				( attribute "SEC_TYPE" "SH0201"
					( Origin gFrontEnd )
				)
				( attribute "VER" "1"
					( Origin gFrontEnd )
				)
				( attribute "XY" "(-1125,1300)"
					( Origin gFrontEnd )
				)
				( attribute "CHIPS_PART_NAME" "SHUNT"
					( Origin gPackager )
				)
				( attribute "CDS_PART_NAME" "SHUNT_SH0201-EMPTY,N_A"
					( Origin gPackager )
				)
				( objectStatus "SH3D1" )
				( pin "a"
					( attribute "PN" "1"
						( Origin gPackager )
					)
					( objectStatus "SH3D1.1" )
				)
				( pin "b"
					( attribute "PN" "2"
						( Origin gPackager )
					)
					( objectStatus "SH3D1.2" )
				)
			)
			( gate "@baseboard_fab2_lib.baseboard_fab2(sch_1):page215_i295"
				( attribute "CDS_LIB" "mstr_discrete"
					( Origin gPackager )
				)
				( attribute "CDS_LOCATION" "R3U2"
					( Origin gPackager )
				)
				( attribute "CDS_SEC" "1"
					( Origin gPackager )
				)
				( attribute "LOCATION" "R3U2"
					( Origin gFrontEnd )
				)
				( attribute "MATERIAL" "CHIP"
					( Origin gFrontEnd )
				)
				( attribute "PACK_TYPE" "0402"
					( Origin gFrontEnd )
				)
				( attribute "PART_NUMBER" "G21796-017"
					( Origin gFrontEnd )
				)
				( attribute "PHYS_PAGE" "215"
					( Origin gFrontEnd )
				)
				( attribute "ROOM" "VDDQ_ABC_PWR_VR"
					( Origin gFrontEnd )
				)
				( attribute "ROT" "0"
					( Origin gFrontEnd )
				)
				( attribute "SEC" "1"
					( Origin gFrontEnd )
				)
				( attribute "SEC_TYPE" "0402"
					( Origin gFrontEnd )
				)
				( attribute "TOLERANCE" "1%"
					( Origin gFrontEnd )
				)
				( attribute "VALUE" "100.0"
					( Origin gFrontEnd )
				)
				( attribute "VER" "2"
					( Origin gFrontEnd )
				)
				( attribute "WATTAGE" "1/16W"
					( Origin gFrontEnd )
				)
				( attribute "XY" "(4100,2925)"
					( Origin gFrontEnd )
				)
				( attribute "CHIPS_PART_NAME" "RES"
					( Origin gPackager )
				)
				( attribute "CDS_PART_NAME" "RES_0402-100.0,1%,1/16W,CHIP,GA"
					( Origin gPackager )
				)
				( objectStatus "R3U2" )
				( pin "a"
					( attribute "PN" "1"
						( Origin gPackager )
					)
					( objectStatus "R3U2.1" )
				)
				( pin "b"
					( attribute "PN" "2"
						( Origin gPackager )
					)
					( objectStatus "R3U2.2" )
				)
			)
			( gate "@baseboard_fab2_lib.baseboard_fab2(sch_1):page215_i296"
				( attribute "CDS_LIB" "mstr_discrete"
					( Origin gPackager )
				)
				( attribute "CDS_LOCATION" "R7F24"
					( Origin gPackager )
				)
				( attribute "CDS_SEC" "1"
					( Origin gPackager )
				)
				( attribute "LOCATION" "R7F24"
					( Origin gFrontEnd )
				)
				( attribute "MATERIAL" "CHIP"
					( Origin gFrontEnd )
				)
				( attribute "PACK_TYPE" "0402"
					( Origin gFrontEnd )
				)
				( attribute "PART_NUMBER" "G21796-250"
					( Origin gFrontEnd )
				)
				( attribute "PHYS_PAGE" "215"
					( Origin gFrontEnd )
				)
				( attribute "ROOM" "VDDQ_ABC_PWR_VR"
					( Origin gFrontEnd )
				)
				( attribute "ROT" "0"
					( Origin gFrontEnd )
				)
				( attribute "SEC" "1"
					( Origin gFrontEnd )
				)
				( attribute "SEC_TYPE" "0402"
					( Origin gFrontEnd )
				)
				( attribute "TOLERANCE" "1.0%"
					( Origin gFrontEnd )
				)
				( attribute "VALUE" "22.1"
					( Origin gFrontEnd )
				)
				( attribute "VER" "1"
					( Origin gFrontEnd )
				)
				( attribute "WATTAGE" "1/16W"
					( Origin gFrontEnd )
				)
				( attribute "XY" "(3500,2650)"
					( Origin gFrontEnd )
				)
				( attribute "CHIPS_PART_NAME" "RES"
					( Origin gPackager )
				)
				( attribute "CDS_PART_NAME" "RES_0402-22.1,1.0%,1/16W,CHIP,A"
					( Origin gPackager )
				)
				( objectStatus "R7F24" )
				( pin "a"
					( attribute "PN" "1"
						( Origin gPackager )
					)
					( objectStatus "R7F24.1" )
				)
				( pin "b"
					( attribute "PN" "2"
						( Origin gPackager )
					)
					( objectStatus "R7F24.2" )
				)
			)
			( gate "@baseboard_fab2_lib.baseboard_fab2(sch_1):page215_i297"
				( attribute "CDS_LIB" "mstr_discrete"
					( Origin gPackager )
				)
				( attribute "CDS_LOCATION" "R7F23"
					( Origin gPackager )
				)
				( attribute "CDS_SEC" "1"
					( Origin gPackager )
				)
				( attribute "LOCATION" "R7F23"
					( Origin gFrontEnd )
				)
				( attribute "MATERIAL" "CHIP"
					( Origin gFrontEnd )
				)
				( attribute "PACK_TYPE" "0402"
					( Origin gFrontEnd )
				)
				( attribute "PART_NUMBER" "G21796-074"
					( Origin gFrontEnd )
				)
				( attribute "PHYS_PAGE" "215"
					( Origin gFrontEnd )
				)
				( attribute "ROT" "0"
					( Origin gFrontEnd )
				)
				( attribute "SEC" "1"
					( Origin gPackager )
				)
				( attribute "TOLERANCE" "1%"
					( Origin gFrontEnd )
				)
				( attribute "VALUE" "33.2"
					( Origin gFrontEnd )
				)
				( attribute "VER" "1"
					( Origin gFrontEnd )
				)
				( attribute "WATTAGE" "1/16W"
					( Origin gFrontEnd )
				)
				( attribute "XY" "(3425,2550)"
					( Origin gFrontEnd )
				)
				( attribute "CHIPS_PART_NAME" "RES"
					( Origin gPackager )
				)
				( attribute "CDS_PART_NAME" "RES_0402-33.2,1%,1/16W,CHIP,G2A"
					( Origin gPackager )
				)
				( objectStatus "R7F23" )
				( pin "a"
					( attribute "PN" "1"
						( Origin gPackager )
					)
					( objectStatus "R7F23.1" )
				)
				( pin "b"
					( attribute "PN" "2"
						( Origin gPackager )
					)
					( objectStatus "R7F23.2" )
				)
			)
			( gate "@baseboard_fab2_lib.baseboard_fab2(sch_1):page215_i298"
				( attribute "CDS_LIB" "mstr_discrete"
					( Origin gPackager )
				)
				( attribute "CDS_LOCATION" "R7F25"
					( Origin gPackager )
				)
				( attribute "CDS_SEC" "1"
					( Origin gPackager )
				)
				( attribute "LOCATION" "R7F25"
					( Origin gFrontEnd )
				)
				( attribute "MATERIAL" "CHIP"
					( Origin gFrontEnd )
				)
				( attribute "PACK_TYPE" "0402"
					( Origin gFrontEnd )
				)
				( attribute "PART_NUMBER" "G21796-173"
					( Origin gFrontEnd )
				)
				( attribute "PHYS_PAGE" "215"
					( Origin gFrontEnd )
				)
				( attribute "ROOM" "VDDQ_ABC_PWR_VR"
					( Origin gFrontEnd )
				)
				( attribute "ROT" "0"
					( Origin gFrontEnd )
				)
				( attribute "SEC" "1"
					( Origin gPackager )
				)
				( attribute "TOLERANCE" "1%"
					( Origin gFrontEnd )
				)
				( attribute "VALUE" "20.0"
					( Origin gFrontEnd )
				)
				( attribute "VER" "1"
					( Origin gFrontEnd )
				)
				( attribute "WATTAGE" "1/16W"
					( Origin gFrontEnd )
				)
				( attribute "XY" "(3400,2150)"
					( Origin gFrontEnd )
				)
				( attribute "CHIPS_PART_NAME" "RES"
					( Origin gPackager )
				)
				( attribute "CDS_PART_NAME" "RES_0402-20.0,1%,1/16W,CHIP,G2A"
					( Origin gPackager )
				)
				( objectStatus "R7F25" )
				( pin "a"
					( attribute "PN" "1"
						( Origin gPackager )
					)
					( objectStatus "R7F25.1" )
				)
				( pin "b"
					( attribute "PN" "2"
						( Origin gPackager )
					)
					( objectStatus "R7F25.2" )
				)
			)
			( gate "@baseboard_fab2_lib.baseboard_fab2(sch_1):page215_i300"
				( attribute "CDS_LIB" "mstr_discrete"
					( Origin gPackager )
				)
				( attribute "CDS_LOCATION" "R7F36"
					( Origin gPackager )
				)
				( attribute "CDS_SEC" "1"
					( Origin gPackager )
				)
				( attribute "LOCATION" "R7F36"
					( Origin gFrontEnd )
				)
				( attribute "MATERIAL" "EMPTY"
					( Origin gFrontEnd )
				)
				( attribute "PACK_TYPE" "0402"
					( Origin gFrontEnd )
				)
				( attribute "PART_NUMBER" "G21796-311"
					( Origin gFrontEnd )
				)
				( attribute "PHYS_PAGE" "215"
					( Origin gFrontEnd )
				)
				( attribute "ROOM" "VDDQ_ABC_PWR_VR"
					( Origin gFrontEnd )
				)
				( attribute "ROT" "0"
					( Origin gFrontEnd )
				)
				( attribute "SEC" "1"
					( Origin gFrontEnd )
				)
				( attribute "SEC_TYPE" "0402"
					( Origin gFrontEnd )
				)
				( attribute "TOLERANCE" "1.0%"
					( Origin gFrontEnd )
				)
				( attribute "VALUE" "2.26K"
					( Origin gFrontEnd )
				)
				( attribute "VER" "2"
					( Origin gFrontEnd )
				)
				( attribute "WATTAGE" "1/16W"
					( Origin gFrontEnd )
				)
				( attribute "XY" "(3075,3050)"
					( Origin gFrontEnd )
				)
				( attribute "CHIPS_PART_NAME" "RES"
					( Origin gPackager )
				)
				( attribute "CDS_PART_NAME" "RES_0402-2.26K,1.0%,1/16W,EMPTA"
					( Origin gPackager )
				)
				( objectStatus "R7F36" )
				( pin "a"
					( attribute "PN" "1"
						( Origin gPackager )
					)
					( objectStatus "R7F36.1" )
				)
				( pin "b"
					( attribute "PN" "2"
						( Origin gPackager )
					)
					( objectStatus "R7F36.2" )
				)
			)
			( gate "@baseboard_fab2_lib.baseboard_fab2(sch_1):page215_i301"
				( attribute "CDS_LIB" "mstr_discrete"
					( Origin gPackager )
				)
				( attribute "CDS_LOCATION" "R7F22"
					( Origin gPackager )
				)
				( attribute "CDS_SEC" "1"
					( Origin gPackager )
				)
				( attribute "LOCATION" "R7F22"
					( Origin gFrontEnd )
				)
				( attribute "MATERIAL" "CHIP"
					( Origin gFrontEnd )
				)
				( attribute "PACK_TYPE" "0402"
					( Origin gFrontEnd )
				)
				( attribute "PART_NUMBER" "G21796-026"
					( Origin gFrontEnd )
				)
				( attribute "PHYS_PAGE" "215"
					( Origin gFrontEnd )
				)
				( attribute "ROOM" "VDDQ_ABC_PWR_VR"
					( Origin gFrontEnd )
				)
				( attribute "ROT" "0"
					( Origin gFrontEnd )
				)
				( attribute "SEC" "1"
					( Origin gFrontEnd )
				)
				( attribute "SEC_TYPE" "0402"
					( Origin gFrontEnd )
				)
				( attribute "TOLERANCE" "1%"
					( Origin gFrontEnd )
				)
				( attribute "VALUE" "1.00K"
					( Origin gFrontEnd )
				)
				( attribute "VER" "2"
					( Origin gFrontEnd )
				)
				( attribute "WATTAGE" "1/16W"
					( Origin gFrontEnd )
				)
				( attribute "XY" "(2750,3200)"
					( Origin gFrontEnd )
				)
				( attribute "CHIPS_PART_NAME" "RES"
					( Origin gPackager )
				)
				( attribute "CDS_PART_NAME" "RES_0402-1.00K,1%,1/16W,CHIP,GA"
					( Origin gPackager )
				)
				( objectStatus "R7F22" )
				( pin "a"
					( attribute "PN" "1"
						( Origin gPackager )
					)
					( objectStatus "R7F22.1" )
				)
				( pin "b"
					( attribute "PN" "2"
						( Origin gPackager )
					)
					( objectStatus "R7F22.2" )
				)
			)
			( gate "@baseboard_fab2_lib.baseboard_fab2(sch_1):page215_i302"
				( attribute "CDS_LIB" "mstr_discrete"
					( Origin gPackager )
				)
				( attribute "CDS_LOCATION" "R7G4"
					( Origin gPackager )
				)
				( attribute "CDS_SEC" "1"
					( Origin gPackager )
				)
				( attribute "LOCATION" "R7G4"
					( Origin gFrontEnd )
				)
				( attribute "MATERIAL" "CHIP"
					( Origin gFrontEnd )
				)
				( attribute "PACK_TYPE" "0402"
					( Origin gFrontEnd )
				)
				( attribute "PART_NUMBER" "G21497-005"
					( Origin gFrontEnd )
				)
				( attribute "PHYS_PAGE" "215"
					( Origin gFrontEnd )
				)
				( attribute "ROOM" "VDDQ_ABC_PWR_VR"
					( Origin gFrontEnd )
				)
				( attribute "ROT" "0"
					( Origin gFrontEnd )
				)
				( attribute "SEC" "1"
					( Origin gFrontEnd )
				)
				( attribute "SEC_TYPE" "0402"
					( Origin gFrontEnd )
				)
				( attribute "TOLERANCE" "5%"
					( Origin gFrontEnd )
				)
				( attribute "VALUE" "0.0"
					( Origin gFrontEnd )
				)
				( attribute "VER" "1"
					( Origin gFrontEnd )
				)
				( attribute "WATTAGE" "1/16W"
					( Origin gFrontEnd )
				)
				( attribute "XY" "(2925,2500)"
					( Origin gFrontEnd )
				)
				( attribute "CHIPS_PART_NAME" "RES"
					( Origin gPackager )
				)
				( attribute "CDS_PART_NAME" "RES_0402-0.0,5%,1/16W,CHIP,G21A"
					( Origin gPackager )
				)
				( objectStatus "R7G4" )
				( pin "a"
					( attribute "PN" "1"
						( Origin gPackager )
					)
					( objectStatus "R7G4.1" )
				)
				( pin "b"
					( attribute "PN" "2"
						( Origin gPackager )
					)
					( objectStatus "R7G4.2" )
				)
			)
			( gate "@baseboard_fab2_lib.baseboard_fab2(sch_1):page215_i303"
				( attribute "CDS_LIB" "mstr_discrete"
					( Origin gPackager )
				)
				( attribute "CDS_LOCATION" "R7F27"
					( Origin gPackager )
				)
				( attribute "CDS_SEC" "1"
					( Origin gPackager )
				)
				( attribute "LOCATION" "R7F27"
					( Origin gFrontEnd )
				)
				( attribute "MATERIAL" "CHIP"
					( Origin gFrontEnd )
				)
				( attribute "PACK_TYPE" "0402"
					( Origin gFrontEnd )
				)
				( attribute "PART_NUMBER" "G21796-026"
					( Origin gFrontEnd )
				)
				( attribute "PHYS_PAGE" "215"
					( Origin gFrontEnd )
				)
				( attribute "ROOM" "VDDQ_ABC_PWR_VR"
					( Origin gFrontEnd )
				)
				( attribute "ROT" "0"
					( Origin gFrontEnd )
				)
				( attribute "SEC" "1"
					( Origin gFrontEnd )
				)
				( attribute "SEC_TYPE" "0402"
					( Origin gFrontEnd )
				)
				( attribute "TOLERANCE" "1%"
					( Origin gFrontEnd )
				)
				( attribute "VALUE" "1.00K"
					( Origin gFrontEnd )
				)
				( attribute "VER" "2"
					( Origin gFrontEnd )
				)
				( attribute "WATTAGE" "1/16W"
					( Origin gFrontEnd )
				)
				( attribute "XY" "(2400,3200)"
					( Origin gFrontEnd )
				)
				( attribute "CHIPS_PART_NAME" "RES"
					( Origin gPackager )
				)
				( attribute "CDS_PART_NAME" "RES_0402-1.00K,1%,1/16W,CHIP,GA"
					( Origin gPackager )
				)
				( objectStatus "R7F27" )
				( pin "a"
					( attribute "PN" "1"
						( Origin gPackager )
					)
					( objectStatus "R7F27.1" )
				)
				( pin "b"
					( attribute "PN" "2"
						( Origin gPackager )
					)
					( objectStatus "R7F27.2" )
				)
			)
			( gate "@baseboard_fab2_lib.baseboard_fab2(sch_1):page215_i304"
				( attribute "CDS_LIB" "mstr_discrete"
					( Origin gPackager )
				)
				( attribute "CDS_LOCATION" "R7F26"
					( Origin gPackager )
				)
				( attribute "CDS_SEC" "1"
					( Origin gPackager )
				)
				( attribute "LOCATION" "R7F26"
					( Origin gFrontEnd )
				)
				( attribute "MATERIAL" "CHIP"
					( Origin gFrontEnd )
				)
				( attribute "PACK_TYPE" "0402"
					( Origin gFrontEnd )
				)
				( attribute "PART_NUMBER" "G21796-173"
					( Origin gFrontEnd )
				)
				( attribute "PHYS_PAGE" "215"
					( Origin gFrontEnd )
				)
				( attribute "ROOM" "VDDQ_ABC_PWR_VR"
					( Origin gFrontEnd )
				)
				( attribute "ROT" "0"
					( Origin gFrontEnd )
				)
				( attribute "SEC" "1"
					( Origin gPackager )
				)
				( attribute "TOLERANCE" "1%"
					( Origin gFrontEnd )
				)
				( attribute "VALUE" "20.0"
					( Origin gFrontEnd )
				)
				( attribute "VER" "1"
					( Origin gFrontEnd )
				)
				( attribute "WATTAGE" "1/16W"
					( Origin gFrontEnd )
				)
				( attribute "XY" "(3075,2100)"
					( Origin gFrontEnd )
				)
				( attribute "CHIPS_PART_NAME" "RES"
					( Origin gPackager )
				)
				( attribute "CDS_PART_NAME" "RES_0402-20.0,1%,1/16W,CHIP,G2A"
					( Origin gPackager )
				)
				( objectStatus "R7F26" )
				( pin "a"
					( attribute "PN" "1"
						( Origin gPackager )
					)
					( objectStatus "R7F26.1" )
				)
				( pin "b"
					( attribute "PN" "2"
						( Origin gPackager )
					)
					( objectStatus "R7F26.2" )
				)
			)
			( gate "@baseboard_fab2_lib.baseboard_fab2(sch_1):page215_i305"
				( attribute "CDS_LIB" "mstr_discrete"
					( Origin gPackager )
				)
				( attribute "CDS_LOCATION" "C7F14"
					( Origin gPackager )
				)
				( attribute "CDS_SEC" "1"
					( Origin gPackager )
				)
				( attribute "LOCATION" "C7F14"
					( Origin gFrontEnd )
				)
				( attribute "MATERIAL" "X7R"
					( Origin gFrontEnd )
				)
				( attribute "PACK_TYPE" "0402LF"
					( Origin gFrontEnd )
				)
				( attribute "PART_NUMBER" "A36096-046"
					( Origin gFrontEnd )
				)
				( attribute "PHYS_PAGE" "215"
					( Origin gFrontEnd )
				)
				( attribute "ROOM" "VDDQ_ABC_PWR_VR"
					( Origin gFrontEnd )
				)
				( attribute "ROT" "0"
					( Origin gFrontEnd )
				)
				( attribute "SEC" "1"
					( Origin gFrontEnd )
				)
				( attribute "SEC_TYPE" "0402LF"
					( Origin gFrontEnd )
				)
				( attribute "TOLERANCE" "10%"
					( Origin gFrontEnd )
				)
				( attribute "VALUE" "1000PF"
					( Origin gFrontEnd )
				)
				( attribute "VER" "1"
					( Origin gFrontEnd )
				)
				( attribute "VOLTAGE" "50V"
					( Units "uVoltage" "V" 1.000000)
					( Origin gFrontEnd )
				)
				( attribute "XY" "(3225,1350)"
					( Origin gFrontEnd )
				)
				( attribute "CHIPS_PART_NAME" "CAP"
					( Origin gPackager )
				)
				( attribute "CDS_PART_NAME" "CAP_0402LF-1000PF,50V,10%,X7R,A"
					( Origin gPackager )
				)
				( objectStatus "C7F14" )
				( pin "a"
					( attribute "PN" "1"
						( Origin gPackager )
					)
					( objectStatus "C7F14.1" )
				)
				( pin "b"
					( attribute "PN" "2"
						( Origin gPackager )
					)
					( objectStatus "C7F14.2" )
				)
			)
			( gate "@baseboard_fab2_lib.baseboard_fab2(sch_1):page215_i307"
				( attribute "CDS_LIB" "mstr_discrete"
					( Origin gPackager )
				)
				( attribute "CDS_LOCATION" "R7G2"
					( Origin gPackager )
				)
				( attribute "CDS_SEC" "1"
					( Origin gPackager )
				)
				( attribute "LOCATION" "R7G2"
					( Origin gFrontEnd )
				)
				( attribute "MATERIAL" "CHIP"
					( Origin gFrontEnd )
				)
				( attribute "PACK_TYPE" "0402"
					( Origin gFrontEnd )
				)
				( attribute "PART_NUMBER" "G21497-005"
					( Origin gFrontEnd )
				)
				( attribute "PHYS_PAGE" "215"
					( Origin gFrontEnd )
				)
				( attribute "ROOM" "VDDQ_ABC_PWR_VR"
					( Origin gFrontEnd )
				)
				( attribute "ROT" "0"
					( Origin gFrontEnd )
				)
				( attribute "SEC" "1"
					( Origin gFrontEnd )
				)
				( attribute "SEC_TYPE" "0402"
					( Origin gFrontEnd )
				)
				( attribute "TOLERANCE" "5%"
					( Origin gFrontEnd )
				)
				( attribute "VALUE" "0.0"
					( Origin gFrontEnd )
				)
				( attribute "VER" "1"
					( Origin gFrontEnd )
				)
				( attribute "WATTAGE" "1/16W"
					( Origin gFrontEnd )
				)
				( attribute "XY" "(3075,1800)"
					( Origin gFrontEnd )
				)
				( attribute "CHIPS_PART_NAME" "RES"
					( Origin gPackager )
				)
				( attribute "CDS_PART_NAME" "RES_0402-0.0,5%,1/16W,CHIP,G21A"
					( Origin gPackager )
				)
				( objectStatus "R7G2" )
				( pin "a"
					( attribute "PN" "1"
						( Origin gPackager )
					)
					( objectStatus "R7G2.1" )
				)
				( pin "b"
					( attribute "PN" "2"
						( Origin gPackager )
					)
					( objectStatus "R7G2.2" )
				)
			)
			( gate "@baseboard_fab2_lib.baseboard_fab2(sch_1):page215_i309"
				( attribute "CDS_LIB" "dev_discrete"
					( Origin gPackager )
				)
				( attribute "CDS_LOCATION" "C7F18"
					( Origin gPackager )
				)
				( attribute "CDS_SEC" "1"
					( Origin gPackager )
				)
				( attribute "LOCATION" "C7F18"
					( Origin gFrontEnd )
				)
				( attribute "MATERIAL" "X6S"
					( Origin gFrontEnd )
				)
				( attribute "PACK_TYPE" "0402V"
					( Origin gFrontEnd )
				)
				( attribute "PART_NUMBER" "D97712-004"
					( Origin gFrontEnd )
				)
				( attribute "PHYS_PAGE" "215"
					( Origin gFrontEnd )
				)
				( attribute "ROOM" "VDDQ_ABC_PWR_VR"
					( Origin gFrontEnd )
				)
				( attribute "ROT" "0"
					( Origin gFrontEnd )
				)
				( attribute "SEC" "1"
					( Origin gPackager )
				)
				( attribute "TOLERANCE" "10%"
					( Origin gFrontEnd )
				)
				( attribute "VALUE" "1.0UF"
					( Origin gFrontEnd )
				)
				( attribute "VER" "1"
					( Origin gFrontEnd )
				)
				( attribute "VOLTAGE" "6.3V"
					( Units "uVoltage" "V" 1.000000)
					( Origin gFrontEnd )
				)
				( attribute "XY" "(1825,3200)"
					( Origin gFrontEnd )
				)
				( attribute "CHIPS_PART_NAME" "CAP_A"
					( Origin gPackager )
				)
				( attribute "CDS_PART_NAME" "CAP_A_0402V-1.0UF,6.3V,10%,X6SA"
					( Origin gPackager )
				)
				( objectStatus "C7F18" )
				( pin "a"
					( attribute "PN" "1"
						( Origin gPackager )
					)
					( objectStatus "C7F18.1" )
				)
				( pin "b"
					( attribute "PN" "2"
						( Origin gPackager )
					)
					( objectStatus "C7F18.2" )
				)
			)
			( gate "@baseboard_fab2_lib.baseboard_fab2(sch_1):page215_i311"
				( attribute "CDS_LIB" "dev_discrete"
					( Origin gPackager )
				)
				( attribute "CDS_LOCATION" "C7F17"
					( Origin gPackager )
				)
				( attribute "CDS_SEC" "1"
					( Origin gPackager )
				)
				( attribute "LOCATION" "C7F17"
					( Origin gFrontEnd )
				)
				( attribute "MATERIAL" "X7R"
					( Origin gFrontEnd )
				)
				( attribute "PACK_TYPE" "0402V"
					( Origin gFrontEnd )
				)
				( attribute "PART_NUMBER" "A36096-030"
					( Origin gFrontEnd )
				)
				( attribute "PHYS_PAGE" "215"
					( Origin gFrontEnd )
				)
				( attribute "ROOM" "VDDQ_ABC_PWR_VR"
					( Origin gFrontEnd )
				)
				( attribute "ROT" "0"
					( Origin gFrontEnd )
				)
				( attribute "SEC" "1"
					( Origin gFrontEnd )
				)
				( attribute "SEC_TYPE" "0402V"
					( Origin gFrontEnd )
				)
				( attribute "TOLERANCE" "10%"
					( Origin gFrontEnd )
				)
				( attribute "VALUE" "0.1UF"
					( Origin gFrontEnd )
				)
				( attribute "VER" "1"
					( Origin gFrontEnd )
				)
				( attribute "VOLTAGE" "16V"
					( Units "uVoltage" "V" 1.000000)
					( Origin gFrontEnd )
				)
				( attribute "XY" "(1425,3200)"
					( Origin gFrontEnd )
				)
				( attribute "CHIPS_PART_NAME" "CAP_A"
					( Origin gPackager )
				)
				( attribute "CDS_PART_NAME" "CAP_A_0402V-0.1UF,16V,10%,X7R,A"
					( Origin gPackager )
				)
				( objectStatus "C7F17" )
				( pin "a"
					( attribute "PN" "1"
						( Origin gPackager )
					)
					( objectStatus "C7F17.1" )
				)
				( pin "b"
					( attribute "PN" "2"
						( Origin gPackager )
					)
					( objectStatus "C7F17.2" )
				)
			)
			( gate "@baseboard_fab2_lib.baseboard_fab2(sch_1):page215_i313"
				( attribute "CDS_LIB" "mstr_discrete"
					( Origin gPackager )
				)
				( attribute "CDS_LOCATION" "R3T13"
					( Origin gPackager )
				)
				( attribute "CDS_SEC" "1"
					( Origin gPackager )
				)
				( attribute "LOCATION" "R3T13"
					( Origin gFrontEnd )
				)
				( attribute "MATERIAL" "CHIP"
					( Origin gFrontEnd )
				)
				( attribute "PACK_TYPE" "0402"
					( Origin gFrontEnd )
				)
				( attribute "PART_NUMBER" "G21497-005"
					( Origin gFrontEnd )
				)
				( attribute "PHYS_PAGE" "215"
					( Origin gFrontEnd )
				)
				( attribute "ROOM" "VDDQ_ABC_PWR_VR"
					( Origin gFrontEnd )
				)
				( attribute "ROT" "0"
					( Origin gFrontEnd )
				)
				( attribute "SEC" "1"
					( Origin gFrontEnd )
				)
				( attribute "SEC_TYPE" "0402"
					( Origin gFrontEnd )
				)
				( attribute "TOLERANCE" "5%"
					( Origin gFrontEnd )
				)
				( attribute "VALUE" "0.0"
					( Origin gFrontEnd )
				)
				( attribute "VER" "2"
					( Origin gFrontEnd )
				)
				( attribute "WATTAGE" "1/16W"
					( Origin gFrontEnd )
				)
				( attribute "XY" "(1125,3550)"
					( Origin gFrontEnd )
				)
				( attribute "CHIPS_PART_NAME" "RES"
					( Origin gPackager )
				)
				( attribute "CDS_PART_NAME" "RES_0402-0.0,5%,1/16W,CHIP,G21A"
					( Origin gPackager )
				)
				( objectStatus "R3T13" )
				( pin "a"
					( attribute "PN" "1"
						( Origin gPackager )
					)
					( objectStatus "R3T13.1" )
				)
				( pin "b"
					( attribute "PN" "2"
						( Origin gPackager )
					)
					( objectStatus "R3T13.2" )
				)
			)
			( gate "@baseboard_fab2_lib.baseboard_fab2(sch_1):page215_i315"
				( attribute "BOM_COST" "SM_CONTROLLER"
					( Origin gFrontEnd )
				)
				( attribute "CDS_LIB" "mstr_discrete"
					( Origin gPackager )
				)
				( attribute "CDS_LOCATION" "R7F20"
					( Origin gPackager )
				)
				( attribute "CDS_SEC" "1"
					( Origin gPackager )
				)
				( attribute "LOCATION" "R7F20"
					( Origin gFrontEnd )
				)
				( attribute "MATERIAL" "EMPTY"
					( Origin gFrontEnd )
				)
				( attribute "PACK_TYPE" "0402"
					( Origin gFrontEnd )
				)
				( attribute "PART_NUMBER" "G21796-010"
					( Origin gFrontEnd )
				)
				( attribute "PHYS_PAGE" "215"
					( Origin gFrontEnd )
				)
				( attribute "ROOM" "BMC"
					( Origin gFrontEnd )
				)
				( attribute "ROT" "0"
					( Origin gFrontEnd )
				)
				( attribute "SEC" "1"
					( Origin gPackager )
				)
				( attribute "TOLERANCE" "1%"
					( Origin gFrontEnd )
				)
				( attribute "VALUE" "100.0K"
					( Origin gFrontEnd )
				)
				( attribute "VER" "2"
					( Origin gFrontEnd )
				)
				( attribute "WATTAGE" "1/16W"
					( Origin gFrontEnd )
				)
				( attribute "XY" "(425,3625)"
					( Origin gFrontEnd )
				)
				( attribute "CHIPS_PART_NAME" "RES"
					( Origin gPackager )
				)
				( attribute "CDS_PART_NAME" "RES_0402-100.0K,1%,1/16W,EMPTYA"
					( Origin gPackager )
				)
				( objectStatus "R7F20" )
				( pin "a"
					( attribute "PN" "1"
						( Origin gPackager )
					)
					( objectStatus "R7F20.1" )
				)
				( pin "b"
					( attribute "PN" "2"
						( Origin gPackager )
					)
					( objectStatus "R7F20.2" )
				)
			)
			( gate "@baseboard_fab2_lib.baseboard_fab2(sch_1):page215_i317"
				( attribute "CDS_LIB" "mstr_discrete"
					( Origin gPackager )
				)
				( attribute "CDS_LOCATION" "R7G10"
					( Origin gPackager )
				)
				( attribute "CDS_SEC" "1"
					( Origin gPackager )
				)
				( attribute "LOCATION" "R7G10"
					( Origin gFrontEnd )
				)
				( attribute "MATERIAL" "CHIP"
					( Origin gFrontEnd )
				)
				( attribute "PACK_TYPE" "0402"
					( Origin gFrontEnd )
				)
				( attribute "PART_NUMBER" "G21796-078"
					( Origin gFrontEnd )
				)
				( attribute "PHYS_PAGE" "215"
					( Origin gFrontEnd )
				)
				( attribute "ROOM" "VDDQ_ABC_PWR_VR"
					( Origin gFrontEnd )
				)
				( attribute "ROT" "0"
					( Origin gFrontEnd )
				)
				( attribute "SEC" "1"
					( Origin gPackager )
				)
				( attribute "TOLERANCE" "1%"
					( Origin gFrontEnd )
				)
				( attribute "VALUE" "8.06K"
					( Origin gFrontEnd )
				)
				( attribute "VER" "2"
					( Origin gFrontEnd )
				)
				( attribute "WATTAGE" "1/16W"
					( Origin gFrontEnd )
				)
				( attribute "XY" "(850,400)"
					( Origin gFrontEnd )
				)
				( attribute "CHIPS_PART_NAME" "RES"
					( Origin gPackager )
				)
				( attribute "CDS_PART_NAME" "RES_0402-8.06K,1%,1/16W,CHIP,GA"
					( Origin gPackager )
				)
				( objectStatus "R7G10" )
				( pin "a"
					( attribute "PN" "1"
						( Origin gPackager )
					)
					( objectStatus "R7G10.1" )
				)
				( pin "b"
					( attribute "PN" "2"
						( Origin gPackager )
					)
					( objectStatus "R7G10.2" )
				)
			)
			( gate "@baseboard_fab2_lib.baseboard_fab2(sch_1):page215_i320"
				( attribute "CDS_LIB" "mstr_discrete"
					( Origin gPackager )
				)
				( attribute "CDS_LOCATION" "C7G3"
					( Origin gPackager )
				)
				( attribute "CDS_SEC" "1"
					( Origin gPackager )
				)
				( attribute "LOCATION" "C7G3"
					( Origin gFrontEnd )
				)
				( attribute "MATERIAL" "X7R"
					( Origin gFrontEnd )
				)
				( attribute "PACK_TYPE" "0402LF"
					( Origin gFrontEnd )
				)
				( attribute "PART_NUMBER" "A36096-050"
					( Origin gFrontEnd )
				)
				( attribute "PHYS_PAGE" "215"
					( Origin gFrontEnd )
				)
				( attribute "ROOM" "VDDQ_ABC_PWR_VR"
					( Origin gFrontEnd )
				)
				( attribute "ROT" "2"
					( Origin gFrontEnd )
				)
				( attribute "SEC" "1"
					( Origin gFrontEnd )
				)
				( attribute "SEC_TYPE" "0402LF"
					( Origin gFrontEnd )
				)
				( attribute "TOLERANCE" "10%"
					( Origin gFrontEnd )
				)
				( attribute "VALUE" "220PF"
					( Origin gFrontEnd )
				)
				( attribute "VER" "1"
					( Origin gFrontEnd )
				)
				( attribute "VOLTAGE" "50V"
					( Units "uVoltage" "V" 1.000000)
					( Origin gFrontEnd )
				)
				( attribute "XY" "(325,850)"
					( Origin gFrontEnd )
				)
				( attribute "CHIPS_PART_NAME" "CAP"
					( Origin gPackager )
				)
				( attribute "CDS_PART_NAME" "CAP_0402LF-220PF,50V,10%,X7R,AA"
					( Origin gPackager )
				)
				( objectStatus "C7G3" )
				( pin "a"
					( attribute "PN" "1"
						( Origin gPackager )
					)
					( objectStatus "C7G3.1" )
				)
				( pin "b"
					( attribute "PN" "2"
						( Origin gPackager )
					)
					( objectStatus "C7G3.2" )
				)
			)
			( gate "@baseboard_fab2_lib.baseboard_fab2(sch_1):page215_i321"
				( attribute "CDS_LIB" "mstr_discrete"
					( Origin gPackager )
				)
				( attribute "CDS_LOCATION" "R7G8"
					( Origin gPackager )
				)
				( attribute "CDS_SEC" "1"
					( Origin gPackager )
				)
				( attribute "LOCATION" "R7G8"
					( Origin gFrontEnd )
				)
				( attribute "MATERIAL" "CHIP"
					( Origin gFrontEnd )
				)
				( attribute "PACK_TYPE" "0402"
					( Origin gFrontEnd )
				)
				( attribute "PART_NUMBER" "G21796-082"
					( Origin gFrontEnd )
				)
				( attribute "PHYS_PAGE" "215"
					( Origin gFrontEnd )
				)
				( attribute "ROOM" "VDDQ_ABC_PWR_VR"
					( Origin gFrontEnd )
				)
				( attribute "ROT" "0"
					( Origin gFrontEnd )
				)
				( attribute "SEC" "1"
					( Origin gPackager )
				)
				( attribute "TOLERANCE" "1%"
					( Origin gFrontEnd )
				)
				( attribute "VALUE" "4.02K"
					( Origin gFrontEnd )
				)
				( attribute "VER" "2"
					( Origin gFrontEnd )
				)
				( attribute "WATTAGE" "1/16W"
					( Origin gFrontEnd )
				)
				( attribute "XY" "(500,400)"
					( Origin gFrontEnd )
				)
				( attribute "CHIPS_PART_NAME" "RES"
					( Origin gPackager )
				)
				( attribute "CDS_PART_NAME" "RES_0402-4.02K,1%,1/16W,CHIP,GA"
					( Origin gPackager )
				)
				( objectStatus "R7G8" )
				( pin "a"
					( attribute "PN" "1"
						( Origin gPackager )
					)
					( objectStatus "R7G8.1" )
				)
				( pin "b"
					( attribute "PN" "2"
						( Origin gPackager )
					)
					( objectStatus "R7G8.2" )
				)
			)
			( gate "@baseboard_fab2_lib.baseboard_fab2(sch_1):page215_i325"
				( attribute "CDS_LIB" "dev_discrete"
					( Origin gPackager )
				)
				( attribute "CDS_LOCATION" "C7F16"
					( Origin gPackager )
				)
				( attribute "CDS_SEC" "1"
					( Origin gPackager )
				)
				( attribute "LOCATION" "C7F16"
					( Origin gFrontEnd )
				)
				( attribute "MATERIAL" "X6S"
					( Origin gFrontEnd )
				)
				( attribute "PACK_TYPE" "0402V"
					( Origin gFrontEnd )
				)
				( attribute "PART_NUMBER" "D97712-004"
					( Origin gFrontEnd )
				)
				( attribute "PHYS_PAGE" "215"
					( Origin gFrontEnd )
				)
				( attribute "ROOM" "VDDQ_ABC_PWR_VR"
					( Origin gFrontEnd )
				)
				( attribute "ROT" "0"
					( Origin gFrontEnd )
				)
				( attribute "SEC" "1"
					( Origin gFrontEnd )
				)
				( attribute "SEC_TYPE" "0402V"
					( Origin gFrontEnd )
				)
				( attribute "TOLERANCE" "10%"
					( Origin gFrontEnd )
				)
				( attribute "VALUE" "1.0UF"
					( Origin gFrontEnd )
				)
				( attribute "VER" "1"
					( Origin gFrontEnd )
				)
				( attribute "VOLTAGE" "6.3V"
					( Units "uVoltage" "V" 1.000000)
					( Origin gFrontEnd )
				)
				( attribute "XY" "(3000,500)"
					( Origin gFrontEnd )
				)
				( attribute "CHIPS_PART_NAME" "CAP_A"
					( Origin gPackager )
				)
				( attribute "CDS_PART_NAME" "CAP_A_0402V-1.0UF,6.3V,10%,X6SA"
					( Origin gPackager )
				)
				( objectStatus "C7F16" )
				( pin "a"
					( attribute "PN" "1"
						( Origin gPackager )
					)
					( objectStatus "C7F16.1" )
				)
				( pin "b"
					( attribute "PN" "2"
						( Origin gPackager )
					)
					( objectStatus "C7F16.2" )
				)
			)
			( gate "@baseboard_fab2_lib.baseboard_fab2(sch_1):page215_i327"
				( attribute "CDS_LIB" "dev_discrete"
					( Origin gPackager )
				)
				( attribute "CDS_LOCATION" "C7F15"
					( Origin gPackager )
				)
				( attribute "CDS_SEC" "1"
					( Origin gPackager )
				)
				( attribute "LOCATION" "C7F15"
					( Origin gFrontEnd )
				)
				( attribute "MATERIAL" "X7R"
					( Origin gFrontEnd )
				)
				( attribute "PACK_TYPE" "0402V"
					( Origin gFrontEnd )
				)
				( attribute "PART_NUMBER" "A36096-030"
					( Origin gFrontEnd )
				)
				( attribute "PHYS_PAGE" "215"
					( Origin gFrontEnd )
				)
				( attribute "ROOM" "VDDQ_ABC_PWR_VR"
					( Origin gFrontEnd )
				)
				( attribute "ROT" "0"
					( Origin gFrontEnd )
				)
				( attribute "SEC" "1"
					( Origin gFrontEnd )
				)
				( attribute "SEC_TYPE" "0402V"
					( Origin gFrontEnd )
				)
				( attribute "TOLERANCE" "10%"
					( Origin gFrontEnd )
				)
				( attribute "VALUE" "0.1UF"
					( Origin gFrontEnd )
				)
				( attribute "VER" "1"
					( Origin gFrontEnd )
				)
				( attribute "VOLTAGE" "16V"
					( Units "uVoltage" "V" 1.000000)
					( Origin gFrontEnd )
				)
				( attribute "XY" "(2600,500)"
					( Origin gFrontEnd )
				)
				( attribute "CHIPS_PART_NAME" "CAP_A"
					( Origin gPackager )
				)
				( attribute "CDS_PART_NAME" "CAP_A_0402V-0.1UF,16V,10%,X7R,A"
					( Origin gPackager )
				)
				( objectStatus "C7F15" )
				( pin "a"
					( attribute "PN" "1"
						( Origin gPackager )
					)
					( objectStatus "C7F15.1" )
				)
				( pin "b"
					( attribute "PN" "2"
						( Origin gPackager )
					)
					( objectStatus "C7F15.2" )
				)
			)
			( gate "@baseboard_fab2_lib.baseboard_fab2(sch_1):page215_i330"
				( attribute "CDS_LIB" "mstr_discrete"
					( Origin gPackager )
				)
				( attribute "CDS_LOCATION" "R3T11"
					( Origin gPackager )
				)
				( attribute "CDS_SEC" "1"
					( Origin gPackager )
				)
				( attribute "LOCATION" "R3T11"
					( Origin gFrontEnd )
				)
				( attribute "MATERIAL" "EMPTY"
					( Origin gFrontEnd )
				)
				( attribute "PACK_TYPE" "0402"
					( Origin gFrontEnd )
				)
				( attribute "PART_NUMBER" "G21796-047"
					( Origin gFrontEnd )
				)
				( attribute "PHYS_PAGE" "215"
					( Origin gFrontEnd )
				)
				( attribute "ROOM" "VDDQ_ABC_PWR_VR"
					( Origin gFrontEnd )
				)
				( attribute "ROT" "0"
					( Origin gFrontEnd )
				)
				( attribute "SEC" "1"
					( Origin gFrontEnd )
				)
				( attribute "SEC_TYPE" "0402"
					( Origin gFrontEnd )
				)
				( attribute "TOLERANCE" "1%"
					( Origin gFrontEnd )
				)
				( attribute "VALUE" "49.9"
					( Origin gFrontEnd )
				)
				( attribute "VER" "2"
					( Origin gFrontEnd )
				)
				( attribute "WATTAGE" "1/16W"
					( Origin gFrontEnd )
				)
				( attribute "XY" "(-100,3625)"
					( Origin gFrontEnd )
				)
				( attribute "CHIPS_PART_NAME" "RES"
					( Origin gPackager )
				)
				( attribute "CDS_PART_NAME" "RES_0402-49.9,1%,1/16W,EMPTY,GA"
					( Origin gPackager )
				)
				( objectStatus "R3T11" )
				( pin "a"
					( attribute "PN" "1"
						( Origin gPackager )
					)
					( objectStatus "R3T11.1" )
				)
				( pin "b"
					( attribute "PN" "2"
						( Origin gPackager )
					)
					( objectStatus "R3T11.2" )
				)
			)
			( gate "@baseboard_fab2_lib.baseboard_fab2(sch_1):page215_i331"
				( attribute "CDS_LIB" "mstr_discrete"
					( Origin gPackager )
				)
				( attribute "CDS_LOCATION" "R7G24"
					( Origin gPackager )
				)
				( attribute "CDS_SEC" "1"
					( Origin gPackager )
				)
				( attribute "LOCATION" "R7G24"
					( Origin gFrontEnd )
				)
				( attribute "MATERIAL" "CHIP"
					( Origin gFrontEnd )
				)
				( attribute "PACK_TYPE" "0402"
					( Origin gFrontEnd )
				)
				( attribute "PART_NUMBER" "G21796-009"
					( Origin gFrontEnd )
				)
				( attribute "PHYS_PAGE" "215"
					( Origin gFrontEnd )
				)
				( attribute "ROOM" "VDDQ_ABC_PWR_VR"
					( Origin gFrontEnd )
				)
				( attribute "ROT" "0"
					( Origin gFrontEnd )
				)
				( attribute "SEC" "1"
					( Origin gFrontEnd )
				)
				( attribute "SEC_TYPE" "0402"
					( Origin gFrontEnd )
				)
				( attribute "TOLERANCE" "1%"
					( Origin gFrontEnd )
				)
				( attribute "VALUE" "150.0"
					( Origin gFrontEnd )
				)
				( attribute "VER" "1"
					( Origin gFrontEnd )
				)
				( attribute "WATTAGE" "1/16W"
					( Origin gFrontEnd )
				)
				( attribute "XY" "(125,3100)"
					( Origin gFrontEnd )
				)
				( attribute "CHIPS_PART_NAME" "RES"
					( Origin gPackager )
				)
				( attribute "CDS_PART_NAME" "RES_0402-150.0,1%,1/16W,CHIP,GA"
					( Origin gPackager )
				)
				( objectStatus "R7G24" )
				( pin "a"
					( attribute "PN" "1"
						( Origin gPackager )
					)
					( objectStatus "R7G24.1" )
				)
				( pin "b"
					( attribute "PN" "2"
						( Origin gPackager )
					)
					( objectStatus "R7G24.2" )
				)
			)
			( gate "@baseboard_fab2_lib.baseboard_fab2(sch_1):page215_i332"
				( attribute "CDS_LIB" "mstr_discrete"
					( Origin gPackager )
				)
				( attribute "CDS_LOCATION" "R3U3"
					( Origin gPackager )
				)
				( attribute "CDS_SEC" "1"
					( Origin gPackager )
				)
				( attribute "LOCATION" "R3U3"
					( Origin gFrontEnd )
				)
				( attribute "MATERIAL" "CHIP"
					( Origin gFrontEnd )
				)
				( attribute "PACK_TYPE" "0402"
					( Origin gFrontEnd )
				)
				( attribute "PART_NUMBER" "G21497-005"
					( Origin gFrontEnd )
				)
				( attribute "PHYS_PAGE" "215"
					( Origin gFrontEnd )
				)
				( attribute "ROOM" "PVCCIN_CPU0_VR"
					( Origin gFrontEnd )
				)
				( attribute "ROT" "0"
					( Origin gFrontEnd )
				)
				( attribute "SEC" "1"
					( Origin gPackager )
				)
				( attribute "TOLERANCE" "5%"
					( Origin gFrontEnd )
				)
				( attribute "VALUE" "0.0"
					( Origin gFrontEnd )
				)
				( attribute "VER" "1"
					( Origin gFrontEnd )
				)
				( attribute "WATTAGE" "1/16W"
					( Origin gFrontEnd )
				)
				( attribute "XY" "(-300,2925)"
					( Origin gFrontEnd )
				)
				( attribute "CHIPS_PART_NAME" "RES"
					( Origin gPackager )
				)
				( attribute "CDS_PART_NAME" "RES_0402-0.0,5%,1/16W,CHIP,G21A"
					( Origin gPackager )
				)
				( objectStatus "R3U3" )
				( pin "a"
					( attribute "PN" "1"
						( Origin gPackager )
					)
					( objectStatus "R3U3.1" )
				)
				( pin "b"
					( attribute "PN" "2"
						( Origin gPackager )
					)
					( objectStatus "R3U3.2" )
				)
			)
			( gate "@baseboard_fab2_lib.baseboard_fab2(sch_1):page215_i336"
				( attribute "CDS_LIB" "mstr_discrete"
					( Origin gPackager )
				)
				( attribute "CDS_LOCATION" "R7F34"
					( Origin gPackager )
				)
				( attribute "CDS_SEC" "1"
					( Origin gPackager )
				)
				( attribute "LOCATION" "R7F34"
					( Origin gFrontEnd )
				)
				( attribute "MATERIAL" "CHIP"
					( Origin gFrontEnd )
				)
				( attribute "PACK_TYPE" "0402"
					( Origin gFrontEnd )
				)
				( attribute "PART_NUMBER" "G21796-160"
					( Origin gFrontEnd )
				)
				( attribute "PHYS_PAGE" "215"
					( Origin gFrontEnd )
				)
				( attribute "ROOM" "VDDQ_ABC_PWR_VR"
					( Origin gFrontEnd )
				)
				( attribute "ROT" "0"
					( Origin gFrontEnd )
				)
				( attribute "SEC" "1"
					( Origin gFrontEnd )
				)
				( attribute "SEC_TYPE" "0402"
					( Origin gFrontEnd )
				)
				( attribute "TOLERANCE" "1%"
					( Origin gFrontEnd )
				)
				( attribute "VALUE" "100.0K"
					( Origin gFrontEnd )
				)
				( attribute "VER" "2"
					( Origin gFrontEnd )
				)
				( attribute "WATTAGE" "1/16W"
					( Origin gFrontEnd )
				)
				( attribute "XY" "(-950,3775)"
					( Origin gFrontEnd )
				)
				( attribute "CHIPS_PART_NAME" "RES"
					( Origin gPackager )
				)
				( attribute "CDS_PART_NAME" "RES_0402-100.0K,1%,1/16W,CHIP,B"
					( Origin gPackager )
				)
				( objectStatus "R7F34" )
				( pin "a"
					( attribute "PN" "1"
						( Origin gPackager )
					)
					( objectStatus "R7F34.1" )
				)
				( pin "b"
					( attribute "PN" "2"
						( Origin gPackager )
					)
					( objectStatus "R7F34.2" )
				)
			)
			( gate "@baseboard_fab2_lib.baseboard_fab2(sch_1):page215_i337"
				( attribute "CDS_LIB" "mstr_discrete"
					( Origin gPackager )
				)
				( attribute "CDS_LOCATION" "R7G3"
					( Origin gPackager )
				)
				( attribute "CDS_SEC" "1"
					( Origin gPackager )
				)
				( attribute "LOCATION" "R7G3"
					( Origin gFrontEnd )
				)
				( attribute "MATERIAL" "CHIP"
					( Origin gFrontEnd )
				)
				( attribute "PACK_TYPE" "0402"
					( Origin gFrontEnd )
				)
				( attribute "PART_NUMBER" "G21796-003"
					( Origin gFrontEnd )
				)
				( attribute "PHYS_PAGE" "215"
					( Origin gFrontEnd )
				)
				( attribute "ROOM" "VDDQ_ABC_PWR_VR"
					( Origin gFrontEnd )
				)
				( attribute "ROT" "0"
					( Origin gFrontEnd )
				)
				( attribute "SEC" "1"
					( Origin gFrontEnd )
				)
				( attribute "SEC_TYPE" "0402"
					( Origin gFrontEnd )
				)
				( attribute "TOLERANCE" "1%"
					( Origin gFrontEnd )
				)
				( attribute "VALUE" "1.5K"
					( Origin gFrontEnd )
				)
				( attribute "VER" "2"
					( Origin gFrontEnd )
				)
				( attribute "WATTAGE" "1/16W"
					( Origin gFrontEnd )
				)
				( attribute "XY" "(-950,3400)"
					( Origin gFrontEnd )
				)
				( attribute "CHIPS_PART_NAME" "RES"
					( Origin gPackager )
				)
				( attribute "CDS_PART_NAME" "RES_0402-1.5K,1%,1/16W,CHIP,G2A"
					( Origin gPackager )
				)
				( objectStatus "R7G3" )
				( pin "a"
					( attribute "PN" "1"
						( Origin gPackager )
					)
					( objectStatus "R7G3.1" )
				)
				( pin "b"
					( attribute "PN" "2"
						( Origin gPackager )
					)
					( objectStatus "R7G3.2" )
				)
			)
			( gate "@baseboard_fab2_lib.baseboard_fab2(sch_1):page215_i339"
				( attribute "CDS_LIB" "mstr_discrete"
					( Origin gPackager )
				)
				( attribute "CDS_LOCATION" "C7G1"
					( Origin gPackager )
				)
				( attribute "CDS_SEC" "1"
					( Origin gPackager )
				)
				( attribute "LOCATION" "C7G1"
					( Origin gFrontEnd )
				)
				( attribute "MATERIAL" "X7R"
					( Origin gFrontEnd )
				)
				( attribute "PACK_TYPE" "0402LF"
					( Origin gFrontEnd )
				)
				( attribute "PART_NUMBER" "A36096-046"
					( Origin gFrontEnd )
				)
				( attribute "PHYS_PAGE" "215"
					( Origin gFrontEnd )
				)
				( attribute "ROOM" "VDDQ_ABC_PWR_VR"
					( Origin gFrontEnd )
				)
				( attribute "ROT" "2"
					( Origin gFrontEnd )
				)
				( attribute "SEC" "1"
					( Origin gFrontEnd )
				)
				( attribute "SEC_TYPE" "0402LF"
					( Origin gFrontEnd )
				)
				( attribute "TOLERANCE" "10%"
					( Origin gFrontEnd )
				)
				( attribute "VALUE" "1000PF"
					( Origin gFrontEnd )
				)
				( attribute "VER" "1"
					( Origin gFrontEnd )
				)
				( attribute "VOLTAGE" "50V"
					( Units "uVoltage" "V" 1.000000)
					( Origin gFrontEnd )
				)
				( attribute "XY" "(-1175,3400)"
					( Origin gFrontEnd )
				)
				( attribute "CHIPS_PART_NAME" "CAP"
					( Origin gPackager )
				)
				( attribute "CDS_PART_NAME" "CAP_0402LF-1000PF,50V,10%,X7R,A"
					( Origin gPackager )
				)
				( objectStatus "C7G1" )
				( pin "a"
					( attribute "PN" "1"
						( Origin gPackager )
					)
					( objectStatus "C7G1.1" )
				)
				( pin "b"
					( attribute "PN" "2"
						( Origin gPackager )
					)
					( objectStatus "C7G1.2" )
				)
			)
			( gate "@baseboard_fab2_lib.baseboard_fab2(sch_1):page215_i341"
				( attribute "CDS_LIB" "mstr_discrete"
					( Origin gPackager )
				)
				( attribute "CDS_LOCATION" "R3U10"
					( Origin gPackager )
				)
				( attribute "CDS_SEC" "1"
					( Origin gPackager )
				)
				( attribute "LOCATION" "R3U10"
					( Origin gFrontEnd )
				)
				( attribute "MATERIAL" "CHIP"
					( Origin gFrontEnd )
				)
				( attribute "PACK_TYPE" "0402"
					( Origin gFrontEnd )
				)
				( attribute "PART_NUMBER" "G21497-005"
					( Origin gFrontEnd )
				)
				( attribute "PHYS_PAGE" "215"
					( Origin gFrontEnd )
				)
				( attribute "ROOM" "PVCCIN_CPU0_VR"
					( Origin gFrontEnd )
				)
				( attribute "ROT" "0"
					( Origin gFrontEnd )
				)
				( attribute "SEC" "1"
					( Origin gPackager )
				)
				( attribute "TOLERANCE" "5%"
					( Origin gFrontEnd )
				)
				( attribute "VALUE" "0.0"
					( Origin gFrontEnd )
				)
				( attribute "VER" "1"
					( Origin gFrontEnd )
				)
				( attribute "WATTAGE" "1/16W"
					( Origin gFrontEnd )
				)
				( attribute "XY" "(-1225,2775)"
					( Origin gFrontEnd )
				)
				( attribute "CHIPS_PART_NAME" "RES"
					( Origin gPackager )
				)
				( attribute "CDS_PART_NAME" "RES_0402-0.0,5%,1/16W,CHIP,G21A"
					( Origin gPackager )
				)
				( objectStatus "R3U10" )
				( pin "a"
					( attribute "PN" "1"
						( Origin gPackager )
					)
					( objectStatus "R3U10.1" )
				)
				( pin "b"
					( attribute "PN" "2"
						( Origin gPackager )
					)
					( objectStatus "R3U10.2" )
				)
			)
			( gate "@baseboard_fab2_lib.baseboard_fab2(sch_1):page215_i342"
				( attribute "CDS_LIB" "mstr_discrete"
					( Origin gPackager )
				)
				( attribute "CDS_LOCATION" "C7G4"
					( Origin gPackager )
				)
				( attribute "CDS_SEC" "1"
					( Origin gPackager )
				)
				( attribute "LOCATION" "C7G4"
					( Origin gFrontEnd )
				)
				( attribute "MATERIAL" "X7R"
					( Origin gFrontEnd )
				)
				( attribute "NO_XNET_CONNECTION" "1"
					( Origin gFrontEnd )
				)
				( attribute "PACK_TYPE" "0402LF"
					( Origin gFrontEnd )
				)
				( attribute "PART_NUMBER" "A36096-050"
					( Origin gFrontEnd )
				)
				( attribute "PHYS_PAGE" "215"
					( Origin gFrontEnd )
				)
				( attribute "ROOM" "VDDQ_ABC_PWR_VR"
					( Origin gFrontEnd )
				)
				( attribute "ROT" "0"
					( Origin gFrontEnd )
				)
				( attribute "SEC" "1"
					( Origin gFrontEnd )
				)
				( attribute "SEC_TYPE" "0402LF"
					( Origin gFrontEnd )
				)
				( attribute "TOLERANCE" "10%"
					( Origin gFrontEnd )
				)
				( attribute "VALUE" "220PF"
					( Origin gFrontEnd )
				)
				( attribute "VER" "1"
					( Origin gFrontEnd )
				)
				( attribute "VOLTAGE" "50V"
					( Units "uVoltage" "V" 1.000000)
					( Origin gFrontEnd )
				)
				( attribute "XY" "(-850,1150)"
					( Origin gFrontEnd )
				)
				( attribute "CHIPS_PART_NAME" "CAP"
					( Origin gPackager )
				)
				( attribute "CDS_PART_NAME" "CAP_0402LF-220PF,50V,10%,X7R,AA"
					( Origin gPackager )
				)
				( objectStatus "C7G4" )
				( pin "a"
					( attribute "PN" "1"
						( Origin gPackager )
					)
					( objectStatus "C7G4.1" )
				)
				( pin "b"
					( attribute "PN" "2"
						( Origin gPackager )
					)
					( objectStatus "C7G4.2" )
				)
			)
			( gate "@baseboard_fab2_lib.baseboard_fab2(sch_1):page215_i343"
				( attribute "CDS_LIB" "mstr_discrete"
					( Origin gPackager )
				)
				( attribute "CDS_LOCATION" "R7F21"
					( Origin gPackager )
				)
				( attribute "CDS_SEC" "1"
					( Origin gPackager )
				)
				( attribute "LOCATION" "R7F21"
					( Origin gFrontEnd )
				)
				( attribute "MATERIAL" "CHIP"
					( Origin gFrontEnd )
				)
				( attribute "PACK_TYPE" "0402"
					( Origin gFrontEnd )
				)
				( attribute "PART_NUMBER" "G21497-005"
					( Origin gFrontEnd )
				)
				( attribute "PHYS_PAGE" "215"
					( Origin gFrontEnd )
				)
				( attribute "ROOM" "PVCCIN_CPU0_VR"
					( Origin gFrontEnd )
				)
				( attribute "ROT" "0"
					( Origin gFrontEnd )
				)
				( attribute "SEC" "1"
					( Origin gPackager )
				)
				( attribute "TOLERANCE" "5%"
					( Origin gFrontEnd )
				)
				( attribute "VALUE" "0.0"
					( Origin gFrontEnd )
				)
				( attribute "VER" "1"
					( Origin gFrontEnd )
				)
				( attribute "WATTAGE" "1/16W"
					( Origin gFrontEnd )
				)
				( attribute "XY" "(-975,1600)"
					( Origin gFrontEnd )
				)
				( attribute "CHIPS_PART_NAME" "RES"
					( Origin gPackager )
				)
				( attribute "CDS_PART_NAME" "RES_0402-0.0,5%,1/16W,CHIP,G21A"
					( Origin gPackager )
				)
				( objectStatus "R7F21" )
				( pin "a"
					( attribute "PN" "1"
						( Origin gPackager )
					)
					( objectStatus "R7F21.1" )
				)
				( pin "b"
					( attribute "PN" "2"
						( Origin gPackager )
					)
					( objectStatus "R7F21.2" )
				)
			)
			( gate "@baseboard_fab2_lib.baseboard_fab2(sch_1):page215_i344"
				( attribute "CDS_LIB" "mstr_discrete"
					( Origin gPackager )
				)
				( attribute "CDS_LOCATION" "R7G9"
					( Origin gPackager )
				)
				( attribute "CDS_SEC" "1"
					( Origin gPackager )
				)
				( attribute "LOCATION" "R7G9"
					( Origin gFrontEnd )
				)
				( attribute "MATERIAL" "CHIP"
					( Origin gFrontEnd )
				)
				( attribute "NO_XNET_CONNECTION" "1"
					( Origin gFrontEnd )
				)
				( attribute "PACK_TYPE" "0402"
					( Origin gFrontEnd )
				)
				( attribute "PART_NUMBER" "G21796-066"
					( Origin gFrontEnd )
				)
				( attribute "PHYS_PAGE" "215"
					( Origin gFrontEnd )
				)
				( attribute "ROOM" "VDDQ_ABC_PWR_VR"
					( Origin gFrontEnd )
				)
				( attribute "ROT" "0"
					( Origin gFrontEnd )
				)
				( attribute "SEC" "1"
					( Origin gFrontEnd )
				)
				( attribute "SEC_TYPE" "0402"
					( Origin gFrontEnd )
				)
				( attribute "TOLERANCE" "1%"
					( Origin gFrontEnd )
				)
				( attribute "VALUE" "10.0"
					( Origin gFrontEnd )
				)
				( attribute "VER" "1"
					( Origin gFrontEnd )
				)
				( attribute "WATTAGE" "1/16W"
					( Origin gFrontEnd )
				)
				( attribute "XY" "(-1125,1325)"
					( Origin gFrontEnd )
				)
				( attribute "CHIPS_PART_NAME" "RES"
					( Origin gPackager )
				)
				( attribute "CDS_PART_NAME" "RES_0402-10.0,1%,1/16W,CHIP,G2A"
					( Origin gPackager )
				)
				( objectStatus "R7G9" )
				( pin "a"
					( attribute "PN" "1"
						( Origin gPackager )
					)
					( objectStatus "R7G9.1" )
				)
				( pin "b"
					( attribute "PN" "2"
						( Origin gPackager )
					)
					( objectStatus "R7G9.2" )
				)
			)
			( gate "@baseboard_fab2_lib.baseboard_fab2(sch_1):page215_i358"
				( attribute "CDS_LIB" "mstr_controller"
					( Origin gPackager )
				)
				( attribute "CDS_LMAN_SYM_OUTLINE" "-400,900,400,-900"
					( Origin gPackager )
				)
				( attribute "CDS_LOCATION" "EU7G1"
					( Origin gPackager )
				)
				( attribute "CDS_SEC" "1"
					( Origin gPackager )
				)
				( attribute "LOCATION" "EU7G1"
					( Origin gFrontEnd )
				)
				( attribute "MATERIAL" "IC"
					( Origin gFrontEnd )
				)
				( attribute "PACK_TYPE" "QFN"
					( Origin gFrontEnd )
				)
				( attribute "PART_NUMBER" "H89186-001"
					( Origin gFrontEnd )
				)
				( attribute "PHYS_PAGE" "215"
					( Origin gFrontEnd )
				)
				( attribute "ROT" "0"
					( Origin gFrontEnd )
				)
				( attribute "SEC" "1"
					( Origin gPackager )
				)
				( attribute "VER" "2"
					( Origin gFrontEnd )
				)
				( attribute "XY" "(1725,1900)"
					( Origin gFrontEnd )
				)
				( attribute "CHIPS_PART_NAME" "PXM1310B"
					( Origin gPackager )
				)
				( attribute "CDS_PART_NAME" "PXM1310B_QFN-IC,H89186-001"
					( Origin gPackager )
				)
				( objectStatus "EU7G1" )
				( pin "airef1"
					( attribute "PN" "21"
						( Origin gPackager )
					)
					( objectStatus "EU7G1.21" )
				)
				( pin "airef2"
					( attribute "PN" "23"
						( Origin gPackager )
					)
					( objectStatus "EU7G1.23" )
				)
				( pin "airef3"
					( attribute "PN" "25"
						( Origin gPackager )
					)
					( objectStatus "EU7G1.25" )
				)
				( pin "aisen1"
					( attribute "PN" "22"
						( Origin gPackager )
					)
					( objectStatus "EU7G1.22" )
				)
				( pin "aisen2"
					( attribute "PN" "24"
						( Origin gPackager )
					)
					( objectStatus "EU7G1.24" )
				)
				( pin "aisen3"
					( attribute "PN" "26"
						( Origin gPackager )
					)
					( objectStatus "EU7G1.26" )
				)
				( pin "apwm1"
					( attribute "PN" "5"
						( Origin gPackager )
					)
					( objectStatus "EU7G1.5" )
				)
				( pin "apwm2"
					( attribute "PN" "4"
						( Origin gPackager )
					)
					( objectStatus "EU7G1.4" )
				)
				( pin "apwm3"
					( attribute "PN" "3"
						( Origin gPackager )
					)
					( objectStatus "EU7G1.3" )
				)
				( pin "atsen"
					( attribute "PN" "35"
						( Origin gPackager )
					)
					( objectStatus "EU7G1.35" )
				)
				( pin "avref"
					( attribute "PN" "20"
						( Origin gPackager )
					)
					( objectStatus "EU7G1.20" )
				)
				( pin "avren"
					( attribute "PN" "10"
						( Origin gPackager )
					)
					( objectStatus "EU7G1.10" )
				)
				( pin "avrrdy"
					( attribute "PN" "9"
						( Origin gPackager )
					)
					( objectStatus "EU7G1.9" )
				)
				( pin "avsen"
					( attribute "PN" "19"
						( Origin gPackager )
					)
					( objectStatus "EU7G1.19" )
				)
				( pin "biref1"
					( attribute "PN" "31"
						( Origin gPackager )
					)
					( objectStatus "EU7G1.31" )
				)
				( pin "bisen1"
					( attribute "PN" "32"
						( Origin gPackager )
					)
					( objectStatus "EU7G1.32" )
				)
				( pin "bpwm1"
					( attribute "PN" "1"
						( Origin gPackager )
					)
					( objectStatus "EU7G1.1" )
				)
				( pin "btsen"
					( attribute "PN" "34"
						( Origin gPackager )
					)
					( objectStatus "EU7G1.34" )
				)
				( pin "bvref"
					( attribute "PN" "30"
						( Origin gPackager )
					)
					( objectStatus "EU7G1.30" )
				)
				( pin "bvsen"
					( attribute "PN" "29"
						( Origin gPackager )
					)
					( objectStatus "EU7G1.29" )
				)
				( pin "dnc(0)"
					( attribute "PN" "2"
						( Origin gPackager )
					)
					( objectStatus "EU7G1.2" )
				)
				( pin "dnc(1)"
					( attribute "PN" "28"
						( Origin gPackager )
					)
					( objectStatus "EU7G1.28" )
				)
				( pin "gnd"
					( attribute "PN" "27"
						( Origin gPackager )
					)
					( objectStatus "EU7G1.27" )
				)
				( pin "iinsen"
					( attribute "PN" "38"
						( Origin gPackager )
					)
					( objectStatus "EU7G1.38" )
				)
				( pin "mp0"
					( attribute "PN" "13"
						( Origin gPackager )
					)
					( objectStatus "EU7G1.13" )
				)
				( pin "mp1"
					( attribute "PN" "14"
						( Origin gPackager )
					)
					( objectStatus "EU7G1.14" )
				)
				( pin "mp2"
					( attribute "PN" "18"
						( Origin gPackager )
					)
					( objectStatus "EU7G1.18" )
				)
				( pin "pinalrt_n"
					( attribute "PN" "12"
						( Origin gPackager )
					)
					( objectStatus "EU7G1.12" )
				)
				( pin "reset_n"
					( attribute "PN" "8"
						( Origin gPackager )
					)
					( objectStatus "EU7G1.8" )
				)
				( pin "scl"
					( attribute "PN" "7"
						( Origin gPackager )
					)
					( objectStatus "EU7G1.7" )
				)
				( pin "sda"
					( attribute "PN" "6"
						( Origin gPackager )
					)
					( objectStatus "EU7G1.6" )
				)
				( pin "thpad"
					( attribute "PN" "41"
						( Origin gPackager )
					)
					( objectStatus "EU7G1.41" )
				)
				( pin "valrt_n"
					( attribute "PN" "17"
						( Origin gPackager )
					)
					( objectStatus "EU7G1.17" )
				)
				( pin "vclk"
					( attribute "PN" "15"
						( Origin gPackager )
					)
					( objectStatus "EU7G1.15" )
				)
				( pin "vd12"
					( attribute "PN" "40"
						( Origin gPackager )
					)
					( objectStatus "EU7G1.40" )
				)
				( pin "vdd"
					( attribute "PN" "39"
						( Origin gPackager )
					)
					( objectStatus "EU7G1.39" )
				)
				( pin "vdio"
					( attribute "PN" "16"
						( Origin gPackager )
					)
					( objectStatus "EU7G1.16" )
				)
				( pin "vinsen"
					( attribute "PN" "37"
						( Origin gPackager )
					)
					( objectStatus "EU7G1.37" )
				)
				( pin "vrhot_n"
					( attribute "PN" "11"
						( Origin gPackager )
					)
					( objectStatus "EU7G1.11" )
				)
				( pin "xaddr1"
					( attribute "PN" "36"
						( Origin gPackager )
					)
					( objectStatus "EU7G1.36" )
				)
				( pin "xaddr2"
					( attribute "PN" "33"
						( Origin gPackager )
					)
					( objectStatus "EU7G1.33" )
				)
			)
			( gate "@baseboard_fab2_lib.baseboard_fab2(sch_1):page215_i360"
				( attribute "CDS_LIB" "dev_discrete"
					( Origin gPackager )
				)
				( attribute "CDS_LOCATION" "C3U10"
					( Origin gPackager )
				)
				( attribute "CDS_SEC" "1"
					( Origin gPackager )
				)
				( attribute "LOCATION" "C3U10"
					( Origin gFrontEnd )
				)
				( attribute "MATERIAL" "X7R"
					( Origin gFrontEnd )
				)
				( attribute "PACK_TYPE" "0402V"
					( Origin gFrontEnd )
				)
				( attribute "PART_NUMBER" "A36096-030"
					( Origin gFrontEnd )
				)
				( attribute "PHYS_PAGE" "215"
					( Origin gFrontEnd )
				)
				( attribute "ROOM" "VDDQ_ABC_PWR_VR"
					( Origin gFrontEnd )
				)
				( attribute "ROT" "2"
					( Origin gFrontEnd )
				)
				( attribute "SEC" "1"
					( Origin gFrontEnd )
				)
				( attribute "SEC_TYPE" "0402V"
					( Origin gFrontEnd )
				)
				( attribute "TOLERANCE" "10%"
					( Origin gFrontEnd )
				)
				( attribute "VALUE" "0.1UF"
					( Origin gFrontEnd )
				)
				( attribute "VER" "1"
					( Origin gFrontEnd )
				)
				( attribute "VOLTAGE" "16V"
					( Units "uVoltage" "V" 1.000000)
					( Origin gFrontEnd )
				)
				( attribute "XY" "(-75,525)"
					( Origin gFrontEnd )
				)
				( attribute "CHIPS_PART_NAME" "CAP_A"
					( Origin gPackager )
				)
				( attribute "CDS_PART_NAME" "CAP_A_0402V-0.1UF,16V,10%,X7R,A"
					( Origin gPackager )
				)
				( objectStatus "C3U10" )
				( pin "a"
					( attribute "PN" "1"
						( Origin gPackager )
					)
					( objectStatus "C3U10.1" )
				)
				( pin "b"
					( attribute "PN" "2"
						( Origin gPackager )
					)
					( objectStatus "C3U10.2" )
				)
			)
			( gate "@baseboard_fab2_lib.baseboard_fab2(sch_1):page216_i6"
				( attribute "BOM_COST" "PROC_VRD_VCCIN_CPU0"
					( Origin gFrontEnd )
				)
				( attribute "CDS_LIB" "mstr_discrete"
					( Origin gPackager )
				)
				( attribute "CDS_LOCATION" "C6G3"
					( Origin gPackager )
				)
				( attribute "CDS_SEC" "1"
					( Origin gPackager )
				)
				( attribute "LOCATION" "C6G3"
					( Origin gFrontEnd )
				)
				( attribute "MATERIAL" "X6S"
					( Origin gFrontEnd )
				)
				( attribute "PACK_TYPE" "0805LF"
					( Origin gFrontEnd )
				)
				( attribute "PART_NUMBER" "C95333-002"
					( Origin gFrontEnd )
				)
				( attribute "PHYS_PAGE" "216"
					( Origin gFrontEnd )
				)
				( attribute "ROOM" "VDDQ_ABC_PWR_VR"
					( Origin gFrontEnd )
				)
				( attribute "ROT" "0"
					( Origin gFrontEnd )
				)
				( attribute "SEC" "1"
					( Origin gFrontEnd )
				)
				( attribute "SEC_TYPE" "0805LF"
					( Origin gFrontEnd )
				)
				( attribute "TOLERANCE" "20%"
					( Origin gFrontEnd )
				)
				( attribute "VALUE" "22UF"
					( Origin gFrontEnd )
				)
				( attribute "VER" "1"
					( Origin gFrontEnd )
				)
				( attribute "VOLTAGE" "4V"
					( Units "uVoltage" "V" 1.000000)
					( Origin gFrontEnd )
				)
				( attribute "XY" "(4000,1750)"
					( Origin gFrontEnd )
				)
				( attribute "CHIPS_PART_NAME" "CAP"
					( Origin gPackager )
				)
				( attribute "CDS_PART_NAME" "CAP_0805LF-22UF,4V,20%,X6S,C95A"
					( Origin gPackager )
				)
				( objectStatus "C6G3" )
				( pin "a"
					( attribute "PN" "1"
						( Origin gPackager )
					)
					( objectStatus "C6G3.1" )
				)
				( pin "b"
					( attribute "PN" "2"
						( Origin gPackager )
					)
					( objectStatus "C6G3.2" )
				)
			)
			( gate "@baseboard_fab2_lib.baseboard_fab2(sch_1):page216_i44"
				( attribute "CDS_LIB" "mstr_discrete"
					( Origin gPackager )
				)
				( attribute "CDS_LOCATION" "C7G31"
					( Origin gPackager )
				)
				( attribute "CDS_SEC" "1"
					( Origin gPackager )
				)
				( attribute "LOCATION" "C7G31"
					( Origin gFrontEnd )
				)
				( attribute "MATERIAL" "X7R"
					( Origin gFrontEnd )
				)
				( attribute "PACK_TYPE" "0402"
					( Origin gFrontEnd )
				)
				( attribute "PART_NUMBER" "A36096-104"
					( Origin gFrontEnd )
				)
				( attribute "PHYS_PAGE" "216"
					( Origin gFrontEnd )
				)
				( attribute "ROOM" "VDDQ_ABC_PWR_VR"
					( Origin gFrontEnd )
				)
				( attribute "ROT" "2"
					( Origin gFrontEnd )
				)
				( attribute "SEC" "1"
					( Origin gFrontEnd )
				)
				( attribute "SEC_TYPE" "0402"
					( Origin gFrontEnd )
				)
				( attribute "SPOF" "TRUE"
					( Origin gFrontEnd )
				)
				( attribute "TOLERANCE" "10%"
					( Origin gFrontEnd )
				)
				( attribute "VALUE" "0.220UF"
					( Origin gFrontEnd )
				)
				( attribute "VER" "1"
					( Origin gFrontEnd )
				)
				( attribute "VOLTAGE" "16V"
					( Units "uVoltage" "V" 1.000000)
					( Origin gFrontEnd )
				)
				( attribute "XY" "(-1025,1875)"
					( Origin gFrontEnd )
				)
				( attribute "CHIPS_PART_NAME" "CAP"
					( Origin gPackager )
				)
				( attribute "CDS_PART_NAME" "CAP_0402-0.220UF,16V,10%,X7R,AA"
					( Origin gPackager )
				)
				( objectStatus "C7G31" )
				( pin "a"
					( attribute "PN" "1"
						( Origin gPackager )
					)
					( objectStatus "C7G31.1" )
				)
				( pin "b"
					( attribute "PN" "2"
						( Origin gPackager )
					)
					( objectStatus "C7G31.2" )
				)
			)
			( gate "@baseboard_fab2_lib.baseboard_fab2(sch_1):page216_i45"
				( attribute "CDS_LIB" "mstr_discrete"
					( Origin gPackager )
				)
				( attribute "CDS_LOCATION" "C3U2"
					( Origin gPackager )
				)
				( attribute "CDS_SEC" "1"
					( Origin gPackager )
				)
				( attribute "LOCATION" "C3U2"
					( Origin gFrontEnd )
				)
				( attribute "MATERIAL" "X6S"
					( Origin gFrontEnd )
				)
				( attribute "PACK_TYPE" "0805"
					( Origin gFrontEnd )
				)
				( attribute "PART_NUMBER" "C95333-007"
					( Origin gFrontEnd )
				)
				( attribute "PHYS_PAGE" "216"
					( Origin gFrontEnd )
				)
				( attribute "ROOM" "VDDQ_ABC_PWR_VR"
					( Origin gFrontEnd )
				)
				( attribute "ROT" "0"
					( Origin gFrontEnd )
				)
				( attribute "SEC" "1"
					( Origin gFrontEnd )
				)
				( attribute "SEC_TYPE" "0805"
					( Origin gFrontEnd )
				)
				( attribute "TOLERANCE" "10%"
					( Origin gFrontEnd )
				)
				( attribute "VALUE" "10UF"
					( Origin gFrontEnd )
				)
				( attribute "VER" "1"
					( Origin gFrontEnd )
				)
				( attribute "VOLTAGE" "16V"
					( Units "uVoltage" "V" 1.000000)
					( Origin gFrontEnd )
				)
				( attribute "XY" "(-2675,2525)"
					( Origin gFrontEnd )
				)
				( attribute "CHIPS_PART_NAME" "CAP"
					( Origin gPackager )
				)
				( attribute "CDS_PART_NAME" "CAP_0805-10UF,16V,10%,X6S,C953A"
					( Origin gPackager )
				)
				( objectStatus "C3U2" )
				( pin "a"
					( attribute "PN" "1"
						( Origin gPackager )
					)
					( objectStatus "C3U2.1" )
				)
				( pin "b"
					( attribute "PN" "2"
						( Origin gPackager )
					)
					( objectStatus "C3U2.2" )
				)
			)
			( gate "@baseboard_fab2_lib.baseboard_fab2(sch_1):page216_i46"
				( attribute "CDS_LIB" "mstr_discrete"
					( Origin gPackager )
				)
				( attribute "CDS_LOCATION" "C3U3"
					( Origin gPackager )
				)
				( attribute "CDS_SEC" "1"
					( Origin gPackager )
				)
				( attribute "LOCATION" "C3U3"
					( Origin gFrontEnd )
				)
				( attribute "MATERIAL" "X6S"
					( Origin gFrontEnd )
				)
				( attribute "PACK_TYPE" "0805"
					( Origin gFrontEnd )
				)
				( attribute "PART_NUMBER" "C95333-007"
					( Origin gFrontEnd )
				)
				( attribute "PHYS_PAGE" "216"
					( Origin gFrontEnd )
				)
				( attribute "ROOM" "VDDQ_ABC_PWR_VR"
					( Origin gFrontEnd )
				)
				( attribute "ROT" "0"
					( Origin gFrontEnd )
				)
				( attribute "SEC" "1"
					( Origin gFrontEnd )
				)
				( attribute "SEC_TYPE" "0805"
					( Origin gFrontEnd )
				)
				( attribute "TOLERANCE" "10%"
					( Origin gFrontEnd )
				)
				( attribute "VALUE" "10UF"
					( Origin gFrontEnd )
				)
				( attribute "VER" "1"
					( Origin gFrontEnd )
				)
				( attribute "VOLTAGE" "16V"
					( Units "uVoltage" "V" 1.000000)
					( Origin gFrontEnd )
				)
				( attribute "XY" "(-2425,2525)"
					( Origin gFrontEnd )
				)
				( attribute "CHIPS_PART_NAME" "CAP"
					( Origin gPackager )
				)
				( attribute "CDS_PART_NAME" "CAP_0805-10UF,16V,10%,X6S,C953A"
					( Origin gPackager )
				)
				( objectStatus "C3U3" )
				( pin "a"
					( attribute "PN" "1"
						( Origin gPackager )
					)
					( objectStatus "C3U3.1" )
				)
				( pin "b"
					( attribute "PN" "2"
						( Origin gPackager )
					)
					( objectStatus "C3U3.2" )
				)
			)
			( gate "@baseboard_fab2_lib.baseboard_fab2(sch_1):page216_i47"
				( attribute "CDS_LIB" "mstr_discrete"
					( Origin gPackager )
				)
				( attribute "CDS_LOCATION" "C3U4"
					( Origin gPackager )
				)
				( attribute "CDS_SEC" "1"
					( Origin gPackager )
				)
				( attribute "LOCATION" "C3U4"
					( Origin gFrontEnd )
				)
				( attribute "MATERIAL" "X6S"
					( Origin gFrontEnd )
				)
				( attribute "PACK_TYPE" "0805"
					( Origin gFrontEnd )
				)
				( attribute "PART_NUMBER" "C95333-007"
					( Origin gFrontEnd )
				)
				( attribute "PHYS_PAGE" "216"
					( Origin gFrontEnd )
				)
				( attribute "ROOM" "VDDQ_ABC_PWR_VR"
					( Origin gFrontEnd )
				)
				( attribute "ROT" "0"
					( Origin gFrontEnd )
				)
				( attribute "SEC" "1"
					( Origin gFrontEnd )
				)
				( attribute "SEC_TYPE" "0805"
					( Origin gFrontEnd )
				)
				( attribute "TOLERANCE" "10%"
					( Origin gFrontEnd )
				)
				( attribute "VALUE" "10UF"
					( Origin gFrontEnd )
				)
				( attribute "VER" "1"
					( Origin gFrontEnd )
				)
				( attribute "VOLTAGE" "16V"
					( Units "uVoltage" "V" 1.000000)
					( Origin gFrontEnd )
				)
				( attribute "XY" "(-2150,2550)"
					( Origin gFrontEnd )
				)
				( attribute "CHIPS_PART_NAME" "CAP"
					( Origin gPackager )
				)
				( attribute "CDS_PART_NAME" "CAP_0805-10UF,16V,10%,X6S,C953A"
					( Origin gPackager )
				)
				( objectStatus "C3U4" )
				( pin "a"
					( attribute "PN" "1"
						( Origin gPackager )
					)
					( objectStatus "C3U4.1" )
				)
				( pin "b"
					( attribute "PN" "2"
						( Origin gPackager )
					)
					( objectStatus "C3U4.2" )
				)
			)
			( gate "@baseboard_fab2_lib.baseboard_fab2(sch_1):page216_i48"
				( attribute "CDS_LIB" "mstr_discrete"
					( Origin gPackager )
				)
				( attribute "CDS_LOCATION" "C7G37"
					( Origin gPackager )
				)
				( attribute "CDS_SEC" "1"
					( Origin gPackager )
				)
				( attribute "LOCATION" "C7G37"
					( Origin gFrontEnd )
				)
				( attribute "MATERIAL" "X6S"
					( Origin gFrontEnd )
				)
				( attribute "PACK_TYPE" "0402"
					( Origin gFrontEnd )
				)
				( attribute "PART_NUMBER" "D97712-011"
					( Origin gFrontEnd )
				)
				( attribute "PHYS_PAGE" "216"
					( Origin gFrontEnd )
				)
				( attribute "ROOM" "VDDQ_ABC_PWR_VR"
					( Origin gFrontEnd )
				)
				( attribute "ROT" "0"
					( Origin gFrontEnd )
				)
				( attribute "SEC" "1"
					( Origin gFrontEnd )
				)
				( attribute "SEC_TYPE" "0402"
					( Origin gFrontEnd )
				)
				( attribute "TOLERANCE" "10%"
					( Origin gFrontEnd )
				)
				( attribute "VALUE" "1.0UF"
					( Origin gFrontEnd )
				)
				( attribute "VER" "1"
					( Origin gFrontEnd )
				)
				( attribute "VOLTAGE" "16V"
					( Units "uVoltage" "V" 1.000000)
					( Origin gFrontEnd )
				)
				( attribute "XY" "(-1900,2475)"
					( Origin gFrontEnd )
				)
				( attribute "CHIPS_PART_NAME" "CAP"
					( Origin gPackager )
				)
				( attribute "CDS_PART_NAME" "CAP_0402-1.0UF,16V,10%,X6S,D97A"
					( Origin gPackager )
				)
				( objectStatus "C7G37" )
				( pin "a"
					( attribute "PN" "1"
						( Origin gPackager )
					)
					( objectStatus "C7G37.1" )
				)
				( pin "b"
					( attribute "PN" "2"
						( Origin gPackager )
					)
					( objectStatus "C7G37.2" )
				)
			)
			( gate "@baseboard_fab2_lib.baseboard_fab2(sch_1):page216_i50"
				( attribute "CDS_LIB" "mstr_discrete"
					( Origin gPackager )
				)
				( attribute "CDS_LOCATION" "C7G33"
					( Origin gPackager )
				)
				( attribute "CDS_SEC" "1"
					( Origin gPackager )
				)
				( attribute "LOCATION" "C7G33"
					( Origin gFrontEnd )
				)
				( attribute "MATERIAL" "X6S"
					( Origin gFrontEnd )
				)
				( attribute "PACK_TYPE" "0402"
					( Origin gFrontEnd )
				)
				( attribute "PART_NUMBER" "D97712-011"
					( Origin gFrontEnd )
				)
				( attribute "PHYS_PAGE" "216"
					( Origin gFrontEnd )
				)
				( attribute "ROOM" "VDDQ_ABC_PWR_VR"
					( Origin gFrontEnd )
				)
				( attribute "ROT" "0"
					( Origin gFrontEnd )
				)
				( attribute "SEC" "1"
					( Origin gFrontEnd )
				)
				( attribute "SEC_TYPE" "0402"
					( Origin gFrontEnd )
				)
				( attribute "TOLERANCE" "10%"
					( Origin gFrontEnd )
				)
				( attribute "VALUE" "1.0UF"
					( Origin gFrontEnd )
				)
				( attribute "VER" "1"
					( Origin gFrontEnd )
				)
				( attribute "VOLTAGE" "16V"
					( Units "uVoltage" "V" 1.000000)
					( Origin gFrontEnd )
				)
				( attribute "XY" "(-1400,2475)"
					( Origin gFrontEnd )
				)
				( attribute "CHIPS_PART_NAME" "CAP"
					( Origin gPackager )
				)
				( attribute "CDS_PART_NAME" "CAP_0402-1.0UF,16V,10%,X6S,D97A"
					( Origin gPackager )
				)
				( objectStatus "C7G33" )
				( pin "a"
					( attribute "PN" "1"
						( Origin gPackager )
					)
					( objectStatus "C7G33.1" )
				)
				( pin "b"
					( attribute "PN" "2"
						( Origin gPackager )
					)
					( objectStatus "C7G33.2" )
				)
			)
			( gate "@baseboard_fab2_lib.baseboard_fab2(sch_1):page216_i51"
				( attribute "CDS_LIB" "dev_discrete"
					( Origin gPackager )
				)
				( attribute "CDS_LOCATION" "C7G29"
					( Origin gPackager )
				)
				( attribute "CDS_SEC" "1"
					( Origin gPackager )
				)
				( attribute "LOCATION" "C7G29"
					( Origin gFrontEnd )
				)
				( attribute "MATERIAL" "X7R"
					( Origin gFrontEnd )
				)
				( attribute "PACK_TYPE" "0402V"
					( Origin gFrontEnd )
				)
				( attribute "PART_NUMBER" "A36096-030"
					( Origin gFrontEnd )
				)
				( attribute "PHYS_PAGE" "216"
					( Origin gFrontEnd )
				)
				( attribute "ROOM" "VDDQ_ABC_PWR_VR"
					( Origin gFrontEnd )
				)
				( attribute "ROT" "0"
					( Origin gFrontEnd )
				)
				( attribute "SEC" "1"
					( Origin gFrontEnd )
				)
				( attribute "SEC_TYPE" "0402V"
					( Origin gFrontEnd )
				)
				( attribute "TOLERANCE" "10%"
					( Origin gFrontEnd )
				)
				( attribute "VALUE" "0.1UF"
					( Origin gFrontEnd )
				)
				( attribute "VER" "1"
					( Origin gFrontEnd )
				)
				( attribute "VOLTAGE" "16V"
					( Units "uVoltage" "V" 1.000000)
					( Origin gFrontEnd )
				)
				( attribute "XY" "(-1650,2475)"
					( Origin gFrontEnd )
				)
				( attribute "CHIPS_PART_NAME" "CAP_A"
					( Origin gPackager )
				)
				( attribute "CDS_PART_NAME" "CAP_A_0402V-0.1UF,16V,10%,X7R,A"
					( Origin gPackager )
				)
				( objectStatus "C7G29" )
				( pin "a"
					( attribute "PN" "1"
						( Origin gPackager )
					)
					( objectStatus "C7G29.1" )
				)
				( pin "b"
					( attribute "PN" "2"
						( Origin gPackager )
					)
					( objectStatus "C7G29.2" )
				)
			)
			( gate "@baseboard_fab2_lib.baseboard_fab2(sch_1):page216_i52"
				( attribute "CDS_LIB" "mstr_discrete"
					( Origin gPackager )
				)
				( attribute "CDS_LOCATION" "R3U6"
					( Origin gPackager )
				)
				( attribute "CDS_SEC" "1"
					( Origin gPackager )
				)
				( attribute "LOCATION" "R3U6"
					( Origin gFrontEnd )
				)
				( attribute "MATERIAL" "CHIP"
					( Origin gFrontEnd )
				)
				( attribute "PACK_TYPE" "0402"
					( Origin gFrontEnd )
				)
				( attribute "PART_NUMBER" "G21796-090"
					( Origin gFrontEnd )
				)
				( attribute "PHYS_PAGE" "216"
					( Origin gFrontEnd )
				)
				( attribute "ROOM" "VDDQ_ABC_PWR_VR"
					( Origin gFrontEnd )
				)
				( attribute "ROT" "0"
					( Origin gFrontEnd )
				)
				( attribute "SEC" "1"
					( Origin gFrontEnd )
				)
				( attribute "SEC_TYPE" "0402"
					( Origin gFrontEnd )
				)
				( attribute "TOLERANCE" "1%"
					( Origin gFrontEnd )
				)
				( attribute "VALUE" "1.0"
					( Origin gFrontEnd )
				)
				( attribute "VER" "1"
					( Origin gFrontEnd )
				)
				( attribute "WATTAGE" "1/16W"
					( Origin gFrontEnd )
				)
				( attribute "XY" "(-1175,3050)"
					( Origin gFrontEnd )
				)
				( attribute "CHIPS_PART_NAME" "RES"
					( Origin gPackager )
				)
				( attribute "CDS_PART_NAME" "RES_0402-1.0,1%,1/16W,CHIP,G21A"
					( Origin gPackager )
				)
				( objectStatus "R3U6" )
				( pin "a"
					( attribute "PN" "1"
						( Origin gPackager )
					)
					( objectStatus "R3U6.1" )
				)
				( pin "b"
					( attribute "PN" "2"
						( Origin gPackager )
					)
					( objectStatus "R3U6.2" )
				)
			)
			( gate "@baseboard_fab2_lib.baseboard_fab2(sch_1):page216_i53"
				( attribute "CDS_LIB" "dev_discrete"
					( Origin gPackager )
				)
				( attribute "CDS_LOCATION" "C7G35"
					( Origin gPackager )
				)
				( attribute "CDS_SEC" "1"
					( Origin gPackager )
				)
				( attribute "LOCATION" "C7G35"
					( Origin gFrontEnd )
				)
				( attribute "MATERIAL" "X6S"
					( Origin gFrontEnd )
				)
				( attribute "PACK_TYPE" "0402V"
					( Origin gFrontEnd )
				)
				( attribute "PART_NUMBER" "D97712-004"
					( Origin gFrontEnd )
				)
				( attribute "PHYS_PAGE" "216"
					( Origin gFrontEnd )
				)
				( attribute "ROOM" "VDDQ_ABC_PWR_VR"
					( Origin gFrontEnd )
				)
				( attribute "ROT" "2"
					( Origin gFrontEnd )
				)
				( attribute "SEC" "1"
					( Origin gFrontEnd )
				)
				( attribute "SEC_TYPE" "0402V"
					( Origin gFrontEnd )
				)
				( attribute "TOLERANCE" "10%"
					( Origin gFrontEnd )
				)
				( attribute "VALUE" "1.0UF"
					( Origin gFrontEnd )
				)
				( attribute "VER" "1"
					( Origin gFrontEnd )
				)
				( attribute "VOLTAGE" "6.3V"
					( Units "uVoltage" "V" 1.000000)
					( Origin gFrontEnd )
				)
				( attribute "XY" "(-675,2500)"
					( Origin gFrontEnd )
				)
				( attribute "CHIPS_PART_NAME" "CAP_A"
					( Origin gPackager )
				)
				( attribute "CDS_PART_NAME" "CAP_A_0402V-1.0UF,6.3V,10%,X6SA"
					( Origin gPackager )
				)
				( objectStatus "C7G35" )
				( pin "a"
					( attribute "PN" "1"
						( Origin gPackager )
					)
					( objectStatus "C7G35.1" )
				)
				( pin "b"
					( attribute "PN" "2"
						( Origin gPackager )
					)
					( objectStatus "C7G35.2" )
				)
			)
			( gate "@baseboard_fab2_lib.baseboard_fab2(sch_1):page216_i54"
				( attribute "CDS_LIB" "mstr_discrete"
					( Origin gPackager )
				)
				( attribute "CDS_LOCATION" "C7G34"
					( Origin gPackager )
				)
				( attribute "CDS_SEC" "1"
					( Origin gPackager )
				)
				( attribute "LOCATION" "C7G34"
					( Origin gFrontEnd )
				)
				( attribute "MATERIAL" "X7R"
					( Origin gFrontEnd )
				)
				( attribute "PACK_TYPE" "0402"
					( Origin gFrontEnd )
				)
				( attribute "PART_NUMBER" "A36096-155"
					( Origin gFrontEnd )
				)
				( attribute "PHYS_PAGE" "216"
					( Origin gFrontEnd )
				)
				( attribute "ROOM" "VDDQ_ABC_PWR_VR"
					( Origin gFrontEnd )
				)
				( attribute "ROT" "0"
					( Origin gFrontEnd )
				)
				( attribute "SEC" "1"
					( Origin gFrontEnd )
				)
				( attribute "SEC_TYPE" "0402"
					( Origin gFrontEnd )
				)
				( attribute "TOLERANCE" "10%"
					( Origin gFrontEnd )
				)
				( attribute "VALUE" "0.22UF"
					( Origin gFrontEnd )
				)
				( attribute "VER" "1"
					( Origin gFrontEnd )
				)
				( attribute "VOLTAGE" "16V"
					( Units "uVoltage" "V" 1.000000)
					( Origin gFrontEnd )
				)
				( attribute "XY" "(-500,2525)"
					( Origin gFrontEnd )
				)
				( attribute "CHIPS_PART_NAME" "CAP"
					( Origin gPackager )
				)
				( attribute "CDS_PART_NAME" "CAP_0402-0.22UF,16V,10%,X7R,A3A"
					( Origin gPackager )
				)
				( objectStatus "C7G34" )
				( pin "a"
					( attribute "PN" "1"
						( Origin gPackager )
					)
					( objectStatus "C7G34.1" )
				)
				( pin "b"
					( attribute "PN" "2"
						( Origin gPackager )
					)
					( objectStatus "C7G34.2" )
				)
			)
			( gate "@baseboard_fab2_lib.baseboard_fab2(sch_1):page210_i55"
				( attribute "CDS_LIB" "dev_discrete"
					( Origin gPackager )
				)
				( attribute "LOCATION" "CT57"
					( Origin gFrontEnd )
				)
				( attribute "MATERIAL" "X7R"
					( Origin gFrontEnd )
				)
				( attribute "PACK_TYPE" "0402V"
					( Origin gFrontEnd )
				)
				( attribute "PART_NUMBER" "A36096-030"
					( Origin gFrontEnd )
				)
				( attribute "PHYS_PAGE" "210"
					( Origin gFrontEnd )
				)
				( attribute "ROOM" "PVCCIN_CPU0_PWR_VR"
					( Origin gFrontEnd )
				)
				( attribute "ROT" "0"
					( Origin gFrontEnd )
				)
				( attribute "TOLERANCE" "10%"
					( Origin gFrontEnd )
				)
				( attribute "VALUE" "0.1UF"
					( Origin gFrontEnd )
				)
				( attribute "VER" "1"
					( Origin gFrontEnd )
				)
				( attribute "VOLTAGE" "16V"
					( Units "uVoltage" "V" 1.000000)
					( Origin gFrontEnd )
				)
				( attribute "XY" "(-4450,3100)"
					( Origin gFrontEnd )
				)
				( attribute "CHIPS_PART_NAME" "CAP_A"
					( Origin gPackager )
				)
				( attribute "CDS_PART_NAME" "CAP_A_0402V-0.1UF,16V,10%,X7R,A"
					( Origin gPackager )
				)
				( attribute "CDS_LOCATION" "CT57"
					( Origin gPackager )
				)
				( attribute "CDS_SEC" "1"
					( Origin gPackager )
				)
				( attribute "SEC" "1"
					( Origin gPackager )
				)
				( attribute "STATUS" "NOPOP"
					( Origin gFrontEnd )
				)
				( objectStatus "CT57" )
				( pin "a"
					( attribute "PN" "1"
						( Origin gPackager )
					)
					( objectStatus "CT57.1" )
				)
				( pin "b"
					( attribute "PN" "2"
						( Origin gPackager )
					)
					( objectStatus "CT57.2" )
				)
			)
			( gate "@baseboard_fab2_lib.baseboard_fab2(sch_1):page216_i65"
				( attribute "CDS_LIB" "mstr_discrete"
					( Origin gPackager )
				)
				( attribute "CDS_LOCATION" "L7G2"
					( Origin gPackager )
				)
				( attribute "CDS_SEC" "1"
					( Origin gPackager )
				)
				( attribute "LOCATION" "L7G2"
					( Origin gFrontEnd )
				)
				( attribute "MATERIAL" "IND"
					( Origin gFrontEnd )
				)
				( attribute "PACK_TYPE" "SM"
					( Origin gFrontEnd )
				)
				( attribute "PART_NUMBER" "D92183-034"
					( Origin gFrontEnd )
				)
				( attribute "PHYS_PAGE" "216"
					( Origin gFrontEnd )
				)
				( attribute "ROOM" "VDDQ_ABC_PWR_VR"
					( Origin gFrontEnd )
				)
				( attribute "ROT" "0"
					( Origin gFrontEnd )
				)
				( attribute "SEC" "1"
					( Origin gFrontEnd )
				)
				( attribute "SEC_TYPE" "SM"
					( Origin gFrontEnd )
				)
				( attribute "VALUE" "0.12UH"
					( Origin gFrontEnd )
				)
				( attribute "VER" "1"
					( Origin gFrontEnd )
				)
				( attribute "XY" "(3125,-425)"
					( Origin gFrontEnd )
				)
				( attribute "CHIPS_PART_NAME" "INDUCTOR"
					( Origin gPackager )
				)
				( attribute "CDS_PART_NAME" "INDUCTOR_SM-0.12UH,IND,D92183-A"
					( Origin gPackager )
				)
				( objectStatus "L7G2" )
				( pin "ina"
					( attribute "PN" "1"
						( Origin gPackager )
					)
					( objectStatus "L7G2.1" )
				)
				( pin "inb"
					( attribute "PN" "2"
						( Origin gPackager )
					)
					( objectStatus "L7G2.2" )
				)
			)
			( gate "@baseboard_fab2_lib.baseboard_fab2(sch_1):page216_i68"
				( attribute "BOM_COST" "PROC_VRD_VCCIN_CPU0"
					( Origin gFrontEnd )
				)
				( attribute "CDS_LIB" "mstr_discrete"
					( Origin gPackager )
				)
				( attribute "CDS_LOCATION" "C7G27"
					( Origin gPackager )
				)
				( attribute "CDS_SEC" "1"
					( Origin gPackager )
				)
				( attribute "LOCATION" "C7G27"
					( Origin gFrontEnd )
				)
				( attribute "MATERIAL" "X6S"
					( Origin gFrontEnd )
				)
				( attribute "PACK_TYPE" "0805LF"
					( Origin gFrontEnd )
				)
				( attribute "PART_NUMBER" "C95333-002"
					( Origin gFrontEnd )
				)
				( attribute "PHYS_PAGE" "216"
					( Origin gFrontEnd )
				)
				( attribute "ROOM" "VDDQ_ABC_PWR_VR"
					( Origin gFrontEnd )
				)
				( attribute "ROT" "0"
					( Origin gFrontEnd )
				)
				( attribute "SEC" "1"
					( Origin gFrontEnd )
				)
				( attribute "SEC_TYPE" "0805LF"
					( Origin gFrontEnd )
				)
				( attribute "TOLERANCE" "20%"
					( Origin gFrontEnd )
				)
				( attribute "VALUE" "22UF"
					( Origin gFrontEnd )
				)
				( attribute "VER" "1"
					( Origin gFrontEnd )
				)
				( attribute "VOLTAGE" "4V"
					( Units "uVoltage" "V" 1.000000)
					( Origin gFrontEnd )
				)
				( attribute "XY" "(4050,-625)"
					( Origin gFrontEnd )
				)
				( attribute "CHIPS_PART_NAME" "CAP"
					( Origin gPackager )
				)
				( attribute "CDS_PART_NAME" "CAP_0805LF-22UF,4V,20%,X6S,C95A"
					( Origin gPackager )
				)
				( objectStatus "C7G27" )
				( pin "a"
					( attribute "PN" "1"
						( Origin gPackager )
					)
					( objectStatus "C7G27.1" )
				)
				( pin "b"
					( attribute "PN" "2"
						( Origin gPackager )
					)
					( objectStatus "C7G27.2" )
				)
			)
			( gate "@baseboard_fab2_lib.baseboard_fab2(sch_1):page216_i72"
				( attribute "CDS_LIB" "mstr_discrete"
					( Origin gPackager )
				)
				( attribute "CDS_LOCATION" "C7G41"
					( Origin gPackager )
				)
				( attribute "CDS_SEC" "1"
					( Origin gPackager )
				)
				( attribute "LOCATION" "C7G41"
					( Origin gFrontEnd )
				)
				( attribute "MATERIAL" "X7R"
					( Origin gFrontEnd )
				)
				( attribute "PACK_TYPE" "0402"
					( Origin gFrontEnd )
				)
				( attribute "PART_NUMBER" "A36096-155"
					( Origin gFrontEnd )
				)
				( attribute "PHYS_PAGE" "216"
					( Origin gFrontEnd )
				)
				( attribute "ROOM" "VDDQ_ABC_PWR_VR"
					( Origin gFrontEnd )
				)
				( attribute "ROT" "0"
					( Origin gFrontEnd )
				)
				( attribute "SEC" "1"
					( Origin gFrontEnd )
				)
				( attribute "SEC_TYPE" "0402"
					( Origin gFrontEnd )
				)
				( attribute "TOLERANCE" "10%"
					( Origin gFrontEnd )
				)
				( attribute "VALUE" "0.22UF"
					( Origin gFrontEnd )
				)
				( attribute "VER" "1"
					( Origin gFrontEnd )
				)
				( attribute "VOLTAGE" "16V"
					( Units "uVoltage" "V" 1.000000)
					( Origin gFrontEnd )
				)
				( attribute "XY" "(-450,150)"
					( Origin gFrontEnd )
				)
				( attribute "CHIPS_PART_NAME" "CAP"
					( Origin gPackager )
				)
				( attribute "CDS_PART_NAME" "CAP_0402-0.22UF,16V,10%,X7R,A3A"
					( Origin gPackager )
				)
				( objectStatus "C7G41" )
				( pin "a"
					( attribute "PN" "1"
						( Origin gPackager )
					)
					( objectStatus "C7G41.1" )
				)
				( pin "b"
					( attribute "PN" "2"
						( Origin gPackager )
					)
					( objectStatus "C7G41.2" )
				)
			)
			( gate "@baseboard_fab2_lib.baseboard_fab2(sch_1):page216_i73"
				( attribute "CDS_LIB" "dev_discrete"
					( Origin gPackager )
				)
				( attribute "CDS_LOCATION" "C7G42"
					( Origin gPackager )
				)
				( attribute "CDS_SEC" "1"
					( Origin gPackager )
				)
				( attribute "LOCATION" "C7G42"
					( Origin gFrontEnd )
				)
				( attribute "MATERIAL" "X6S"
					( Origin gFrontEnd )
				)
				( attribute "PACK_TYPE" "0402V"
					( Origin gFrontEnd )
				)
				( attribute "PART_NUMBER" "D97712-004"
					( Origin gFrontEnd )
				)
				( attribute "PHYS_PAGE" "216"
					( Origin gFrontEnd )
				)
				( attribute "ROOM" "VDDQ_ABC_PWR_VR"
					( Origin gFrontEnd )
				)
				( attribute "ROT" "2"
					( Origin gFrontEnd )
				)
				( attribute "SEC" "1"
					( Origin gFrontEnd )
				)
				( attribute "SEC_TYPE" "0402V"
					( Origin gFrontEnd )
				)
				( attribute "TOLERANCE" "10%"
					( Origin gFrontEnd )
				)
				( attribute "VALUE" "1.0UF"
					( Origin gFrontEnd )
				)
				( attribute "VER" "1"
					( Origin gFrontEnd )
				)
				( attribute "VOLTAGE" "6.3V"
					( Units "uVoltage" "V" 1.000000)
					( Origin gFrontEnd )
				)
				( attribute "XY" "(-575,150)"
					( Origin gFrontEnd )
				)
				( attribute "CHIPS_PART_NAME" "CAP_A"
					( Origin gPackager )
				)
				( attribute "CDS_PART_NAME" "CAP_A_0402V-1.0UF,6.3V,10%,X6SA"
					( Origin gPackager )
				)
				( objectStatus "C7G42" )
				( pin "a"
					( attribute "PN" "1"
						( Origin gPackager )
					)
					( objectStatus "C7G42.1" )
				)
				( pin "b"
					( attribute "PN" "2"
						( Origin gPackager )
					)
					( objectStatus "C7G42.2" )
				)
			)
			( gate "@baseboard_fab2_lib.baseboard_fab2(sch_1):page236_i142"
				( attribute "BOM_COST" "DEBUG"
					( Origin gFrontEnd )
				)
				( attribute "CDS_LIB" "mstr_discrete"
					( Origin gPackager )
				)
				( attribute "LOCATION" "RT46"
					( Origin gFrontEnd )
				)
				( attribute "MATERIAL" "CHIP"
					( Origin gFrontEnd )
				)
				( attribute "PACK_TYPE" "0402"
					( Origin gFrontEnd )
				)
				( attribute "PART_NUMBER" "G21497-005"
					( Origin gFrontEnd )
				)
				( attribute "PHYS_PAGE" "236"
					( Origin gFrontEnd )
				)
				( attribute "ROOM" "BMC_DEBUG_HEADER"
					( Origin gFrontEnd )
				)
				( attribute "ROT" "0"
					( Origin gFrontEnd )
				)
				( attribute "TOLERANCE" "5%"
					( Origin gFrontEnd )
				)
				( attribute "VALUE" "0.0"
					( Origin gFrontEnd )
				)
				( attribute "VER" "1"
					( Origin gFrontEnd )
				)
				( attribute "WATTAGE" "1/16W"
					( Origin gFrontEnd )
				)
				( attribute "XY" "(7900,2300)"
					( Origin gFrontEnd )
				)
				( attribute "CHIPS_PART_NAME" "RES"
					( Origin gPackager )
				)
				( attribute "CDS_PART_NAME" "RES_0402-0.0,5%,1/16W,CHIP,G21A"
					( Origin gPackager )
				)
				( attribute "CDS_LOCATION" "RT46"
					( Origin gPackager )
				)
				( attribute "CDS_SEC" "1"
					( Origin gPackager )
				)
				( attribute "SEC" "1"
					( Origin gPackager )
				)
				( objectStatus "RT46" )
				( pin "a"
					( attribute "PN" "1"
						( Origin gPackager )
					)
					( objectStatus "RT46.1" )
				)
				( pin "b"
					( attribute "PN" "2"
						( Origin gPackager )
					)
					( objectStatus "RT46.2" )
				)
			)
			( gate "@baseboard_fab2_lib.baseboard_fab2(sch_1):page216_i76"
				( attribute "CDS_LIB" "mstr_discrete"
					( Origin gPackager )
				)
				( attribute "CDS_LOCATION" "R3U9"
					( Origin gPackager )
				)
				( attribute "CDS_SEC" "1"
					( Origin gPackager )
				)
				( attribute "LOCATION" "R3U9"
					( Origin gFrontEnd )
				)
				( attribute "MATERIAL" "CHIP"
					( Origin gFrontEnd )
				)
				( attribute "PACK_TYPE" "0402"
					( Origin gFrontEnd )
				)
				( attribute "PART_NUMBER" "G21796-090"
					( Origin gFrontEnd )
				)
				( attribute "PHYS_PAGE" "216"
					( Origin gFrontEnd )
				)
				( attribute "ROOM" "VDDQ_ABC_PWR_VR"
					( Origin gFrontEnd )
				)
				( attribute "ROT" "0"
					( Origin gFrontEnd )
				)
				( attribute "SEC" "1"
					( Origin gFrontEnd )
				)
				( attribute "SEC_TYPE" "0402"
					( Origin gFrontEnd )
				)
				( attribute "TOLERANCE" "1%"
					( Origin gFrontEnd )
				)
				( attribute "VALUE" "1.0"
					( Origin gFrontEnd )
				)
				( attribute "VER" "1"
					( Origin gFrontEnd )
				)
				( attribute "WATTAGE" "1/16W"
					( Origin gFrontEnd )
				)
				( attribute "XY" "(-1200,675)"
					( Origin gFrontEnd )
				)
				( attribute "CHIPS_PART_NAME" "RES"
					( Origin gPackager )
				)
				( attribute "CDS_PART_NAME" "RES_0402-1.0,1%,1/16W,CHIP,G21A"
					( Origin gPackager )
				)
				( objectStatus "R3U9" )
				( pin "a"
					( attribute "PN" "1"
						( Origin gPackager )
					)
					( objectStatus "R3U9.1" )
				)
				( pin "b"
					( attribute "PN" "2"
						( Origin gPackager )
					)
					( objectStatus "R3U9.2" )
				)
			)
			( gate "@baseboard_fab2_lib.baseboard_fab2(sch_1):page216_i77"
				( attribute "CDS_LIB" "mstr_discrete"
					( Origin gPackager )
				)
				( attribute "CDS_LOCATION" "C7G40"
					( Origin gPackager )
				)
				( attribute "CDS_SEC" "1"
					( Origin gPackager )
				)
				( attribute "LOCATION" "C7G40"
					( Origin gFrontEnd )
				)
				( attribute "MATERIAL" "X6S"
					( Origin gFrontEnd )
				)
				( attribute "PACK_TYPE" "0402"
					( Origin gFrontEnd )
				)
				( attribute "PART_NUMBER" "D97712-011"
					( Origin gFrontEnd )
				)
				( attribute "PHYS_PAGE" "216"
					( Origin gFrontEnd )
				)
				( attribute "ROOM" "VDDQ_ABC_PWR_VR"
					( Origin gFrontEnd )
				)
				( attribute "ROT" "0"
					( Origin gFrontEnd )
				)
				( attribute "SEC" "1"
					( Origin gFrontEnd )
				)
				( attribute "SEC_TYPE" "0402"
					( Origin gFrontEnd )
				)
				( attribute "TOLERANCE" "10%"
					( Origin gFrontEnd )
				)
				( attribute "VALUE" "1.0UF"
					( Origin gFrontEnd )
				)
				( attribute "VER" "1"
					( Origin gFrontEnd )
				)
				( attribute "VOLTAGE" "16V"
					( Units "uVoltage" "V" 1.000000)
					( Origin gFrontEnd )
				)
				( attribute "XY" "(-1450,125)"
					( Origin gFrontEnd )
				)
				( attribute "CHIPS_PART_NAME" "CAP"
					( Origin gPackager )
				)
				( attribute "CDS_PART_NAME" "CAP_0402-1.0UF,16V,10%,X6S,D97A"
					( Origin gPackager )
				)
				( objectStatus "C7G40" )
				( pin "a"
					( attribute "PN" "1"
						( Origin gPackager )
					)
					( objectStatus "C7G40.1" )
				)
				( pin "b"
					( attribute "PN" "2"
						( Origin gPackager )
					)
					( objectStatus "C7G40.2" )
				)
			)
			( gate "@baseboard_fab2_lib.baseboard_fab2(sch_1):page216_i78"
				( attribute "CDS_LIB" "dev_discrete"
					( Origin gPackager )
				)
				( attribute "CDS_LOCATION" "C7G36"
					( Origin gPackager )
				)
				( attribute "CDS_SEC" "1"
					( Origin gPackager )
				)
				( attribute "LOCATION" "C7G36"
					( Origin gFrontEnd )
				)
				( attribute "MATERIAL" "X7R"
					( Origin gFrontEnd )
				)
				( attribute "PACK_TYPE" "0402V"
					( Origin gFrontEnd )
				)
				( attribute "PART_NUMBER" "A36096-030"
					( Origin gFrontEnd )
				)
				( attribute "PHYS_PAGE" "216"
					( Origin gFrontEnd )
				)
				( attribute "ROOM" "VDDQ_ABC_PWR_VR"
					( Origin gFrontEnd )
				)
				( attribute "ROT" "0"
					( Origin gFrontEnd )
				)
				( attribute "SEC" "1"
					( Origin gFrontEnd )
				)
				( attribute "SEC_TYPE" "0402V"
					( Origin gFrontEnd )
				)
				( attribute "TOLERANCE" "10%"
					( Origin gFrontEnd )
				)
				( attribute "VALUE" "0.1UF"
					( Origin gFrontEnd )
				)
				( attribute "VER" "1"
					( Origin gFrontEnd )
				)
				( attribute "VOLTAGE" "16V"
					( Units "uVoltage" "V" 1.000000)
					( Origin gFrontEnd )
				)
				( attribute "XY" "(-1675,100)"
					( Origin gFrontEnd )
				)
				( attribute "CHIPS_PART_NAME" "CAP_A"
					( Origin gPackager )
				)
				( attribute "CDS_PART_NAME" "CAP_A_0402V-0.1UF,16V,10%,X7R,A"
					( Origin gPackager )
				)
				( objectStatus "C7G36" )
				( pin "a"
					( attribute "PN" "1"
						( Origin gPackager )
					)
					( objectStatus "C7G36.1" )
				)
				( pin "b"
					( attribute "PN" "2"
						( Origin gPackager )
					)
					( objectStatus "C7G36.2" )
				)
			)
			( gate "@baseboard_fab2_lib.baseboard_fab2(sch_1):page216_i79"
				( attribute "CDS_LIB" "mstr_discrete"
					( Origin gPackager )
				)
				( attribute "CDS_LOCATION" "C7G30"
					( Origin gPackager )
				)
				( attribute "CDS_SEC" "1"
					( Origin gPackager )
				)
				( attribute "LOCATION" "C7G30"
					( Origin gFrontEnd )
				)
				( attribute "MATERIAL" "X6S"
					( Origin gFrontEnd )
				)
				( attribute "PACK_TYPE" "0402"
					( Origin gFrontEnd )
				)
				( attribute "PART_NUMBER" "D97712-011"
					( Origin gFrontEnd )
				)
				( attribute "PHYS_PAGE" "216"
					( Origin gFrontEnd )
				)
				( attribute "ROOM" "VDDQ_ABC_PWR_VR"
					( Origin gFrontEnd )
				)
				( attribute "ROT" "0"
					( Origin gFrontEnd )
				)
				( attribute "SEC" "1"
					( Origin gFrontEnd )
				)
				( attribute "SEC_TYPE" "0402"
					( Origin gFrontEnd )
				)
				( attribute "TOLERANCE" "10%"
					( Origin gFrontEnd )
				)
				( attribute "VALUE" "1.0UF"
					( Origin gFrontEnd )
				)
				( attribute "VER" "1"
					( Origin gFrontEnd )
				)
				( attribute "VOLTAGE" "16V"
					( Units "uVoltage" "V" 1.000000)
					( Origin gFrontEnd )
				)
				( attribute "XY" "(-1900,125)"
					( Origin gFrontEnd )
				)
				( attribute "CHIPS_PART_NAME" "CAP"
					( Origin gPackager )
				)
				( attribute "CDS_PART_NAME" "CAP_0402-1.0UF,16V,10%,X6S,D97A"
					( Origin gPackager )
				)
				( objectStatus "C7G30" )
				( pin "a"
					( attribute "PN" "1"
						( Origin gPackager )
					)
					( objectStatus "C7G30.1" )
				)
				( pin "b"
					( attribute "PN" "2"
						( Origin gPackager )
					)
					( objectStatus "C7G30.2" )
				)
			)
			( gate "@baseboard_fab2_lib.baseboard_fab2(sch_1):page216_i80"
				( attribute "CDS_LIB" "mstr_discrete"
					( Origin gPackager )
				)
				( attribute "CDS_LOCATION" "C3U9"
					( Origin gPackager )
				)
				( attribute "CDS_SEC" "1"
					( Origin gPackager )
				)
				( attribute "LOCATION" "C3U9"
					( Origin gFrontEnd )
				)
				( attribute "MATERIAL" "X6S"
					( Origin gFrontEnd )
				)
				( attribute "PACK_TYPE" "0805"
					( Origin gFrontEnd )
				)
				( attribute "PART_NUMBER" "C95333-007"
					( Origin gFrontEnd )
				)
				( attribute "PHYS_PAGE" "216"
					( Origin gFrontEnd )
				)
				( attribute "ROOM" "VDDQ_ABC_PWR_VR"
					( Origin gFrontEnd )
				)
				( attribute "ROT" "0"
					( Origin gFrontEnd )
				)
				( attribute "SEC" "1"
					( Origin gFrontEnd )
				)
				( attribute "SEC_TYPE" "0805"
					( Origin gFrontEnd )
				)
				( attribute "TOLERANCE" "10%"
					( Origin gFrontEnd )
				)
				( attribute "VALUE" "10UF"
					( Origin gFrontEnd )
				)
				( attribute "VER" "1"
					( Origin gFrontEnd )
				)
				( attribute "VOLTAGE" "16V"
					( Units "uVoltage" "V" 1.000000)
					( Origin gFrontEnd )
				)
				( attribute "XY" "(-2125,100)"
					( Origin gFrontEnd )
				)
				( attribute "CHIPS_PART_NAME" "CAP"
					( Origin gPackager )
				)
				( attribute "CDS_PART_NAME" "CAP_0805-10UF,16V,10%,X6S,C953A"
					( Origin gPackager )
				)
				( objectStatus "C3U9" )
				( pin "a"
					( attribute "PN" "1"
						( Origin gPackager )
					)
					( objectStatus "C3U9.1" )
				)
				( pin "b"
					( attribute "PN" "2"
						( Origin gPackager )
					)
					( objectStatus "C3U9.2" )
				)
			)
			( gate "@baseboard_fab2_lib.baseboard_fab2(sch_1):page216_i81"
				( attribute "CDS_LIB" "mstr_discrete"
					( Origin gPackager )
				)
				( attribute "CDS_LOCATION" "C3U7"
					( Origin gPackager )
				)
				( attribute "CDS_SEC" "1"
					( Origin gPackager )
				)
				( attribute "LOCATION" "C3U7"
					( Origin gFrontEnd )
				)
				( attribute "MATERIAL" "X6S"
					( Origin gFrontEnd )
				)
				( attribute "PACK_TYPE" "0805"
					( Origin gFrontEnd )
				)
				( attribute "PART_NUMBER" "C95333-007"
					( Origin gFrontEnd )
				)
				( attribute "PHYS_PAGE" "216"
					( Origin gFrontEnd )
				)
				( attribute "ROOM" "VDDQ_ABC_PWR_VR"
					( Origin gFrontEnd )
				)
				( attribute "ROT" "0"
					( Origin gFrontEnd )
				)
				( attribute "SEC" "1"
					( Origin gFrontEnd )
				)
				( attribute "SEC_TYPE" "0805"
					( Origin gFrontEnd )
				)
				( attribute "TOLERANCE" "10%"
					( Origin gFrontEnd )
				)
				( attribute "VALUE" "10UF"
					( Origin gFrontEnd )
				)
				( attribute "VER" "1"
					( Origin gFrontEnd )
				)
				( attribute "VOLTAGE" "16V"
					( Units "uVoltage" "V" 1.000000)
					( Origin gFrontEnd )
				)
				( attribute "XY" "(-2350,125)"
					( Origin gFrontEnd )
				)
				( attribute "CHIPS_PART_NAME" "CAP"
					( Origin gPackager )
				)
				( attribute "CDS_PART_NAME" "CAP_0805-10UF,16V,10%,X6S,C953A"
					( Origin gPackager )
				)
				( objectStatus "C3U7" )
				( pin "a"
					( attribute "PN" "1"
						( Origin gPackager )
					)
					( objectStatus "C3U7.1" )
				)
				( pin "b"
					( attribute "PN" "2"
						( Origin gPackager )
					)
					( objectStatus "C3U7.2" )
				)
			)
			( gate "@baseboard_fab2_lib.baseboard_fab2(sch_1):page216_i84"
				( attribute "CDS_LIB" "mstr_discrete"
					( Origin gPackager )
				)
				( attribute "CDS_LOCATION" "C3U6"
					( Origin gPackager )
				)
				( attribute "CDS_SEC" "1"
					( Origin gPackager )
				)
				( attribute "LOCATION" "C3U6"
					( Origin gFrontEnd )
				)
				( attribute "MATERIAL" "X6S"
					( Origin gFrontEnd )
				)
				( attribute "PACK_TYPE" "0805"
					( Origin gFrontEnd )
				)
				( attribute "PART_NUMBER" "C95333-007"
					( Origin gFrontEnd )
				)
				( attribute "PHYS_PAGE" "216"
					( Origin gFrontEnd )
				)
				( attribute "ROOM" "VDDQ_ABC_PWR_VR"
					( Origin gFrontEnd )
				)
				( attribute "ROT" "0"
					( Origin gFrontEnd )
				)
				( attribute "SEC" "1"
					( Origin gFrontEnd )
				)
				( attribute "SEC_TYPE" "0805"
					( Origin gFrontEnd )
				)
				( attribute "TOLERANCE" "10%"
					( Origin gFrontEnd )
				)
				( attribute "VALUE" "10UF"
					( Origin gFrontEnd )
				)
				( attribute "VER" "1"
					( Origin gFrontEnd )
				)
				( attribute "VOLTAGE" "16V"
					( Units "uVoltage" "V" 1.000000)
					( Origin gFrontEnd )
				)
				( attribute "XY" "(-2600,100)"
					( Origin gFrontEnd )
				)
				( attribute "CHIPS_PART_NAME" "CAP"
					( Origin gPackager )
				)
				( attribute "CDS_PART_NAME" "CAP_0805-10UF,16V,10%,X6S,C953A"
					( Origin gPackager )
				)
				( objectStatus "C3U6" )
				( pin "a"
					( attribute "PN" "1"
						( Origin gPackager )
					)
					( objectStatus "C3U6.1" )
				)
				( pin "b"
					( attribute "PN" "2"
						( Origin gPackager )
					)
					( objectStatus "C3U6.2" )
				)
			)
			( gate "@baseboard_fab2_lib.baseboard_fab2(sch_1):page216_i102"
				( attribute "CDS_LIB" "mstr_discrete"
					( Origin gPackager )
				)
				( attribute "CDS_LOCATION" "EU7G2"
					( Origin gPackager )
				)
				( attribute "LOCATION" "EU7G2"
					( Origin gFrontEnd )
				)
				( attribute "MATERIAL" "IC"
					( Origin gFrontEnd )
				)
				( attribute "NO_XNET_CONNECTION" "1"
					( Origin gFrontEnd )
				)
				( attribute "PACK_TYPE" "SM"
					( Origin gFrontEnd )
				)
				( attribute "PART_NUMBER" "H73688-001"
					( Origin gFrontEnd )
				)
				( attribute "PHYS_PAGE" "216"
					( Origin gFrontEnd )
				)
				( attribute "ROT" "0"
					( Origin gFrontEnd )
				)
				( attribute "SEC" "1"
					( Origin gFrontEnd )
				)
				( attribute "SEC_TYPE" "SM"
					( Origin gFrontEnd )
				)
				( attribute "VALUE" "IR35411"
					( Origin gFrontEnd )
				)
				( attribute "VER" "1"
					( Origin gFrontEnd )
				)
				( attribute "XY" "(1425,2250)"
					( Origin gFrontEnd )
				)
				( attribute "CHIPS_PART_NAME" "IR354XX"
					( Origin gPackager )
				)
				( attribute "CDS_PART_NAME" "IR354XX_SM-IR35411,IC,H73688-0A"
					( Origin gPackager )
				)
				( attribute "CDS_SEC" "1"
					( Origin gPackager )
				)
				( objectStatus "EU7G2" )
				( pin "boost"
					( attribute "PN" "33"
						( Origin gPackager )
					)
					( objectStatus "EU7G2.33" )
				)
				( pin "en"
					( attribute "PN" "35"
						( Origin gPackager )
					)
					( objectStatus "EU7G2.35" )
				)
				( pin "gl(0)"
					( attribute "PN" "6"
						( Origin gPackager )
					)
					( objectStatus "EU7G2.6" )
				)
				( pin "gl(1)"
					( attribute "PN" "41"
						( Origin gPackager )
					)
					( objectStatus "EU7G2.41" )
				)
				( pin "iout"
					( attribute "PN" "38"
						( Origin gPackager )
					)
					( objectStatus "EU7G2.38" )
				)
				( pin "lgnd"
					( attribute "PN" "2"
						( Origin gPackager )
					)
					( objectStatus "EU7G2.2" )
				)
				( pin "nc"
					( attribute "PN" "31"
						( Origin gPackager )
					)
					( objectStatus "EU7G2.31" )
				)
				( pin "ocset"
					( attribute "PN" "37"
						( Origin gPackager )
					)
					( objectStatus "EU7G2.37" )
				)
				( pin "pgnd(0)"
					( attribute "PN" "5"
						( Origin gPackager )
					)
					( objectStatus "EU7G2.5" )
				)
				( pin "pgnd(1)"
					( attribute "PN" "7"
						( Origin gPackager )
					)
					( objectStatus "EU7G2.7" )
				)
				( pin "pgnd(2)"
					( attribute "PN" "40"
						( Origin gPackager )
					)
					( objectStatus "EU7G2.40" )
				)
				( pin "phase"
					( attribute "PN" "32"
						( Origin gPackager )
					)
					( objectStatus "EU7G2.32" )
				)
				( pin "pwm"
					( attribute "PN" "34"
						( Origin gPackager )
					)
					( objectStatus "EU7G2.34" )
				)
				( pin "refin"
					( attribute "PN" "39"
						( Origin gPackager )
					)
					( objectStatus "EU7G2.39" )
				)
				( pin "sw"
					( attribute "PN" "10"
						( Origin gPackager )
					)
					( objectStatus "EU7G2.10" )
				)
				( pin "tout_flt"
					( attribute "PN" "36"
						( Origin gPackager )
					)
					( objectStatus "EU7G2.36" )
				)
				( pin "vcc"
					( attribute "PN" "3"
						( Origin gPackager )
					)
					( objectStatus "EU7G2.3" )
				)
				( pin "vdrv"
					( attribute "PN" "4"
						( Origin gPackager )
					)
					( objectStatus "EU7G2.4" )
				)
				( pin "vin(0)"
					( attribute "PN" "25"
						( Origin gPackager )
					)
					( objectStatus "EU7G2.25" )
				)
				( pin "vin(1)"
					( attribute "PN" "30"
						( Origin gPackager )
					)
					( objectStatus "EU7G2.30" )
				)
				( pin "vos"
					( attribute "PN" "1"
						( Origin gPackager )
					)
					( objectStatus "EU7G2.1" )
				)
			)
			( gate "@baseboard_fab2_lib.baseboard_fab2(sch_1):page216_i103"
				( attribute "CDS_LIB" "mstr_discrete"
					( Origin gPackager )
				)
				( attribute "CDS_LOCATION" "EU7G3"
					( Origin gPackager )
				)
				( attribute "CDS_SEC" "1"
					( Origin gPackager )
				)
				( attribute "LOCATION" "EU7G3"
					( Origin gFrontEnd )
				)
				( attribute "MATERIAL" "IC"
					( Origin gFrontEnd )
				)
				( attribute "NO_XNET_CONNECTION" "1"
					( Origin gFrontEnd )
				)
				( attribute "PACK_TYPE" "SM"
					( Origin gFrontEnd )
				)
				( attribute "PART_NUMBER" "H73688-001"
					( Origin gFrontEnd )
				)
				( attribute "PHYS_PAGE" "216"
					( Origin gFrontEnd )
				)
				( attribute "ROT" "0"
					( Origin gFrontEnd )
				)
				( attribute "SEC" "1"
					( Origin gFrontEnd )
				)
				( attribute "SEC_TYPE" "SM"
					( Origin gFrontEnd )
				)
				( attribute "VALUE" "IR35411"
					( Origin gFrontEnd )
				)
				( attribute "VER" "1"
					( Origin gFrontEnd )
				)
				( attribute "XY" "(1425,-125)"
					( Origin gFrontEnd )
				)
				( attribute "CHIPS_PART_NAME" "IR354XX"
					( Origin gPackager )
				)
				( attribute "CDS_PART_NAME" "IR354XX_SM-IR35411,IC,H73688-0A"
					( Origin gPackager )
				)
				( objectStatus "EU7G3" )
				( pin "boost"
					( attribute "PN" "33"
						( Origin gPackager )
					)
					( objectStatus "EU7G3.33" )
				)
				( pin "en"
					( attribute "PN" "35"
						( Origin gPackager )
					)
					( objectStatus "EU7G3.35" )
				)
				( pin "gl(0)"
					( attribute "PN" "6"
						( Origin gPackager )
					)
					( objectStatus "EU7G3.6" )
				)
				( pin "gl(1)"
					( attribute "PN" "41"
						( Origin gPackager )
					)
					( objectStatus "EU7G3.41" )
				)
				( pin "iout"
					( attribute "PN" "38"
						( Origin gPackager )
					)
					( objectStatus "EU7G3.38" )
				)
				( pin "lgnd"
					( attribute "PN" "2"
						( Origin gPackager )
					)
					( objectStatus "EU7G3.2" )
				)
				( pin "nc"
					( attribute "PN" "31"
						( Origin gPackager )
					)
					( objectStatus "EU7G3.31" )
				)
				( pin "ocset"
					( attribute "PN" "37"
						( Origin gPackager )
					)
					( objectStatus "EU7G3.37" )
				)
				( pin "pgnd(0)"
					( attribute "PN" "5"
						( Origin gPackager )
					)
					( objectStatus "EU7G3.5" )
				)
				( pin "pgnd(1)"
					( attribute "PN" "7"
						( Origin gPackager )
					)
					( objectStatus "EU7G3.7" )
				)
				( pin "pgnd(2)"
					( attribute "PN" "40"
						( Origin gPackager )
					)
					( objectStatus "EU7G3.40" )
				)
				( pin "phase"
					( attribute "PN" "32"
						( Origin gPackager )
					)
					( objectStatus "EU7G3.32" )
				)
				( pin "pwm"
					( attribute "PN" "34"
						( Origin gPackager )
					)
					( objectStatus "EU7G3.34" )
				)
				( pin "refin"
					( attribute "PN" "39"
						( Origin gPackager )
					)
					( objectStatus "EU7G3.39" )
				)
				( pin "sw"
					( attribute "PN" "10"
						( Origin gPackager )
					)
					( objectStatus "EU7G3.10" )
				)
				( pin "tout_flt"
					( attribute "PN" "36"
						( Origin gPackager )
					)
					( objectStatus "EU7G3.36" )
				)
				( pin "vcc"
					( attribute "PN" "3"
						( Origin gPackager )
					)
					( objectStatus "EU7G3.3" )
				)
				( pin "vdrv"
					( attribute "PN" "4"
						( Origin gPackager )
					)
					( objectStatus "EU7G3.4" )
				)
				( pin "vin(0)"
					( attribute "PN" "25"
						( Origin gPackager )
					)
					( objectStatus "EU7G3.25" )
				)
				( pin "vin(1)"
					( attribute "PN" "30"
						( Origin gPackager )
					)
					( objectStatus "EU7G3.30" )
				)
				( pin "vos"
					( attribute "PN" "1"
						( Origin gPackager )
					)
					( objectStatus "EU7G3.1" )
				)
			)
			( gate "@baseboard_fab2_lib.baseboard_fab2(sch_1):page216_i104"
				( attribute "CDS_LIB" "mstr_discrete"
					( Origin gPackager )
				)
				( attribute "CDS_LOCATION" "R7G25"
					( Origin gPackager )
				)
				( attribute "CDS_SEC" "1"
					( Origin gPackager )
				)
				( attribute "LOCATION" "R7G25"
					( Origin gFrontEnd )
				)
				( attribute "MATERIAL" "EMPTY"
					( Origin gFrontEnd )
				)
				( attribute "PACK_TYPE" "0402"
					( Origin gFrontEnd )
				)
				( attribute "PART_NUMBER" "G21796-187"
					( Origin gFrontEnd )
				)
				( attribute "PHYS_PAGE" "216"
					( Origin gFrontEnd )
				)
				( attribute "ROT" "0"
					( Origin gFrontEnd )
				)
				( attribute "SEC" "1"
					( Origin gFrontEnd )
				)
				( attribute "SEC_TYPE" "0402"
					( Origin gFrontEnd )
				)
				( attribute "TOLERANCE" "1%"
					( Origin gFrontEnd )
				)
				( attribute "VALUE" "68.1K"
					( Origin gFrontEnd )
				)
				( attribute "VER" "2"
					( Origin gFrontEnd )
				)
				( attribute "WATTAGE" "1/16W"
					( Origin gFrontEnd )
				)
				( attribute "XY" "(4225,2400)"
					( Origin gFrontEnd )
				)
				( attribute "CHIPS_PART_NAME" "RES"
					( Origin gPackager )
				)
				( attribute "CDS_PART_NAME" "RES_0402-68.1K,1%,1/16W,EMPTY,A"
					( Origin gPackager )
				)
				( objectStatus "R7G25" )
				( pin "a"
					( attribute "PN" "1"
						( Origin gPackager )
					)
					( objectStatus "R7G25.1" )
				)
				( pin "b"
					( attribute "PN" "2"
						( Origin gPackager )
					)
					( objectStatus "R7G25.2" )
				)
			)
			( gate "@baseboard_fab2_lib.baseboard_fab2(sch_1):page216_i106"
				( attribute "CDS_LIB" "mstr_discrete"
					( Origin gPackager )
				)
				( attribute "CDS_LOCATION" "R7G30"
					( Origin gPackager )
				)
				( attribute "CDS_SEC" "1"
					( Origin gPackager )
				)
				( attribute "LOCATION" "R7G30"
					( Origin gFrontEnd )
				)
				( attribute "MATERIAL" "EMPTY"
					( Origin gFrontEnd )
				)
				( attribute "PACK_TYPE" "0402"
					( Origin gFrontEnd )
				)
				( attribute "PART_NUMBER" "G21796-187"
					( Origin gFrontEnd )
				)
				( attribute "PHYS_PAGE" "216"
					( Origin gFrontEnd )
				)
				( attribute "ROT" "0"
					( Origin gFrontEnd )
				)
				( attribute "SEC" "1"
					( Origin gFrontEnd )
				)
				( attribute "SEC_TYPE" "0402"
					( Origin gFrontEnd )
				)
				( attribute "TOLERANCE" "1%"
					( Origin gFrontEnd )
				)
				( attribute "VALUE" "68.1K"
					( Origin gFrontEnd )
				)
				( attribute "VER" "2"
					( Origin gFrontEnd )
				)
				( attribute "WATTAGE" "1/16W"
					( Origin gFrontEnd )
				)
				( attribute "XY" "(4325,0)"
					( Origin gFrontEnd )
				)
				( attribute "CHIPS_PART_NAME" "RES"
					( Origin gPackager )
				)
				( attribute "CDS_PART_NAME" "RES_0402-68.1K,1%,1/16W,EMPTY,A"
					( Origin gPackager )
				)
				( objectStatus "R7G30" )
				( pin "a"
					( attribute "PN" "1"
						( Origin gPackager )
					)
					( objectStatus "R7G30.1" )
				)
				( pin "b"
					( attribute "PN" "2"
						( Origin gPackager )
					)
					( objectStatus "R7G30.2" )
				)
			)
			( gate "@baseboard_fab2_lib.baseboard_fab2(sch_1):page217_i58"
				( attribute "BOM_COST" "MEM_VRD_PVPP_AB"
					( Origin gFrontEnd )
				)
				( attribute "CDS_LIB" "mstr_discrete"
					( Origin gPackager )
				)
				( attribute "CDS_LOCATION" "R3U4"
					( Origin gPackager )
				)
				( attribute "CDS_SEC" "1"
					( Origin gPackager )
				)
				( attribute "LOCATION" "R3U4"
					( Origin gFrontEnd )
				)
				( attribute "MATERIAL" "CHIP"
					( Origin gFrontEnd )
				)
				( attribute "PACK_TYPE" "0603"
					( Origin gFrontEnd )
				)
				( attribute "PART_NUMBER" "G22026-003"
					( Origin gFrontEnd )
				)
				( attribute "PHYS_PAGE" "217"
					( Origin gFrontEnd )
				)
				( attribute "ROOM" "VDDQ_ABC_PWR_VR"
					( Origin gFrontEnd )
				)
				( attribute "ROT" "0"
					( Origin gFrontEnd )
				)
				( attribute "SEC" "1"
					( Origin gPackager )
				)
				( attribute "TOLERANCE" "1%"
					( Origin gFrontEnd )
				)
				( attribute "VALUE" "120.0"
					( Origin gFrontEnd )
				)
				( attribute "VER" "2"
					( Origin gFrontEnd )
				)
				( attribute "WATTAGE" "1/10W"
					( Origin gFrontEnd )
				)
				( attribute "XY" "(4975,-475)"
					( Origin gFrontEnd )
				)
				( attribute "CHIPS_PART_NAME" "RES"
					( Origin gPackager )
				)
				( attribute "CDS_PART_NAME" "RES_0603-120.0,1%,1/10W,CHIP,GA"
					( Origin gPackager )
				)
				( objectStatus "R3U4" )
				( pin "a"
					( attribute "PN" "1"
						( Origin gPackager )
					)
					( objectStatus "R3U4.1" )
				)
				( pin "b"
					( attribute "PN" "2"
						( Origin gPackager )
					)
					( objectStatus "R3U4.2" )
				)
			)
			( gate "@baseboard_fab2_lib.baseboard_fab2(sch_1):page217_i74"
				( attribute "CDS_LIB" "mstr_discrete"
					( Origin gPackager )
				)
				( attribute "CDS_LOCATION" "R4U6"
					( Origin gPackager )
				)
				( attribute "CDS_SEC" "1"
					( Origin gPackager )
				)
				( attribute "LOCATION" "R4U6"
					( Origin gFrontEnd )
				)
				( attribute "MATERIAL" "EMPTY"
					( Origin gFrontEnd )
				)
				( attribute "PACK_TYPE" "0402"
					( Origin gFrontEnd )
				)
				( attribute "PART_NUMBER" "G21796-017"
					( Origin gFrontEnd )
				)
				( attribute "PHYS_PAGE" "217"
					( Origin gFrontEnd )
				)
				( attribute "ROOM" "VDDQ_ABC_PWR_VR"
					( Origin gFrontEnd )
				)
				( attribute "ROT" "0"
					( Origin gFrontEnd )
				)
				( attribute "SEC" "1"
					( Origin gFrontEnd )
				)
				( attribute "SEC_TYPE" "0402"
					( Origin gFrontEnd )
				)
				( attribute "TOLERANCE" "1%"
					( Origin gFrontEnd )
				)
				( attribute "VALUE" "100.0"
					( Origin gFrontEnd )
				)
				( attribute "VER" "2"
					( Origin gFrontEnd )
				)
				( attribute "WATTAGE" "1/16W"
					( Origin gFrontEnd )
				)
				( attribute "XY" "(-250,1700)"
					( Origin gFrontEnd )
				)
				( attribute "CHIPS_PART_NAME" "RES"
					( Origin gPackager )
				)
				( attribute "CDS_PART_NAME" "RES_0402-100.0,1%,1/16W,EMPTY,A"
					( Origin gPackager )
				)
				( objectStatus "R4U6" )
				( pin "a"
					( attribute "PN" "1"
						( Origin gPackager )
					)
					( objectStatus "R4U6.1" )
				)
				( pin "b"
					( attribute "PN" "2"
						( Origin gPackager )
					)
					( objectStatus "R4U6.2" )
				)
			)
			( gate "@baseboard_fab2_lib.baseboard_fab2(sch_1):page217_i75"
				( attribute "CDS_LIB" "mstr_discrete"
					( Origin gPackager )
				)
				( attribute "CDS_LOCATION" "C7G28"
					( Origin gPackager )
				)
				( attribute "CDS_SEC" "1"
					( Origin gPackager )
				)
				( attribute "LOCATION" "C7G28"
					( Origin gFrontEnd )
				)
				( attribute "MATERIAL" "ALUM"
					( Origin gFrontEnd )
				)
				( attribute "PACK_TYPE" "3018"
					( Origin gFrontEnd )
				)
				( attribute "PART_NUMBER" "699013-049"
					( Origin gFrontEnd )
				)
				( attribute "PHYS_PAGE" "217"
					( Origin gFrontEnd )
				)
				( attribute "ROOM" "VDDQ_ABC_PWR_VR"
					( Origin gFrontEnd )
				)
				( attribute "ROT" "0"
					( Origin gFrontEnd )
				)
				( attribute "SEC" "1"
					( Origin gFrontEnd )
				)
				( attribute "SEC_TYPE" "3018"
					( Origin gFrontEnd )
				)
				( attribute "TOLERANCE" "20%"
					( Origin gFrontEnd )
				)
				( attribute "VALUE" "470UF"
					( Origin gFrontEnd )
				)
				( attribute "VER" "1"
					( Origin gFrontEnd )
				)
				( attribute "VOLTAGE" "2.5V"
					( Units "uVoltage" "V" 1.000000)
					( Origin gFrontEnd )
				)
				( attribute "XY" "(3375,-450)"
					( Origin gFrontEnd )
				)
				( attribute "CHIPS_PART_NAME" "CAPP"
					( Origin gPackager )
				)
				( attribute "CDS_PART_NAME" "CAPP_3018-470UF,2.5V,20%,ALUM,A"
					( Origin gPackager )
				)
				( objectStatus "C7G28" )
				( pin "a"
					( attribute "PN" "1"
						( Origin gPackager )
					)
					( objectStatus "C7G28.1" )
				)
				( pin "b"
					( attribute "PN" "2"
						( Origin gPackager )
					)
					( objectStatus "C7G28.2" )
				)
			)
			( gate "@baseboard_fab2_lib.baseboard_fab2(sch_1):page217_i76"
				( attribute "CDS_LIB" "mstr_discrete"
					( Origin gPackager )
				)
				( attribute "CDS_LOCATION" "C3U1"
					( Origin gPackager )
				)
				( attribute "CDS_SEC" "1"
					( Origin gPackager )
				)
				( attribute "LOCATION" "C3U1"
					( Origin gFrontEnd )
				)
				( attribute "MATERIAL" "ALUM"
					( Origin gFrontEnd )
				)
				( attribute "PACK_TYPE" "3018"
					( Origin gFrontEnd )
				)
				( attribute "PART_NUMBER" "699013-049"
					( Origin gFrontEnd )
				)
				( attribute "PHYS_PAGE" "217"
					( Origin gFrontEnd )
				)
				( attribute "ROOM" "VDDQ_ABC_PWR_VR"
					( Origin gFrontEnd )
				)
				( attribute "ROT" "0"
					( Origin gFrontEnd )
				)
				( attribute "SEC" "1"
					( Origin gFrontEnd )
				)
				( attribute "SEC_TYPE" "3018"
					( Origin gFrontEnd )
				)
				( attribute "TOLERANCE" "20%"
					( Origin gFrontEnd )
				)
				( attribute "VALUE" "470UF"
					( Origin gFrontEnd )
				)
				( attribute "VER" "1"
					( Origin gFrontEnd )
				)
				( attribute "VOLTAGE" "2.5V"
					( Units "uVoltage" "V" 1.000000)
					( Origin gFrontEnd )
				)
				( attribute "XY" "(3800,-450)"
					( Origin gFrontEnd )
				)
				( attribute "CHIPS_PART_NAME" "CAPP"
					( Origin gPackager )
				)
				( attribute "CDS_PART_NAME" "CAPP_3018-470UF,2.5V,20%,ALUM,A"
					( Origin gPackager )
				)
				( objectStatus "C3U1" )
				( pin "a"
					( attribute "PN" "1"
						( Origin gPackager )
					)
					( objectStatus "C3U1.1" )
				)
				( pin "b"
					( attribute "PN" "2"
						( Origin gPackager )
					)
					( objectStatus "C3U1.2" )
				)
			)
			( gate "@baseboard_fab2_lib.baseboard_fab2(sch_1):page217_i77"
				( attribute "CDS_LIB" "mstr_discrete"
					( Origin gPackager )
				)
				( attribute "CDS_LOCATION" "C3U5"
					( Origin gPackager )
				)
				( attribute "CDS_SEC" "1"
					( Origin gPackager )
				)
				( attribute "LOCATION" "C3U5"
					( Origin gFrontEnd )
				)
				( attribute "MATERIAL" "ALUM"
					( Origin gFrontEnd )
				)
				( attribute "PACK_TYPE" "3018"
					( Origin gFrontEnd )
				)
				( attribute "PART_NUMBER" "699013-049"
					( Origin gFrontEnd )
				)
				( attribute "PHYS_PAGE" "217"
					( Origin gFrontEnd )
				)
				( attribute "ROOM" "VDDQ_ABC_PWR_VR"
					( Origin gFrontEnd )
				)
				( attribute "ROT" "0"
					( Origin gFrontEnd )
				)
				( attribute "SEC" "1"
					( Origin gFrontEnd )
				)
				( attribute "SEC_TYPE" "3018"
					( Origin gFrontEnd )
				)
				( attribute "TOLERANCE" "20%"
					( Origin gFrontEnd )
				)
				( attribute "VALUE" "470UF"
					( Origin gFrontEnd )
				)
				( attribute "VER" "1"
					( Origin gFrontEnd )
				)
				( attribute "VOLTAGE" "2.5V"
					( Units "uVoltage" "V" 1.000000)
					( Origin gFrontEnd )
				)
				( attribute "XY" "(4225,-450)"
					( Origin gFrontEnd )
				)
				( attribute "CHIPS_PART_NAME" "CAPP"
					( Origin gPackager )
				)
				( attribute "CDS_PART_NAME" "CAPP_3018-470UF,2.5V,20%,ALUM,A"
					( Origin gPackager )
				)
				( objectStatus "C3U5" )
				( pin "a"
					( attribute "PN" "1"
						( Origin gPackager )
					)
					( objectStatus "C3U5.1" )
				)
				( pin "b"
					( attribute "PN" "2"
						( Origin gPackager )
					)
					( objectStatus "C3U5.2" )
				)
			)
			( gate "@baseboard_fab2_lib.baseboard_fab2(sch_1):page217_i78"
				( attribute "CDS_LIB" "mstr_discrete"
					( Origin gPackager )
				)
				( attribute "CDS_LOCATION" "C3U8"
					( Origin gPackager )
				)
				( attribute "CDS_SEC" "1"
					( Origin gPackager )
				)
				( attribute "LOCATION" "C3U8"
					( Origin gFrontEnd )
				)
				( attribute "MATERIAL" "ALUM"
					( Origin gFrontEnd )
				)
				( attribute "PACK_TYPE" "3018"
					( Origin gFrontEnd )
				)
				( attribute "PART_NUMBER" "699013-049"
					( Origin gFrontEnd )
				)
				( attribute "PHYS_PAGE" "217"
					( Origin gFrontEnd )
				)
				( attribute "ROOM" "VDDQ_ABC_PWR_VR"
					( Origin gFrontEnd )
				)
				( attribute "ROT" "0"
					( Origin gFrontEnd )
				)
				( attribute "SEC" "1"
					( Origin gFrontEnd )
				)
				( attribute "SEC_TYPE" "3018"
					( Origin gFrontEnd )
				)
				( attribute "TOLERANCE" "20%"
					( Origin gFrontEnd )
				)
				( attribute "VALUE" "470UF"
					( Origin gFrontEnd )
				)
				( attribute "VER" "1"
					( Origin gFrontEnd )
				)
				( attribute "VOLTAGE" "2.5V"
					( Units "uVoltage" "V" 1.000000)
					( Origin gFrontEnd )
				)
				( attribute "XY" "(4625,-475)"
					( Origin gFrontEnd )
				)
				( attribute "CHIPS_PART_NAME" "CAPP"
					( Origin gPackager )
				)
				( attribute "CDS_PART_NAME" "CAPP_3018-470UF,2.5V,20%,ALUM,A"
					( Origin gPackager )
				)
				( objectStatus "C3U8" )
				( pin "a"
					( attribute "PN" "1"
						( Origin gPackager )
					)
					( objectStatus "C3U8.1" )
				)
				( pin "b"
					( attribute "PN" "2"
						( Origin gPackager )
					)
					( objectStatus "C3U8.2" )
				)
			)
			( gate "@baseboard_fab2_lib.baseboard_fab2(sch_1):page217_i82"
				( attribute "BOM_COST" "MEM_VRD_PVDDQ_CD"
					( Origin gFrontEnd )
				)
				( attribute "CDS_LIB" "mstr_discrete"
					( Origin gPackager )
				)
				( attribute "CDS_LOCATION" "C5U13"
					( Origin gPackager )
				)
				( attribute "CDS_SEC" "1"
					( Origin gPackager )
				)
				( attribute "LOCATION" "C5U13"
					( Origin gFrontEnd )
				)
				( attribute "MATERIAL" "X5R"
					( Origin gFrontEnd )
				)
				( attribute "PACK_TYPE" "0805"
					( Origin gFrontEnd )
				)
				( attribute "PART_NUMBER" "602433-112"
					( Origin gFrontEnd )
				)
				( attribute "PHYS_PAGE" "217"
					( Origin gFrontEnd )
				)
				( attribute "ROOM" "VDDQ_ABC_PWR_VR"
					( Origin gFrontEnd )
				)
				( attribute "ROT" "0"
					( Origin gFrontEnd )
				)
				( attribute "SEC" "1"
					( Origin gFrontEnd )
				)
				( attribute "SEC_TYPE" "0805"
					( Origin gFrontEnd )
				)
				( attribute "TOLERANCE" "20%"
					( Origin gFrontEnd )
				)
				( attribute "VALUE" "100UF"
					( Origin gFrontEnd )
				)
				( attribute "VER" "1"
					( Origin gFrontEnd )
				)
				( attribute "VOLTAGE" "4V"
					( Units "uVoltage" "V" 1.000000)
					( Origin gFrontEnd )
				)
				( attribute "XY" "(5475,2850)"
					( Origin gFrontEnd )
				)
				( attribute "CHIPS_PART_NAME" "CAP"
					( Origin gPackager )
				)
				( attribute "CDS_PART_NAME" "CAP_0805-100UF,4V,20%,X5R,6024A"
					( Origin gPackager )
				)
				( objectStatus "C5U13" )
				( pin "a"
					( attribute "PN" "1"
						( Origin gPackager )
					)
					( objectStatus "C5U13.1" )
				)
				( pin "b"
					( attribute "PN" "2"
						( Origin gPackager )
					)
					( objectStatus "C5U13.2" )
				)
			)
			( gate "@baseboard_fab2_lib.baseboard_fab2(sch_1):page217_i83"
				( attribute "BOM_COST" "MEM_VRD_PVDDQ_CD"
					( Origin gFrontEnd )
				)
				( attribute "CDS_LIB" "mstr_discrete"
					( Origin gPackager )
				)
				( attribute "CDS_LOCATION" "C5U10"
					( Origin gPackager )
				)
				( attribute "CDS_SEC" "1"
					( Origin gPackager )
				)
				( attribute "LOCATION" "C5U10"
					( Origin gFrontEnd )
				)
				( attribute "MATERIAL" "X5R"
					( Origin gFrontEnd )
				)
				( attribute "PACK_TYPE" "0805"
					( Origin gFrontEnd )
				)
				( attribute "PART_NUMBER" "602433-112"
					( Origin gFrontEnd )
				)
				( attribute "PHYS_PAGE" "217"
					( Origin gFrontEnd )
				)
				( attribute "ROOM" "VDDQ_ABC_PWR_VR"
					( Origin gFrontEnd )
				)
				( attribute "ROT" "0"
					( Origin gFrontEnd )
				)
				( attribute "SEC" "1"
					( Origin gFrontEnd )
				)
				( attribute "SEC_TYPE" "0805"
					( Origin gFrontEnd )
				)
				( attribute "TOLERANCE" "20%"
					( Origin gFrontEnd )
				)
				( attribute "VALUE" "100UF"
					( Origin gFrontEnd )
				)
				( attribute "VER" "1"
					( Origin gFrontEnd )
				)
				( attribute "VOLTAGE" "4V"
					( Units "uVoltage" "V" 1.000000)
					( Origin gFrontEnd )
				)
				( attribute "XY" "(5075,2850)"
					( Origin gFrontEnd )
				)
				( attribute "CHIPS_PART_NAME" "CAP"
					( Origin gPackager )
				)
				( attribute "CDS_PART_NAME" "CAP_0805-100UF,4V,20%,X5R,6024A"
					( Origin gPackager )
				)
				( objectStatus "C5U10" )
				( pin "a"
					( attribute "PN" "1"
						( Origin gPackager )
					)
					( objectStatus "C5U10.1" )
				)
				( pin "b"
					( attribute "PN" "2"
						( Origin gPackager )
					)
					( objectStatus "C5U10.2" )
				)
			)
			( gate "@baseboard_fab2_lib.baseboard_fab2(sch_1):page217_i88"
				( attribute "BOM_COST" "MEM_VRD_PVDDQ_CD"
					( Origin gFrontEnd )
				)
				( attribute "CDS_LIB" "mstr_discrete"
					( Origin gPackager )
				)
				( attribute "CDS_LOCATION" "C5U1"
					( Origin gPackager )
				)
				( attribute "CDS_SEC" "1"
					( Origin gPackager )
				)
				( attribute "LOCATION" "C5U1"
					( Origin gFrontEnd )
				)
				( attribute "MATERIAL" "X5R"
					( Origin gFrontEnd )
				)
				( attribute "PACK_TYPE" "0805"
					( Origin gFrontEnd )
				)
				( attribute "PART_NUMBER" "602433-112"
					( Origin gFrontEnd )
				)
				( attribute "PHYS_PAGE" "217"
					( Origin gFrontEnd )
				)
				( attribute "ROOM" "VDDQ_ABC_PWR_VR"
					( Origin gFrontEnd )
				)
				( attribute "ROT" "0"
					( Origin gFrontEnd )
				)
				( attribute "SEC" "1"
					( Origin gFrontEnd )
				)
				( attribute "SEC_TYPE" "0805"
					( Origin gFrontEnd )
				)
				( attribute "TOLERANCE" "20%"
					( Origin gFrontEnd )
				)
				( attribute "VALUE" "100UF"
					( Origin gFrontEnd )
				)
				( attribute "VER" "1"
					( Origin gFrontEnd )
				)
				( attribute "VOLTAGE" "4V"
					( Units "uVoltage" "V" 1.000000)
					( Origin gFrontEnd )
				)
				( attribute "XY" "(4725,2850)"
					( Origin gFrontEnd )
				)
				( attribute "CHIPS_PART_NAME" "CAP"
					( Origin gPackager )
				)
				( attribute "CDS_PART_NAME" "CAP_0805-100UF,4V,20%,X5R,6024A"
					( Origin gPackager )
				)
				( objectStatus "C5U1" )
				( pin "a"
					( attribute "PN" "1"
						( Origin gPackager )
					)
					( objectStatus "C5U1.1" )
				)
				( pin "b"
					( attribute "PN" "2"
						( Origin gPackager )
					)
					( objectStatus "C5U1.2" )
				)
			)
			( gate "@baseboard_fab2_lib.baseboard_fab2(sch_1):page217_i89"
				( attribute "BOM_COST" "MEM_VRD_PVDDQ_CD"
					( Origin gFrontEnd )
				)
				( attribute "CDS_LIB" "mstr_discrete"
					( Origin gPackager )
				)
				( attribute "CDS_LOCATION" "C5U14"
					( Origin gPackager )
				)
				( attribute "CDS_SEC" "1"
					( Origin gPackager )
				)
				( attribute "LOCATION" "C5U14"
					( Origin gFrontEnd )
				)
				( attribute "MATERIAL" "X5R"
					( Origin gFrontEnd )
				)
				( attribute "PACK_TYPE" "0805"
					( Origin gFrontEnd )
				)
				( attribute "PART_NUMBER" "602433-112"
					( Origin gFrontEnd )
				)
				( attribute "PHYS_PAGE" "217"
					( Origin gFrontEnd )
				)
				( attribute "ROOM" "VDDQ_ABC_PWR_VR"
					( Origin gFrontEnd )
				)
				( attribute "ROT" "0"
					( Origin gFrontEnd )
				)
				( attribute "SEC" "1"
					( Origin gFrontEnd )
				)
				( attribute "SEC_TYPE" "0805"
					( Origin gFrontEnd )
				)
				( attribute "TOLERANCE" "20%"
					( Origin gFrontEnd )
				)
				( attribute "VALUE" "100UF"
					( Origin gFrontEnd )
				)
				( attribute "VER" "1"
					( Origin gFrontEnd )
				)
				( attribute "VOLTAGE" "4V"
					( Units "uVoltage" "V" 1.000000)
					( Origin gFrontEnd )
				)
				( attribute "XY" "(4325,2850)"
					( Origin gFrontEnd )
				)
				( attribute "CHIPS_PART_NAME" "CAP"
					( Origin gPackager )
				)
				( attribute "CDS_PART_NAME" "CAP_0805-100UF,4V,20%,X5R,6024A"
					( Origin gPackager )
				)
				( objectStatus "C5U14" )
				( pin "a"
					( attribute "PN" "1"
						( Origin gPackager )
					)
					( objectStatus "C5U14.1" )
				)
				( pin "b"
					( attribute "PN" "2"
						( Origin gPackager )
					)
					( objectStatus "C5U14.2" )
				)
			)
			( gate "@baseboard_fab2_lib.baseboard_fab2(sch_1):page217_i90"
				( attribute "BOM_COST" "MEM_VRD_PVDDQ_CD"
					( Origin gFrontEnd )
				)
				( attribute "CDS_LIB" "mstr_discrete"
					( Origin gPackager )
				)
				( attribute "CDS_LOCATION" "C5U15"
					( Origin gPackager )
				)
				( attribute "CDS_SEC" "1"
					( Origin gPackager )
				)
				( attribute "LOCATION" "C5U15"
					( Origin gFrontEnd )
				)
				( attribute "MATERIAL" "X5R"
					( Origin gFrontEnd )
				)
				( attribute "PACK_TYPE" "0805"
					( Origin gFrontEnd )
				)
				( attribute "PART_NUMBER" "602433-112"
					( Origin gFrontEnd )
				)
				( attribute "PHYS_PAGE" "217"
					( Origin gFrontEnd )
				)
				( attribute "ROOM" "VDDQ_ABC_PWR_VR"
					( Origin gFrontEnd )
				)
				( attribute "ROT" "0"
					( Origin gFrontEnd )
				)
				( attribute "SEC" "1"
					( Origin gFrontEnd )
				)
				( attribute "SEC_TYPE" "0805"
					( Origin gFrontEnd )
				)
				( attribute "TOLERANCE" "20%"
					( Origin gFrontEnd )
				)
				( attribute "VALUE" "100UF"
					( Origin gFrontEnd )
				)
				( attribute "VER" "1"
					( Origin gFrontEnd )
				)
				( attribute "VOLTAGE" "4V"
					( Units "uVoltage" "V" 1.000000)
					( Origin gFrontEnd )
				)
				( attribute "XY" "(3975,2850)"
					( Origin gFrontEnd )
				)
				( attribute "CHIPS_PART_NAME" "CAP"
					( Origin gPackager )
				)
				( attribute "CDS_PART_NAME" "CAP_0805-100UF,4V,20%,X5R,6024A"
					( Origin gPackager )
				)
				( objectStatus "C5U15" )
				( pin "a"
					( attribute "PN" "1"
						( Origin gPackager )
					)
					( objectStatus "C5U15.1" )
				)
				( pin "b"
					( attribute "PN" "2"
						( Origin gPackager )
					)
					( objectStatus "C5U15.2" )
				)
			)
			( gate "@baseboard_fab2_lib.baseboard_fab2(sch_1):page217_i91"
				( attribute "BOM_COST" "MEM_VRD_PVDDQ_CD"
					( Origin gFrontEnd )
				)
				( attribute "CDS_LIB" "mstr_discrete"
					( Origin gPackager )
				)
				( attribute "CDS_LOCATION" "C4T4"
					( Origin gPackager )
				)
				( attribute "CDS_SEC" "1"
					( Origin gPackager )
				)
				( attribute "LOCATION" "C4T4"
					( Origin gFrontEnd )
				)
				( attribute "MATERIAL" "X5R"
					( Origin gFrontEnd )
				)
				( attribute "PACK_TYPE" "0805"
					( Origin gFrontEnd )
				)
				( attribute "PART_NUMBER" "602433-112"
					( Origin gFrontEnd )
				)
				( attribute "PHYS_PAGE" "217"
					( Origin gFrontEnd )
				)
				( attribute "ROOM" "VDDQ_ABC_PWR_VR"
					( Origin gFrontEnd )
				)
				( attribute "ROT" "0"
					( Origin gFrontEnd )
				)
				( attribute "SEC" "1"
					( Origin gFrontEnd )
				)
				( attribute "SEC_TYPE" "0805"
					( Origin gFrontEnd )
				)
				( attribute "TOLERANCE" "20%"
					( Origin gFrontEnd )
				)
				( attribute "VALUE" "100UF"
					( Origin gFrontEnd )
				)
				( attribute "VER" "1"
					( Origin gFrontEnd )
				)
				( attribute "VOLTAGE" "4V"
					( Units "uVoltage" "V" 1.000000)
					( Origin gFrontEnd )
				)
				( attribute "XY" "(3625,2850)"
					( Origin gFrontEnd )
				)
				( attribute "CHIPS_PART_NAME" "CAP"
					( Origin gPackager )
				)
				( attribute "CDS_PART_NAME" "CAP_0805-100UF,4V,20%,X5R,6024A"
					( Origin gPackager )
				)
				( objectStatus "C4T4" )
				( pin "a"
					( attribute "PN" "1"
						( Origin gPackager )
					)
					( objectStatus "C4T4.1" )
				)
				( pin "b"
					( attribute "PN" "2"
						( Origin gPackager )
					)
					( objectStatus "C4T4.2" )
				)
			)
			( gate "@baseboard_fab2_lib.baseboard_fab2(sch_1):page217_i92"
				( attribute "BOM_COST" "MEM_VRD_PVDDQ_CD"
					( Origin gFrontEnd )
				)
				( attribute "CDS_LIB" "mstr_discrete"
					( Origin gPackager )
				)
				( attribute "CDS_LOCATION" "C5G9"
					( Origin gPackager )
				)
				( attribute "CDS_SEC" "1"
					( Origin gPackager )
				)
				( attribute "LOCATION" "C5G9"
					( Origin gFrontEnd )
				)
				( attribute "MATERIAL" "X5R"
					( Origin gFrontEnd )
				)
				( attribute "PACK_TYPE" "0805"
					( Origin gFrontEnd )
				)
				( attribute "PART_NUMBER" "602433-112"
					( Origin gFrontEnd )
				)
				( attribute "PHYS_PAGE" "217"
					( Origin gFrontEnd )
				)
				( attribute "ROOM" "VDDQ_ABC_PWR_VR"
					( Origin gFrontEnd )
				)
				( attribute "ROT" "0"
					( Origin gFrontEnd )
				)
				( attribute "SEC" "1"
					( Origin gFrontEnd )
				)
				( attribute "SEC_TYPE" "0805"
					( Origin gFrontEnd )
				)
				( attribute "TOLERANCE" "20%"
					( Origin gFrontEnd )
				)
				( attribute "VALUE" "100UF"
					( Origin gFrontEnd )
				)
				( attribute "VER" "1"
					( Origin gFrontEnd )
				)
				( attribute "VOLTAGE" "4V"
					( Units "uVoltage" "V" 1.000000)
					( Origin gFrontEnd )
				)
				( attribute "XY" "(3225,2850)"
					( Origin gFrontEnd )
				)
				( attribute "CHIPS_PART_NAME" "CAP"
					( Origin gPackager )
				)
				( attribute "CDS_PART_NAME" "CAP_0805-100UF,4V,20%,X5R,6024A"
					( Origin gPackager )
				)
				( objectStatus "C5G9" )
				( pin "a"
					( attribute "PN" "1"
						( Origin gPackager )
					)
					( objectStatus "C5G9.1" )
				)
				( pin "b"
					( attribute "PN" "2"
						( Origin gPackager )
					)
					( objectStatus "C5G9.2" )
				)
			)
			( gate "@baseboard_fab2_lib.baseboard_fab2(sch_1):page217_i110"
				( attribute "BOM_COST" "MEM_VRD_PVDDQ_CD"
					( Origin gFrontEnd )
				)
				( attribute "CDS_LIB" "mstr_discrete"
					( Origin gPackager )
				)
				( attribute "CDS_LOCATION" "C5G20"
					( Origin gPackager )
				)
				( attribute "CDS_SEC" "1"
					( Origin gPackager )
				)
				( attribute "LOCATION" "C5G20"
					( Origin gFrontEnd )
				)
				( attribute "MATERIAL" "X5R"
					( Origin gFrontEnd )
				)
				( attribute "PACK_TYPE" "0805"
					( Origin gFrontEnd )
				)
				( attribute "PART_NUMBER" "602433-112"
					( Origin gFrontEnd )
				)
				( attribute "PHYS_PAGE" "217"
					( Origin gFrontEnd )
				)
				( attribute "ROOM" "VDDQ_ABC_PWR_VR"
					( Origin gFrontEnd )
				)
				( attribute "ROT" "0"
					( Origin gFrontEnd )
				)
				( attribute "SEC" "1"
					( Origin gFrontEnd )
				)
				( attribute "SEC_TYPE" "0805"
					( Origin gFrontEnd )
				)
				( attribute "TOLERANCE" "20%"
					( Origin gFrontEnd )
				)
				( attribute "VALUE" "100UF"
					( Origin gFrontEnd )
				)
				( attribute "VER" "1"
					( Origin gFrontEnd )
				)
				( attribute "VOLTAGE" "4V"
					( Units "uVoltage" "V" 1.000000)
					( Origin gFrontEnd )
				)
				( attribute "XY" "(2875,2850)"
					( Origin gFrontEnd )
				)
				( attribute "CHIPS_PART_NAME" "CAP"
					( Origin gPackager )
				)
				( attribute "CDS_PART_NAME" "CAP_0805-100UF,4V,20%,X5R,6024A"
					( Origin gPackager )
				)
				( objectStatus "C5G20" )
				( pin "a"
					( attribute "PN" "1"
						( Origin gPackager )
					)
					( objectStatus "C5G20.1" )
				)
				( pin "b"
					( attribute "PN" "2"
						( Origin gPackager )
					)
					( objectStatus "C5G20.2" )
				)
			)
			( gate "@baseboard_fab2_lib.baseboard_fab2(sch_1):page217_i124"
				( attribute "BOM_COST" "MEM_VRD_PVDDQ_CD"
					( Origin gFrontEnd )
				)
				( attribute "CDS_LIB" "mstr_discrete"
					( Origin gPackager )
				)
				( attribute "CDS_LOCATION" "L7F2"
					( Origin gPackager )
				)
				( attribute "CDS_SEC" "1"
					( Origin gPackager )
				)
				( attribute "LOCATION" "L7F2"
					( Origin gFrontEnd )
				)
				( attribute "MATERIAL" "IND"
					( Origin gFrontEnd )
				)
				( attribute "PACK_TYPE" "SM"
					( Origin gFrontEnd )
				)
				( attribute "PART_NUMBER" "D92183-020"
					( Origin gFrontEnd )
				)
				( attribute "PHYS_PAGE" "217"
					( Origin gFrontEnd )
				)
				( attribute "ROOM" "VDDQ_ABC_PWR_VR"
					( Origin gFrontEnd )
				)
				( attribute "ROT" "0"
					( Origin gFrontEnd )
				)
				( attribute "SEC" "1"
					( Origin gFrontEnd )
				)
				( attribute "SEC_TYPE" "SM"
					( Origin gFrontEnd )
				)
				( attribute "VALUE" "100NH"
					( Origin gFrontEnd )
				)
				( attribute "VER" "1"
					( Origin gFrontEnd )
				)
				( attribute "XY" "(-225,900)"
					( Origin gFrontEnd )
				)
				( attribute "CHIPS_PART_NAME" "INDUCTOR"
					( Origin gPackager )
				)
				( attribute "CDS_PART_NAME" "INDUCTOR_SM-100NH,IND,D92183-0B"
					( Origin gPackager )
				)
				( objectStatus "L7F2" )
				( pin "ina"
					( attribute "PN" "1"
						( Origin gPackager )
					)
					( objectStatus "L7F2.1" )
				)
				( pin "inb"
					( attribute "PN" "2"
						( Origin gPackager )
					)
					( objectStatus "L7F2.2" )
				)
			)
			( gate "@baseboard_fab2_lib.baseboard_fab2(sch_1):page217_i175"
				( attribute "CDS_LIB" "mstr_discrete"
					( Origin gPackager )
				)
				( attribute "CDS_LOCATION" "C7G2"
					( Origin gPackager )
				)
				( attribute "CDS_SEC" "1"
					( Origin gPackager )
				)
				( attribute "LOCATION" "C7G2"
					( Origin gFrontEnd )
				)
				( attribute "MATERIAL" "OSCON"
					( Origin gFrontEnd )
				)
				( attribute "PACK_TYPE" "2626"
					( Origin gFrontEnd )
				)
				( attribute "PART_NUMBER" "A31228-047"
					( Origin gFrontEnd )
				)
				( attribute "PHYS_PAGE" "217"
					( Origin gFrontEnd )
				)
				( attribute "ROOM" "VDDQ_ABC_PWR_VR"
					( Origin gFrontEnd )
				)
				( attribute "ROT" "0"
					( Origin gFrontEnd )
				)
				( attribute "SEC" "1"
					( Origin gFrontEnd )
				)
				( attribute "SEC_TYPE" "2626"
					( Origin gFrontEnd )
				)
				( attribute "TOLERANCE" "20%"
					( Origin gFrontEnd )
				)
				( attribute "VALUE" "270UF"
					( Origin gFrontEnd )
				)
				( attribute "VER" "1"
					( Origin gFrontEnd )
				)
				( attribute "VOLTAGE" "16V"
					( Units "uVoltage" "V" 1.000000)
					( Origin gFrontEnd )
				)
				( attribute "XY" "(200,700)"
					( Origin gFrontEnd )
				)
				( attribute "CHIPS_PART_NAME" "CAPP"
					( Origin gPackager )
				)
				( attribute "CDS_PART_NAME" "CAPP_2626-270UF,16V,20%,OSCON,A"
					( Origin gPackager )
				)
				( objectStatus "C7G2" )
				( pin "a"
					( attribute "PN" "1"
						( Origin gPackager )
					)
					( objectStatus "C7G2.1" )
				)
				( pin "b"
					( attribute "PN" "2"
						( Origin gPackager )
					)
					( objectStatus "C7G2.2" )
				)
			)
			( gate "@baseboard_fab2_lib.baseboard_fab2(sch_1):page217_i184"
				( attribute "BOM_COST" "MEM_VRD_PVDDQ_ABC"
					( Origin gFrontEnd )
				)
				( attribute "CDS_LIB" "mstr_discrete"
					( Origin gPackager )
				)
				( attribute "CDS_LOCATION" "C5P39"
					( Origin gPackager )
				)
				( attribute "CDS_SEC" "1"
					( Origin gPackager )
				)
				( attribute "LOCATION" "C5P39"
					( Origin gFrontEnd )
				)
				( attribute "MATERIAL" "X6S"
					( Origin gFrontEnd )
				)
				( attribute "PACK_TYPE" "0805LF"
					( Origin gFrontEnd )
				)
				( attribute "PART_NUMBER" "C95333-002"
					( Origin gFrontEnd )
				)
				( attribute "PHYS_PAGE" "217"
					( Origin gFrontEnd )
				)
				( attribute "ROOM" "VDDQ_ABC_CPU0"
					( Origin gFrontEnd )
				)
				( attribute "ROT" "0"
					( Origin gFrontEnd )
				)
				( attribute "SEC" "1"
					( Origin gFrontEnd )
				)
				( attribute "SEC_TYPE" "0805LF"
					( Origin gFrontEnd )
				)
				( attribute "TOLERANCE" "20%"
					( Origin gFrontEnd )
				)
				( attribute "VALUE" "22UF"
					( Origin gFrontEnd )
				)
				( attribute "VER" "1"
					( Origin gFrontEnd )
				)
				( attribute "VOLTAGE" "4V"
					( Units "uVoltage" "V" 1.000000)
					( Origin gFrontEnd )
				)
				( attribute "XY" "(-1650,2850)"
					( Origin gFrontEnd )
				)
				( attribute "CHIPS_PART_NAME" "CAP"
					( Origin gPackager )
				)
				( attribute "CDS_PART_NAME" "CAP_0805LF-22UF,4V,20%,X6S,C95A"
					( Origin gPackager )
				)
				( objectStatus "C5P39" )
				( pin "a"
					( attribute "PN" "1"
						( Origin gPackager )
					)
					( objectStatus "C5P39.1" )
				)
				( pin "b"
					( attribute "PN" "2"
						( Origin gPackager )
					)
					( objectStatus "C5P39.2" )
				)
			)
			( gate "@baseboard_fab2_lib.baseboard_fab2(sch_1):page217_i186"
				( attribute "BOM_COST" "MEM_VRD_PVDDQ_ABC"
					( Origin gFrontEnd )
				)
				( attribute "CDS_LIB" "mstr_discrete"
					( Origin gPackager )
				)
				( attribute "CDS_LOCATION" "C5D57"
					( Origin gPackager )
				)
				( attribute "CDS_SEC" "1"
					( Origin gPackager )
				)
				( attribute "LOCATION" "C5D57"
					( Origin gFrontEnd )
				)
				( attribute "MATERIAL" "X6S"
					( Origin gFrontEnd )
				)
				( attribute "PACK_TYPE" "0603LF"
					( Origin gFrontEnd )
				)
				( attribute "PART_NUMBER" "E15431-001"
					( Origin gFrontEnd )
				)
				( attribute "PHYS_PAGE" "217"
					( Origin gFrontEnd )
				)
				( attribute "ROOM" "VDDQ_ABC_CPU0"
					( Origin gFrontEnd )
				)
				( attribute "ROT" "0"
					( Origin gFrontEnd )
				)
				( attribute "SEC" "1"
					( Origin gFrontEnd )
				)
				( attribute "SEC_TYPE" "0603LF"
					( Origin gFrontEnd )
				)
				( attribute "TOLERANCE" "20%"
					( Origin gFrontEnd )
				)
				( attribute "VALUE" "10UF"
					( Origin gFrontEnd )
				)
				( attribute "VER" "1"
					( Origin gFrontEnd )
				)
				( attribute "VOLTAGE" "4V"
					( Units "uVoltage" "V" 1.000000)
					( Origin gFrontEnd )
				)
				( attribute "XY" "(150,2825)"
					( Origin gFrontEnd )
				)
				( attribute "CHIPS_PART_NAME" "CAP"
					( Origin gPackager )
				)
				( attribute "CDS_PART_NAME" "CAP_0603LF-10UF,4V,20%,X6S,E15A"
					( Origin gPackager )
				)
				( objectStatus "C5D57" )
				( pin "a"
					( attribute "PN" "1"
						( Origin gPackager )
					)
					( objectStatus "C5D57.1" )
				)
				( pin "b"
					( attribute "PN" "2"
						( Origin gPackager )
					)
					( objectStatus "C5D57.2" )
				)
			)
			( gate "@baseboard_fab2_lib.baseboard_fab2(sch_1):page217_i188"
				( attribute "BOM_COST" "MEM_VRD_PVDDQ_ABC"
					( Origin gFrontEnd )
				)
				( attribute "CDS_LIB" "mstr_discrete"
					( Origin gPackager )
				)
				( attribute "CDS_LOCATION" "C5D56"
					( Origin gPackager )
				)
				( attribute "CDS_SEC" "1"
					( Origin gPackager )
				)
				( attribute "LOCATION" "C5D56"
					( Origin gFrontEnd )
				)
				( attribute "MATERIAL" "X6S"
					( Origin gFrontEnd )
				)
				( attribute "PACK_TYPE" "0603LF"
					( Origin gFrontEnd )
				)
				( attribute "PART_NUMBER" "E15431-001"
					( Origin gFrontEnd )
				)
				( attribute "PHYS_PAGE" "217"
					( Origin gFrontEnd )
				)
				( attribute "ROOM" "VDDQ_ABC_CPU0"
					( Origin gFrontEnd )
				)
				( attribute "ROT" "0"
					( Origin gFrontEnd )
				)
				( attribute "SEC" "1"
					( Origin gFrontEnd )
				)
				( attribute "SEC_TYPE" "0603LF"
					( Origin gFrontEnd )
				)
				( attribute "TOLERANCE" "20%"
					( Origin gFrontEnd )
				)
				( attribute "VALUE" "10UF"
					( Origin gFrontEnd )
				)
				( attribute "VER" "1"
					( Origin gFrontEnd )
				)
				( attribute "VOLTAGE" "4V"
					( Units "uVoltage" "V" 1.000000)
					( Origin gFrontEnd )
				)
				( attribute "XY" "(-200,2850)"
					( Origin gFrontEnd )
				)
				( attribute "CHIPS_PART_NAME" "CAP"
					( Origin gPackager )
				)
				( attribute "CDS_PART_NAME" "CAP_0603LF-10UF,4V,20%,X6S,E15A"
					( Origin gPackager )
				)
				( objectStatus "C5D56" )
				( pin "a"
					( attribute "PN" "1"
						( Origin gPackager )
					)
					( objectStatus "C5D56.1" )
				)
				( pin "b"
					( attribute "PN" "2"
						( Origin gPackager )
					)
					( objectStatus "C5D56.2" )
				)
			)
			( gate "@baseboard_fab2_lib.baseboard_fab2(sch_1):page217_i189"
				( attribute "BOM_COST" "MEM_VRD_PVDDQ_ABC"
					( Origin gFrontEnd )
				)
				( attribute "CDS_LIB" "mstr_discrete"
					( Origin gPackager )
				)
				( attribute "CDS_LOCATION" "C5D55"
					( Origin gPackager )
				)
				( attribute "CDS_SEC" "1"
					( Origin gPackager )
				)
				( attribute "LOCATION" "C5D55"
					( Origin gFrontEnd )
				)
				( attribute "MATERIAL" "X6S"
					( Origin gFrontEnd )
				)
				( attribute "PACK_TYPE" "0603LF"
					( Origin gFrontEnd )
				)
				( attribute "PART_NUMBER" "E15431-001"
					( Origin gFrontEnd )
				)
				( attribute "PHYS_PAGE" "217"
					( Origin gFrontEnd )
				)
				( attribute "ROOM" "VDDQ_ABC_CPU0"
					( Origin gFrontEnd )
				)
				( attribute "ROT" "0"
					( Origin gFrontEnd )
				)
				( attribute "SEC" "1"
					( Origin gFrontEnd )
				)
				( attribute "SEC_TYPE" "0603LF"
					( Origin gFrontEnd )
				)
				( attribute "TOLERANCE" "20%"
					( Origin gFrontEnd )
				)
				( attribute "VALUE" "10UF"
					( Origin gFrontEnd )
				)
				( attribute "VER" "1"
					( Origin gFrontEnd )
				)
				( attribute "VOLTAGE" "4V"
					( Units "uVoltage" "V" 1.000000)
					( Origin gFrontEnd )
				)
				( attribute "XY" "(-550,2850)"
					( Origin gFrontEnd )
				)
				( attribute "CHIPS_PART_NAME" "CAP"
					( Origin gPackager )
				)
				( attribute "CDS_PART_NAME" "CAP_0603LF-10UF,4V,20%,X6S,E15A"
					( Origin gPackager )
				)
				( objectStatus "C5D55" )
				( pin "a"
					( attribute "PN" "1"
						( Origin gPackager )
					)
					( objectStatus "C5D55.1" )
				)
				( pin "b"
					( attribute "PN" "2"
						( Origin gPackager )
					)
					( objectStatus "C5D55.2" )
				)
			)
			( gate "@baseboard_fab2_lib.baseboard_fab2(sch_1):page217_i190"
				( attribute "BOM_COST" "MEM_VRD_PVDDQ_ABC"
					( Origin gFrontEnd )
				)
				( attribute "CDS_LIB" "mstr_discrete"
					( Origin gPackager )
				)
				( attribute "CDS_LOCATION" "C5D54"
					( Origin gPackager )
				)
				( attribute "CDS_SEC" "1"
					( Origin gPackager )
				)
				( attribute "LOCATION" "C5D54"
					( Origin gFrontEnd )
				)
				( attribute "MATERIAL" "X6S"
					( Origin gFrontEnd )
				)
				( attribute "PACK_TYPE" "0603LF"
					( Origin gFrontEnd )
				)
				( attribute "PART_NUMBER" "E15431-001"
					( Origin gFrontEnd )
				)
				( attribute "PHYS_PAGE" "217"
					( Origin gFrontEnd )
				)
				( attribute "ROOM" "VDDQ_ABC_CPU0"
					( Origin gFrontEnd )
				)
				( attribute "ROT" "0"
					( Origin gFrontEnd )
				)
				( attribute "SEC" "1"
					( Origin gFrontEnd )
				)
				( attribute "SEC_TYPE" "0603LF"
					( Origin gFrontEnd )
				)
				( attribute "TOLERANCE" "20%"
					( Origin gFrontEnd )
				)
				( attribute "VALUE" "10UF"
					( Origin gFrontEnd )
				)
				( attribute "VER" "1"
					( Origin gFrontEnd )
				)
				( attribute "VOLTAGE" "4V"
					( Units "uVoltage" "V" 1.000000)
					( Origin gFrontEnd )
				)
				( attribute "XY" "(-900,2850)"
					( Origin gFrontEnd )
				)
				( attribute "CHIPS_PART_NAME" "CAP"
					( Origin gPackager )
				)
				( attribute "CDS_PART_NAME" "CAP_0603LF-10UF,4V,20%,X6S,E15A"
					( Origin gPackager )
				)
				( objectStatus "C5D54" )
				( pin "a"
					( attribute "PN" "1"
						( Origin gPackager )
					)
					( objectStatus "C5D54.1" )
				)
				( pin "b"
					( attribute "PN" "2"
						( Origin gPackager )
					)
					( objectStatus "C5D54.2" )
				)
			)
			( gate "@baseboard_fab2_lib.baseboard_fab2(sch_1):page217_i193"
				( attribute "BOM_COST" "MEM_VRD_PVDDQ_ABC"
					( Origin gFrontEnd )
				)
				( attribute "CDS_LIB" "mstr_discrete"
					( Origin gPackager )
				)
				( attribute "CDS_LOCATION" "C5P38"
					( Origin gPackager )
				)
				( attribute "CDS_SEC" "1"
					( Origin gPackager )
				)
				( attribute "LOCATION" "C5P38"
					( Origin gFrontEnd )
				)
				( attribute "MATERIAL" "X6S"
					( Origin gFrontEnd )
				)
				( attribute "PACK_TYPE" "0805LF"
					( Origin gFrontEnd )
				)
				( attribute "PART_NUMBER" "C95333-002"
					( Origin gFrontEnd )
				)
				( attribute "PHYS_PAGE" "217"
					( Origin gFrontEnd )
				)
				( attribute "ROOM" "VDDQ_ABC_CPU0"
					( Origin gFrontEnd )
				)
				( attribute "ROT" "0"
					( Origin gFrontEnd )
				)
				( attribute "SEC" "1"
					( Origin gFrontEnd )
				)
				( attribute "SEC_TYPE" "0805LF"
					( Origin gFrontEnd )
				)
				( attribute "TOLERANCE" "20%"
					( Origin gFrontEnd )
				)
				( attribute "VALUE" "22UF"
					( Origin gFrontEnd )
				)
				( attribute "VER" "1"
					( Origin gFrontEnd )
				)
				( attribute "VOLTAGE" "4V"
					( Units "uVoltage" "V" 1.000000)
					( Origin gFrontEnd )
				)
				( attribute "XY" "(-1300,2850)"
					( Origin gFrontEnd )
				)
				( attribute "CHIPS_PART_NAME" "CAP"
					( Origin gPackager )
				)
				( attribute "CDS_PART_NAME" "CAP_0805LF-22UF,4V,20%,X6S,C95A"
					( Origin gPackager )
				)
				( objectStatus "C5P38" )
				( pin "a"
					( attribute "PN" "1"
						( Origin gPackager )
					)
					( objectStatus "C5P38.1" )
				)
				( pin "b"
					( attribute "PN" "2"
						( Origin gPackager )
					)
					( objectStatus "C5P38.2" )
				)
			)
			( gate "@baseboard_fab2_lib.baseboard_fab2(sch_1):page217_i205"
				( attribute "CDS_LIB" "dev_discrete"
					( Origin gPackager )
				)
				( attribute "CDS_LOCATION" "C5F2"
					( Origin gPackager )
				)
				( attribute "CDS_SEC" "1"
					( Origin gPackager )
				)
				( attribute "LOCATION" "C5F2"
					( Origin gFrontEnd )
				)
				( attribute "MATERIAL" "X5R"
					( Origin gFrontEnd )
				)
				( attribute "PACK_TYPE" "0603V"
					( Origin gFrontEnd )
				)
				( attribute "PART_NUMBER" "602433-106"
					( Origin gFrontEnd )
				)
				( attribute "PHYS_PAGE" "217"
					( Origin gFrontEnd )
				)
				( attribute "ROT" "0"
					( Origin gFrontEnd )
				)
				( attribute "SEC" "1"
					( Origin gFrontEnd )
				)
				( attribute "SEC_TYPE" "0603V"
					( Origin gFrontEnd )
				)
				( attribute "TOLERANCE" "20%"
					( Origin gFrontEnd )
				)
				( attribute "VALUE" "47UF"
					( Origin gFrontEnd )
				)
				( attribute "VER" "1"
					( Origin gFrontEnd )
				)
				( attribute "VOLTAGE" "4V"
					( Units "uVoltage" "V" 1.000000)
					( Origin gFrontEnd )
				)
				( attribute "XY" "(2925,1000)"
					( Origin gFrontEnd )
				)
				( attribute "CHIPS_PART_NAME" "CAP_A"
					( Origin gPackager )
				)
				( attribute "CDS_PART_NAME" "CAP_A_0603V-47UF,4V,20%,X5R,60A"
					( Origin gPackager )
				)
				( objectStatus "C5F2" )
				( pin "a"
					( attribute "PN" "1"
						( Origin gPackager )
					)
					( objectStatus "C5F2.1" )
				)
				( pin "b"
					( attribute "PN" "2"
						( Origin gPackager )
					)
					( objectStatus "C5F2.2" )
				)
			)
			( gate "@baseboard_fab2_lib.baseboard_fab2(sch_1):page217_i206"
				( attribute "CDS_LIB" "dev_discrete"
					( Origin gPackager )
				)
				( attribute "CDS_LOCATION" "C5F1"
					( Origin gPackager )
				)
				( attribute "CDS_SEC" "1"
					( Origin gPackager )
				)
				( attribute "LOCATION" "C5F1"
					( Origin gFrontEnd )
				)
				( attribute "MATERIAL" "X5R"
					( Origin gFrontEnd )
				)
				( attribute "PACK_TYPE" "0603V"
					( Origin gFrontEnd )
				)
				( attribute "PART_NUMBER" "602433-106"
					( Origin gFrontEnd )
				)
				( attribute "PHYS_PAGE" "217"
					( Origin gFrontEnd )
				)
				( attribute "ROT" "0"
					( Origin gFrontEnd )
				)
				( attribute "SEC" "1"
					( Origin gFrontEnd )
				)
				( attribute "SEC_TYPE" "0603V"
					( Origin gFrontEnd )
				)
				( attribute "TOLERANCE" "20%"
					( Origin gFrontEnd )
				)
				( attribute "VALUE" "47UF"
					( Origin gFrontEnd )
				)
				( attribute "VER" "1"
					( Origin gFrontEnd )
				)
				( attribute "VOLTAGE" "4V"
					( Units "uVoltage" "V" 1.000000)
					( Origin gFrontEnd )
				)
				( attribute "XY" "(3275,1000)"
					( Origin gFrontEnd )
				)
				( attribute "CHIPS_PART_NAME" "CAP_A"
					( Origin gPackager )
				)
				( attribute "CDS_PART_NAME" "CAP_A_0603V-47UF,4V,20%,X5R,60A"
					( Origin gPackager )
				)
				( objectStatus "C5F1" )
				( pin "a"
					( attribute "PN" "1"
						( Origin gPackager )
					)
					( objectStatus "C5F1.1" )
				)
				( pin "b"
					( attribute "PN" "2"
						( Origin gPackager )
					)
					( objectStatus "C5F1.2" )
				)
			)
			( gate "@baseboard_fab2_lib.baseboard_fab2(sch_1):page217_i207"
				( attribute "CDS_LIB" "dev_discrete"
					( Origin gPackager )
				)
				( attribute "CDS_LOCATION" "C5G10"
					( Origin gPackager )
				)
				( attribute "CDS_SEC" "1"
					( Origin gPackager )
				)
				( attribute "LOCATION" "C5G10"
					( Origin gFrontEnd )
				)
				( attribute "MATERIAL" "X5R"
					( Origin gFrontEnd )
				)
				( attribute "PACK_TYPE" "0603V"
					( Origin gFrontEnd )
				)
				( attribute "PART_NUMBER" "602433-106"
					( Origin gFrontEnd )
				)
				( attribute "PHYS_PAGE" "217"
					( Origin gFrontEnd )
				)
				( attribute "ROT" "0"
					( Origin gFrontEnd )
				)
				( attribute "SEC" "1"
					( Origin gFrontEnd )
				)
				( attribute "SEC_TYPE" "0603V"
					( Origin gFrontEnd )
				)
				( attribute "TOLERANCE" "20%"
					( Origin gFrontEnd )
				)
				( attribute "VALUE" "47UF"
					( Origin gFrontEnd )
				)
				( attribute "VER" "1"
					( Origin gFrontEnd )
				)
				( attribute "VOLTAGE" "4V"
					( Units "uVoltage" "V" 1.000000)
					( Origin gFrontEnd )
				)
				( attribute "XY" "(3675,1000)"
					( Origin gFrontEnd )
				)
				( attribute "CHIPS_PART_NAME" "CAP_A"
					( Origin gPackager )
				)
				( attribute "CDS_PART_NAME" "CAP_A_0603V-47UF,4V,20%,X5R,60A"
					( Origin gPackager )
				)
				( objectStatus "C5G10" )
				( pin "a"
					( attribute "PN" "1"
						( Origin gPackager )
					)
					( objectStatus "C5G10.1" )
				)
				( pin "b"
					( attribute "PN" "2"
						( Origin gPackager )
					)
					( objectStatus "C5G10.2" )
				)
			)
			( gate "@baseboard_fab2_lib.baseboard_fab2(sch_1):page217_i208"
				( attribute "CDS_LIB" "dev_discrete"
					( Origin gPackager )
				)
				( attribute "CDS_LOCATION" "C5T2"
					( Origin gPackager )
				)
				( attribute "CDS_SEC" "1"
					( Origin gPackager )
				)
				( attribute "LOCATION" "C5T2"
					( Origin gFrontEnd )
				)
				( attribute "MATERIAL" "X5R"
					( Origin gFrontEnd )
				)
				( attribute "PACK_TYPE" "0603V"
					( Origin gFrontEnd )
				)
				( attribute "PART_NUMBER" "602433-106"
					( Origin gFrontEnd )
				)
				( attribute "PHYS_PAGE" "217"
					( Origin gFrontEnd )
				)
				( attribute "ROT" "0"
					( Origin gFrontEnd )
				)
				( attribute "SEC" "1"
					( Origin gFrontEnd )
				)
				( attribute "SEC_TYPE" "0603V"
					( Origin gFrontEnd )
				)
				( attribute "TOLERANCE" "20%"
					( Origin gFrontEnd )
				)
				( attribute "VALUE" "47UF"
					( Origin gFrontEnd )
				)
				( attribute "VER" "1"
					( Origin gFrontEnd )
				)
				( attribute "VOLTAGE" "4V"
					( Units "uVoltage" "V" 1.000000)
					( Origin gFrontEnd )
				)
				( attribute "XY" "(4000,1725)"
					( Origin gFrontEnd )
				)
				( attribute "CHIPS_PART_NAME" "CAP_A"
					( Origin gPackager )
				)
				( attribute "CDS_PART_NAME" "CAP_A_0603V-47UF,4V,20%,X5R,60A"
					( Origin gPackager )
				)
				( objectStatus "C5T2" )
				( pin "a"
					( attribute "PN" "1"
						( Origin gPackager )
					)
					( objectStatus "C5T2.1" )
				)
				( pin "b"
					( attribute "PN" "2"
						( Origin gPackager )
					)
					( objectStatus "C5T2.2" )
				)
			)
			( gate "@baseboard_fab2_lib.baseboard_fab2(sch_1):page217_i209"
				( attribute "CDS_LIB" "dev_discrete"
					( Origin gPackager )
				)
				( attribute "CDS_LOCATION" "C5U11"
					( Origin gPackager )
				)
				( attribute "CDS_SEC" "1"
					( Origin gPackager )
				)
				( attribute "LOCATION" "C5U11"
					( Origin gFrontEnd )
				)
				( attribute "MATERIAL" "X5R"
					( Origin gFrontEnd )
				)
				( attribute "PACK_TYPE" "0603V"
					( Origin gFrontEnd )
				)
				( attribute "PART_NUMBER" "602433-106"
					( Origin gFrontEnd )
				)
				( attribute "PHYS_PAGE" "217"
					( Origin gFrontEnd )
				)
				( attribute "ROT" "0"
					( Origin gFrontEnd )
				)
				( attribute "SEC" "1"
					( Origin gFrontEnd )
				)
				( attribute "SEC_TYPE" "0603V"
					( Origin gFrontEnd )
				)
				( attribute "TOLERANCE" "20%"
					( Origin gFrontEnd )
				)
				( attribute "VALUE" "47UF"
					( Origin gFrontEnd )
				)
				( attribute "VER" "1"
					( Origin gFrontEnd )
				)
				( attribute "VOLTAGE" "4V"
					( Units "uVoltage" "V" 1.000000)
					( Origin gFrontEnd )
				)
				( attribute "XY" "(4350,1725)"
					( Origin gFrontEnd )
				)
				( attribute "CHIPS_PART_NAME" "CAP_A"
					( Origin gPackager )
				)
				( attribute "CDS_PART_NAME" "CAP_A_0603V-47UF,4V,20%,X5R,60A"
					( Origin gPackager )
				)
				( objectStatus "C5U11" )
				( pin "a"
					( attribute "PN" "1"
						( Origin gPackager )
					)
					( objectStatus "C5U11.1" )
				)
				( pin "b"
					( attribute "PN" "2"
						( Origin gPackager )
					)
					( objectStatus "C5U11.2" )
				)
			)
			( gate "@baseboard_fab2_lib.baseboard_fab2(sch_1):page217_i210"
				( attribute "CDS_LIB" "dev_discrete"
					( Origin gPackager )
				)
				( attribute "CDS_LOCATION" "C5T13"
					( Origin gPackager )
				)
				( attribute "CDS_SEC" "1"
					( Origin gPackager )
				)
				( attribute "LOCATION" "C5T13"
					( Origin gFrontEnd )
				)
				( attribute "MATERIAL" "X5R"
					( Origin gFrontEnd )
				)
				( attribute "PACK_TYPE" "0603V"
					( Origin gFrontEnd )
				)
				( attribute "PART_NUMBER" "602433-106"
					( Origin gFrontEnd )
				)
				( attribute "PHYS_PAGE" "217"
					( Origin gFrontEnd )
				)
				( attribute "ROT" "0"
					( Origin gFrontEnd )
				)
				( attribute "SEC" "1"
					( Origin gFrontEnd )
				)
				( attribute "SEC_TYPE" "0603V"
					( Origin gFrontEnd )
				)
				( attribute "TOLERANCE" "20%"
					( Origin gFrontEnd )
				)
				( attribute "VALUE" "47UF"
					( Origin gFrontEnd )
				)
				( attribute "VER" "1"
					( Origin gFrontEnd )
				)
				( attribute "VOLTAGE" "4V"
					( Units "uVoltage" "V" 1.000000)
					( Origin gFrontEnd )
				)
				( attribute "XY" "(4750,1725)"
					( Origin gFrontEnd )
				)
				( attribute "CHIPS_PART_NAME" "CAP_A"
					( Origin gPackager )
				)
				( attribute "CDS_PART_NAME" "CAP_A_0603V-47UF,4V,20%,X5R,60A"
					( Origin gPackager )
				)
				( objectStatus "C5T13" )
				( pin "a"
					( attribute "PN" "1"
						( Origin gPackager )
					)
					( objectStatus "C5T13.1" )
				)
				( pin "b"
					( attribute "PN" "2"
						( Origin gPackager )
					)
					( objectStatus "C5T13.2" )
				)
			)
			( gate "@baseboard_fab2_lib.baseboard_fab2(sch_1):page217_i211"
				( attribute "CDS_LIB" "dev_discrete"
					( Origin gPackager )
				)
				( attribute "CDS_LOCATION" "C5T4"
					( Origin gPackager )
				)
				( attribute "CDS_SEC" "1"
					( Origin gPackager )
				)
				( attribute "LOCATION" "C5T4"
					( Origin gFrontEnd )
				)
				( attribute "MATERIAL" "X5R"
					( Origin gFrontEnd )
				)
				( attribute "PACK_TYPE" "0603V"
					( Origin gFrontEnd )
				)
				( attribute "PART_NUMBER" "602433-106"
					( Origin gFrontEnd )
				)
				( attribute "PHYS_PAGE" "217"
					( Origin gFrontEnd )
				)
				( attribute "ROT" "0"
					( Origin gFrontEnd )
				)
				( attribute "SEC" "1"
					( Origin gFrontEnd )
				)
				( attribute "SEC_TYPE" "0603V"
					( Origin gFrontEnd )
				)
				( attribute "TOLERANCE" "20%"
					( Origin gFrontEnd )
				)
				( attribute "VALUE" "47UF"
					( Origin gFrontEnd )
				)
				( attribute "VER" "1"
					( Origin gFrontEnd )
				)
				( attribute "VOLTAGE" "4V"
					( Units "uVoltage" "V" 1.000000)
					( Origin gFrontEnd )
				)
				( attribute "XY" "(3650,1725)"
					( Origin gFrontEnd )
				)
				( attribute "CHIPS_PART_NAME" "CAP_A"
					( Origin gPackager )
				)
				( attribute "CDS_PART_NAME" "CAP_A_0603V-47UF,4V,20%,X5R,60A"
					( Origin gPackager )
				)
				( objectStatus "C5T4" )
				( pin "a"
					( attribute "PN" "1"
						( Origin gPackager )
					)
					( objectStatus "C5T4.1" )
				)
				( pin "b"
					( attribute "PN" "2"
						( Origin gPackager )
					)
					( objectStatus "C5T4.2" )
				)
			)
			( gate "@baseboard_fab2_lib.baseboard_fab2(sch_1):page217_i212"
				( attribute "CDS_LIB" "dev_discrete"
					( Origin gPackager )
				)
				( attribute "CDS_LOCATION" "C5T1"
					( Origin gPackager )
				)
				( attribute "CDS_SEC" "1"
					( Origin gPackager )
				)
				( attribute "LOCATION" "C5T1"
					( Origin gFrontEnd )
				)
				( attribute "MATERIAL" "X5R"
					( Origin gFrontEnd )
				)
				( attribute "PACK_TYPE" "0603V"
					( Origin gFrontEnd )
				)
				( attribute "PART_NUMBER" "602433-106"
					( Origin gFrontEnd )
				)
				( attribute "PHYS_PAGE" "217"
					( Origin gFrontEnd )
				)
				( attribute "ROT" "0"
					( Origin gFrontEnd )
				)
				( attribute "SEC" "1"
					( Origin gFrontEnd )
				)
				( attribute "SEC_TYPE" "0603V"
					( Origin gFrontEnd )
				)
				( attribute "TOLERANCE" "20%"
					( Origin gFrontEnd )
				)
				( attribute "VALUE" "47UF"
					( Origin gFrontEnd )
				)
				( attribute "VER" "1"
					( Origin gFrontEnd )
				)
				( attribute "VOLTAGE" "4V"
					( Units "uVoltage" "V" 1.000000)
					( Origin gFrontEnd )
				)
				( attribute "XY" "(3250,1725)"
					( Origin gFrontEnd )
				)
				( attribute "CHIPS_PART_NAME" "CAP_A"
					( Origin gPackager )
				)
				( attribute "CDS_PART_NAME" "CAP_A_0603V-47UF,4V,20%,X5R,60A"
					( Origin gPackager )
				)
				( objectStatus "C5T1" )
				( pin "a"
					( attribute "PN" "1"
						( Origin gPackager )
					)
					( objectStatus "C5T1.1" )
				)
				( pin "b"
					( attribute "PN" "2"
						( Origin gPackager )
					)
					( objectStatus "C5T1.2" )
				)
			)
			( gate "@baseboard_fab2_lib.baseboard_fab2(sch_1):page217_i213"
				( attribute "CDS_LIB" "dev_discrete"
					( Origin gPackager )
				)
				( attribute "CDS_LOCATION" "C5G19"
					( Origin gPackager )
				)
				( attribute "CDS_SEC" "1"
					( Origin gPackager )
				)
				( attribute "LOCATION" "C5G19"
					( Origin gFrontEnd )
				)
				( attribute "MATERIAL" "X5R"
					( Origin gFrontEnd )
				)
				( attribute "PACK_TYPE" "0603V"
					( Origin gFrontEnd )
				)
				( attribute "PART_NUMBER" "602433-106"
					( Origin gFrontEnd )
				)
				( attribute "PHYS_PAGE" "217"
					( Origin gFrontEnd )
				)
				( attribute "ROT" "0"
					( Origin gFrontEnd )
				)
				( attribute "SEC" "1"
					( Origin gFrontEnd )
				)
				( attribute "SEC_TYPE" "0603V"
					( Origin gFrontEnd )
				)
				( attribute "TOLERANCE" "20%"
					( Origin gFrontEnd )
				)
				( attribute "VALUE" "47UF"
					( Origin gFrontEnd )
				)
				( attribute "VER" "1"
					( Origin gFrontEnd )
				)
				( attribute "VOLTAGE" "4V"
					( Units "uVoltage" "V" 1.000000)
					( Origin gFrontEnd )
				)
				( attribute "XY" "(2900,1725)"
					( Origin gFrontEnd )
				)
				( attribute "CHIPS_PART_NAME" "CAP_A"
					( Origin gPackager )
				)
				( attribute "CDS_PART_NAME" "CAP_A_0603V-47UF,4V,20%,X5R,60A"
					( Origin gPackager )
				)
				( objectStatus "C5G19" )
				( pin "a"
					( attribute "PN" "1"
						( Origin gPackager )
					)
					( objectStatus "C5G19.1" )
				)
				( pin "b"
					( attribute "PN" "2"
						( Origin gPackager )
					)
					( objectStatus "C5G19.2" )
				)
			)
			( gate "@baseboard_fab2_lib.baseboard_fab2(sch_1):page217_i216"
				( attribute "CDS_LIB" "dev_discrete"
					( Origin gPackager )
				)
				( attribute "CDS_LOCATION" "C5T5"
					( Origin gPackager )
				)
				( attribute "CDS_SEC" "1"
					( Origin gPackager )
				)
				( attribute "LOCATION" "C5T5"
					( Origin gFrontEnd )
				)
				( attribute "MATERIAL" "X6S"
					( Origin gFrontEnd )
				)
				( attribute "PACK_TYPE" "0603V"
					( Origin gFrontEnd )
				)
				( attribute "PART_NUMBER" "E15431-004"
					( Origin gFrontEnd )
				)
				( attribute "PHYS_PAGE" "217"
					( Origin gFrontEnd )
				)
				( attribute "ROOM" "PVDDQ_ABC"
					( Origin gFrontEnd )
				)
				( attribute "ROT" "0"
					( Origin gFrontEnd )
				)
				( attribute "SEC" "1"
					( Origin gPackager )
				)
				( attribute "TOLERANCE" "20%"
					( Origin gFrontEnd )
				)
				( attribute "VALUE" "22.0UF"
					( Origin gFrontEnd )
				)
				( attribute "VER" "1"
					( Origin gFrontEnd )
				)
				( attribute "VOLTAGE" "4V"
					( Units "uVoltage" "V" 1.000000)
					( Origin gFrontEnd )
				)
				( attribute "XY" "(2550,50)"
					( Origin gFrontEnd )
				)
				( attribute "CHIPS_PART_NAME" "CAP_A"
					( Origin gPackager )
				)
				( attribute "CDS_PART_NAME" "CAP_A_0603V-22.0UF,4V,20%,X6S,A"
					( Origin gPackager )
				)
				( objectStatus "C5T5" )
				( pin "a"
					( attribute "PN" "1"
						( Origin gPackager )
					)
					( objectStatus "C5T5.1" )
				)
				( pin "b"
					( attribute "PN" "2"
						( Origin gPackager )
					)
					( objectStatus "C5T5.2" )
				)
			)
			( gate "@baseboard_fab2_lib.baseboard_fab2(sch_1):page217_i217"
				( attribute "CDS_LIB" "dev_discrete"
					( Origin gPackager )
				)
				( attribute "CDS_LOCATION" "C5G3"
					( Origin gPackager )
				)
				( attribute "CDS_SEC" "1"
					( Origin gPackager )
				)
				( attribute "LOCATION" "C5G3"
					( Origin gFrontEnd )
				)
				( attribute "MATERIAL" "X6S"
					( Origin gFrontEnd )
				)
				( attribute "PACK_TYPE" "0603V"
					( Origin gFrontEnd )
				)
				( attribute "PART_NUMBER" "E15431-004"
					( Origin gFrontEnd )
				)
				( attribute "PHYS_PAGE" "217"
					( Origin gFrontEnd )
				)
				( attribute "ROOM" "PVDDQ_ABC"
					( Origin gFrontEnd )
				)
				( attribute "ROT" "0"
					( Origin gFrontEnd )
				)
				( attribute "SEC" "1"
					( Origin gPackager )
				)
				( attribute "TOLERANCE" "20%"
					( Origin gFrontEnd )
				)
				( attribute "VALUE" "22.0UF"
					( Origin gFrontEnd )
				)
				( attribute "VER" "1"
					( Origin gFrontEnd )
				)
				( attribute "VOLTAGE" "4V"
					( Units "uVoltage" "V" 1.000000)
					( Origin gFrontEnd )
				)
				( attribute "XY" "(2525,-650)"
					( Origin gFrontEnd )
				)
				( attribute "CHIPS_PART_NAME" "CAP_A"
					( Origin gPackager )
				)
				( attribute "CDS_PART_NAME" "CAP_A_0603V-22.0UF,4V,20%,X6S,A"
					( Origin gPackager )
				)
				( objectStatus "C5G3" )
				( pin "a"
					( attribute "PN" "1"
						( Origin gPackager )
					)
					( objectStatus "C5G3.1" )
				)
				( pin "b"
					( attribute "PN" "2"
						( Origin gPackager )
					)
					( objectStatus "C5G3.2" )
				)
			)
			( gate "@baseboard_fab2_lib.baseboard_fab2(sch_1):page217_i218"
				( attribute "CDS_LIB" "dev_discrete"
					( Origin gPackager )
				)
				( attribute "CDS_LOCATION" "C5T6"
					( Origin gPackager )
				)
				( attribute "CDS_SEC" "1"
					( Origin gPackager )
				)
				( attribute "LOCATION" "C5T6"
					( Origin gFrontEnd )
				)
				( attribute "MATERIAL" "X6S"
					( Origin gFrontEnd )
				)
				( attribute "PACK_TYPE" "0603V"
					( Origin gFrontEnd )
				)
				( attribute "PART_NUMBER" "E15431-004"
					( Origin gFrontEnd )
				)
				( attribute "PHYS_PAGE" "217"
					( Origin gFrontEnd )
				)
				( attribute "ROOM" "PVDDQ_ABC"
					( Origin gFrontEnd )
				)
				( attribute "ROT" "0"
					( Origin gFrontEnd )
				)
				( attribute "SEC" "1"
					( Origin gPackager )
				)
				( attribute "TOLERANCE" "20%"
					( Origin gFrontEnd )
				)
				( attribute "VALUE" "22.0UF"
					( Origin gFrontEnd )
				)
				( attribute "VER" "1"
					( Origin gFrontEnd )
				)
				( attribute "VOLTAGE" "4V"
					( Units "uVoltage" "V" 1.000000)
					( Origin gFrontEnd )
				)
				( attribute "XY" "(2275,50)"
					( Origin gFrontEnd )
				)
				( attribute "CHIPS_PART_NAME" "CAP_A"
					( Origin gPackager )
				)
				( attribute "CDS_PART_NAME" "CAP_A_0603V-22.0UF,4V,20%,X6S,A"
					( Origin gPackager )
				)
				( objectStatus "C5T6" )
				( pin "a"
					( attribute "PN" "1"
						( Origin gPackager )
					)
					( objectStatus "C5T6.1" )
				)
				( pin "b"
					( attribute "PN" "2"
						( Origin gPackager )
					)
					( objectStatus "C5T6.2" )
				)
			)
			( gate "@baseboard_fab2_lib.baseboard_fab2(sch_1):page217_i219"
				( attribute "CDS_LIB" "dev_discrete"
					( Origin gPackager )
				)
				( attribute "CDS_LOCATION" "C5T7"
					( Origin gPackager )
				)
				( attribute "CDS_SEC" "1"
					( Origin gPackager )
				)
				( attribute "LOCATION" "C5T7"
					( Origin gFrontEnd )
				)
				( attribute "MATERIAL" "X6S"
					( Origin gFrontEnd )
				)
				( attribute "PACK_TYPE" "0603V"
					( Origin gFrontEnd )
				)
				( attribute "PART_NUMBER" "E15431-004"
					( Origin gFrontEnd )
				)
				( attribute "PHYS_PAGE" "217"
					( Origin gFrontEnd )
				)
				( attribute "ROOM" "PVDDQ_ABC"
					( Origin gFrontEnd )
				)
				( attribute "ROT" "0"
					( Origin gFrontEnd )
				)
				( attribute "SEC" "1"
					( Origin gPackager )
				)
				( attribute "TOLERANCE" "20%"
					( Origin gFrontEnd )
				)
				( attribute "VALUE" "22.0UF"
					( Origin gFrontEnd )
				)
				( attribute "VER" "1"
					( Origin gFrontEnd )
				)
				( attribute "VOLTAGE" "4V"
					( Units "uVoltage" "V" 1.000000)
					( Origin gFrontEnd )
				)
				( attribute "XY" "(1975,50)"
					( Origin gFrontEnd )
				)
				( attribute "CHIPS_PART_NAME" "CAP_A"
					( Origin gPackager )
				)
				( attribute "CDS_PART_NAME" "CAP_A_0603V-22.0UF,4V,20%,X6S,A"
					( Origin gPackager )
				)
				( objectStatus "C5T7" )
				( pin "a"
					( attribute "PN" "1"
						( Origin gPackager )
					)
					( objectStatus "C5T7.1" )
				)
				( pin "b"
					( attribute "PN" "2"
						( Origin gPackager )
					)
					( objectStatus "C5T7.2" )
				)
			)
			( gate "@baseboard_fab2_lib.baseboard_fab2(sch_1):page217_i220"
				( attribute "CDS_LIB" "dev_discrete"
					( Origin gPackager )
				)
				( attribute "CDS_LOCATION" "C5G15"
					( Origin gPackager )
				)
				( attribute "CDS_SEC" "1"
					( Origin gPackager )
				)
				( attribute "LOCATION" "C5G15"
					( Origin gFrontEnd )
				)
				( attribute "MATERIAL" "X6S"
					( Origin gFrontEnd )
				)
				( attribute "PACK_TYPE" "0603V"
					( Origin gFrontEnd )
				)
				( attribute "PART_NUMBER" "E15431-004"
					( Origin gFrontEnd )
				)
				( attribute "PHYS_PAGE" "217"
					( Origin gFrontEnd )
				)
				( attribute "ROOM" "PVDDQ_ABC"
					( Origin gFrontEnd )
				)
				( attribute "ROT" "0"
					( Origin gFrontEnd )
				)
				( attribute "SEC" "1"
					( Origin gPackager )
				)
				( attribute "TOLERANCE" "20%"
					( Origin gFrontEnd )
				)
				( attribute "VALUE" "22.0UF"
					( Origin gFrontEnd )
				)
				( attribute "VER" "1"
					( Origin gFrontEnd )
				)
				( attribute "VOLTAGE" "4V"
					( Units "uVoltage" "V" 1.000000)
					( Origin gFrontEnd )
				)
				( attribute "XY" "(2250,-650)"
					( Origin gFrontEnd )
				)
				( attribute "CHIPS_PART_NAME" "CAP_A"
					( Origin gPackager )
				)
				( attribute "CDS_PART_NAME" "CAP_A_0603V-22.0UF,4V,20%,X6S,A"
					( Origin gPackager )
				)
				( objectStatus "C5G15" )
				( pin "a"
					( attribute "PN" "1"
						( Origin gPackager )
					)
					( objectStatus "C5G15.1" )
				)
				( pin "b"
					( attribute "PN" "2"
						( Origin gPackager )
					)
					( objectStatus "C5G15.2" )
				)
			)
			( gate "@baseboard_fab2_lib.baseboard_fab2(sch_1):page217_i221"
				( attribute "CDS_LIB" "dev_discrete"
					( Origin gPackager )
				)
				( attribute "CDS_LOCATION" "C5G16"
					( Origin gPackager )
				)
				( attribute "CDS_SEC" "1"
					( Origin gPackager )
				)
				( attribute "LOCATION" "C5G16"
					( Origin gFrontEnd )
				)
				( attribute "MATERIAL" "X6S"
					( Origin gFrontEnd )
				)
				( attribute "PACK_TYPE" "0603V"
					( Origin gFrontEnd )
				)
				( attribute "PART_NUMBER" "E15431-004"
					( Origin gFrontEnd )
				)
				( attribute "PHYS_PAGE" "217"
					( Origin gFrontEnd )
				)
				( attribute "ROOM" "PVDDQ_ABC"
					( Origin gFrontEnd )
				)
				( attribute "ROT" "0"
					( Origin gFrontEnd )
				)
				( attribute "SEC" "1"
					( Origin gPackager )
				)
				( attribute "TOLERANCE" "20%"
					( Origin gFrontEnd )
				)
				( attribute "VALUE" "22.0UF"
					( Origin gFrontEnd )
				)
				( attribute "VER" "1"
					( Origin gFrontEnd )
				)
				( attribute "VOLTAGE" "4V"
					( Units "uVoltage" "V" 1.000000)
					( Origin gFrontEnd )
				)
				( attribute "XY" "(1950,-650)"
					( Origin gFrontEnd )
				)
				( attribute "CHIPS_PART_NAME" "CAP_A"
					( Origin gPackager )
				)
				( attribute "CDS_PART_NAME" "CAP_A_0603V-22.0UF,4V,20%,X6S,A"
					( Origin gPackager )
				)
				( objectStatus "C5G16" )
				( pin "a"
					( attribute "PN" "1"
						( Origin gPackager )
					)
					( objectStatus "C5G16.1" )
				)
				( pin "b"
					( attribute "PN" "2"
						( Origin gPackager )
					)
					( objectStatus "C5G16.2" )
				)
			)
			( gate "@baseboard_fab2_lib.baseboard_fab2(sch_1):page217_i222"
				( attribute "CDS_LIB" "dev_discrete"
					( Origin gPackager )
				)
				( attribute "CDS_LOCATION" "C5T8"
					( Origin gPackager )
				)
				( attribute "CDS_SEC" "1"
					( Origin gPackager )
				)
				( attribute "LOCATION" "C5T8"
					( Origin gFrontEnd )
				)
				( attribute "MATERIAL" "X6S"
					( Origin gFrontEnd )
				)
				( attribute "PACK_TYPE" "0603V"
					( Origin gFrontEnd )
				)
				( attribute "PART_NUMBER" "E15431-004"
					( Origin gFrontEnd )
				)
				( attribute "PHYS_PAGE" "217"
					( Origin gFrontEnd )
				)
				( attribute "ROOM" "PVDDQ_ABC"
					( Origin gFrontEnd )
				)
				( attribute "ROT" "0"
					( Origin gFrontEnd )
				)
				( attribute "SEC" "1"
					( Origin gPackager )
				)
				( attribute "TOLERANCE" "20%"
					( Origin gFrontEnd )
				)
				( attribute "VALUE" "22.0UF"
					( Origin gFrontEnd )
				)
				( attribute "VER" "1"
					( Origin gFrontEnd )
				)
				( attribute "VOLTAGE" "4V"
					( Units "uVoltage" "V" 1.000000)
					( Origin gFrontEnd )
				)
				( attribute "XY" "(1675,50)"
					( Origin gFrontEnd )
				)
				( attribute "CHIPS_PART_NAME" "CAP_A"
					( Origin gPackager )
				)
				( attribute "CDS_PART_NAME" "CAP_A_0603V-22.0UF,4V,20%,X6S,A"
					( Origin gPackager )
				)
				( objectStatus "C5T8" )
				( pin "a"
					( attribute "PN" "1"
						( Origin gPackager )
					)
					( objectStatus "C5T8.1" )
				)
				( pin "b"
					( attribute "PN" "2"
						( Origin gPackager )
					)
					( objectStatus "C5T8.2" )
				)
			)
			( gate "@baseboard_fab2_lib.baseboard_fab2(sch_1):page217_i223"
				( attribute "CDS_LIB" "dev_discrete"
					( Origin gPackager )
				)
				( attribute "CDS_LOCATION" "C5G14"
					( Origin gPackager )
				)
				( attribute "CDS_SEC" "1"
					( Origin gPackager )
				)
				( attribute "LOCATION" "C5G14"
					( Origin gFrontEnd )
				)
				( attribute "MATERIAL" "X6S"
					( Origin gFrontEnd )
				)
				( attribute "PACK_TYPE" "0603V"
					( Origin gFrontEnd )
				)
				( attribute "PART_NUMBER" "E15431-004"
					( Origin gFrontEnd )
				)
				( attribute "PHYS_PAGE" "217"
					( Origin gFrontEnd )
				)
				( attribute "ROOM" "PVDDQ_ABC"
					( Origin gFrontEnd )
				)
				( attribute "ROT" "0"
					( Origin gFrontEnd )
				)
				( attribute "SEC" "1"
					( Origin gFrontEnd )
				)
				( attribute "SEC_TYPE" "0603V"
					( Origin gFrontEnd )
				)
				( attribute "TOLERANCE" "20%"
					( Origin gFrontEnd )
				)
				( attribute "VALUE" "22.0UF"
					( Origin gFrontEnd )
				)
				( attribute "VER" "1"
					( Origin gFrontEnd )
				)
				( attribute "VOLTAGE" "4V"
					( Units "uVoltage" "V" 1.000000)
					( Origin gFrontEnd )
				)
				( attribute "XY" "(1650,-650)"
					( Origin gFrontEnd )
				)
				( attribute "CHIPS_PART_NAME" "CAP_A"
					( Origin gPackager )
				)
				( attribute "CDS_PART_NAME" "CAP_A_0603V-22.0UF,4V,20%,X6S,A"
					( Origin gPackager )
				)
				( objectStatus "C5G14" )
				( pin "a"
					( attribute "PN" "1"
						( Origin gPackager )
					)
					( objectStatus "C5G14.1" )
				)
				( pin "b"
					( attribute "PN" "2"
						( Origin gPackager )
					)
					( objectStatus "C5G14.2" )
				)
			)
			( gate "@baseboard_fab2_lib.baseboard_fab2(sch_1):page217_i224"
				( attribute "CDS_LIB" "dev_discrete"
					( Origin gPackager )
				)
				( attribute "CDS_LOCATION" "C5T9"
					( Origin gPackager )
				)
				( attribute "CDS_SEC" "1"
					( Origin gPackager )
				)
				( attribute "LOCATION" "C5T9"
					( Origin gFrontEnd )
				)
				( attribute "MATERIAL" "X6S"
					( Origin gFrontEnd )
				)
				( attribute "PACK_TYPE" "0603V"
					( Origin gFrontEnd )
				)
				( attribute "PART_NUMBER" "E15431-004"
					( Origin gFrontEnd )
				)
				( attribute "PHYS_PAGE" "217"
					( Origin gFrontEnd )
				)
				( attribute "ROOM" "PVDDQ_ABC"
					( Origin gFrontEnd )
				)
				( attribute "ROT" "0"
					( Origin gFrontEnd )
				)
				( attribute "SEC" "1"
					( Origin gPackager )
				)
				( attribute "TOLERANCE" "20%"
					( Origin gFrontEnd )
				)
				( attribute "VALUE" "22.0UF"
					( Origin gFrontEnd )
				)
				( attribute "VER" "1"
					( Origin gFrontEnd )
				)
				( attribute "VOLTAGE" "4V"
					( Units "uVoltage" "V" 1.000000)
					( Origin gFrontEnd )
				)
				( attribute "XY" "(1400,50)"
					( Origin gFrontEnd )
				)
				( attribute "CHIPS_PART_NAME" "CAP_A"
					( Origin gPackager )
				)
				( attribute "CDS_PART_NAME" "CAP_A_0603V-22.0UF,4V,20%,X6S,A"
					( Origin gPackager )
				)
				( objectStatus "C5T9" )
				( pin "a"
					( attribute "PN" "1"
						( Origin gPackager )
					)
					( objectStatus "C5T9.1" )
				)
				( pin "b"
					( attribute "PN" "2"
						( Origin gPackager )
					)
					( objectStatus "C5T9.2" )
				)
			)
			( gate "@baseboard_fab2_lib.baseboard_fab2(sch_1):page217_i225"
				( attribute "CDS_LIB" "dev_discrete"
					( Origin gPackager )
				)
				( attribute "CDS_LOCATION" "C5T10"
					( Origin gPackager )
				)
				( attribute "CDS_SEC" "1"
					( Origin gPackager )
				)
				( attribute "LOCATION" "C5T10"
					( Origin gFrontEnd )
				)
				( attribute "MATERIAL" "X6S"
					( Origin gFrontEnd )
				)
				( attribute "PACK_TYPE" "0603V"
					( Origin gFrontEnd )
				)
				( attribute "PART_NUMBER" "E15431-004"
					( Origin gFrontEnd )
				)
				( attribute "PHYS_PAGE" "217"
					( Origin gFrontEnd )
				)
				( attribute "ROOM" "PVDDQ_ABC"
					( Origin gFrontEnd )
				)
				( attribute "ROT" "0"
					( Origin gFrontEnd )
				)
				( attribute "SEC" "1"
					( Origin gPackager )
				)
				( attribute "TOLERANCE" "20%"
					( Origin gFrontEnd )
				)
				( attribute "VALUE" "22.0UF"
					( Origin gFrontEnd )
				)
				( attribute "VER" "1"
					( Origin gFrontEnd )
				)
				( attribute "VOLTAGE" "4V"
					( Units "uVoltage" "V" 1.000000)
					( Origin gFrontEnd )
				)
				( attribute "XY" "(1125,50)"
					( Origin gFrontEnd )
				)
				( attribute "CHIPS_PART_NAME" "CAP_A"
					( Origin gPackager )
				)
				( attribute "CDS_PART_NAME" "CAP_A_0603V-22.0UF,4V,20%,X6S,A"
					( Origin gPackager )
				)
				( objectStatus "C5T10" )
				( pin "a"
					( attribute "PN" "1"
						( Origin gPackager )
					)
					( objectStatus "C5T10.1" )
				)
				( pin "b"
					( attribute "PN" "2"
						( Origin gPackager )
					)
					( objectStatus "C5T10.2" )
				)
			)
			( gate "@baseboard_fab2_lib.baseboard_fab2(sch_1):page217_i226"
				( attribute "CDS_LIB" "dev_discrete"
					( Origin gPackager )
				)
				( attribute "CDS_LOCATION" "C5G17"
					( Origin gPackager )
				)
				( attribute "CDS_SEC" "1"
					( Origin gPackager )
				)
				( attribute "LOCATION" "C5G17"
					( Origin gFrontEnd )
				)
				( attribute "MATERIAL" "X6S"
					( Origin gFrontEnd )
				)
				( attribute "PACK_TYPE" "0603V"
					( Origin gFrontEnd )
				)
				( attribute "PART_NUMBER" "E15431-004"
					( Origin gFrontEnd )
				)
				( attribute "PHYS_PAGE" "217"
					( Origin gFrontEnd )
				)
				( attribute "ROOM" "PVDDQ_ABC"
					( Origin gFrontEnd )
				)
				( attribute "ROT" "0"
					( Origin gFrontEnd )
				)
				( attribute "SEC" "1"
					( Origin gPackager )
				)
				( attribute "TOLERANCE" "20%"
					( Origin gFrontEnd )
				)
				( attribute "VALUE" "22.0UF"
					( Origin gFrontEnd )
				)
				( attribute "VER" "1"
					( Origin gFrontEnd )
				)
				( attribute "VOLTAGE" "4V"
					( Units "uVoltage" "V" 1.000000)
					( Origin gFrontEnd )
				)
				( attribute "XY" "(1375,-650)"
					( Origin gFrontEnd )
				)
				( attribute "CHIPS_PART_NAME" "CAP_A"
					( Origin gPackager )
				)
				( attribute "CDS_PART_NAME" "CAP_A_0603V-22.0UF,4V,20%,X6S,A"
					( Origin gPackager )
				)
				( objectStatus "C5G17" )
				( pin "a"
					( attribute "PN" "1"
						( Origin gPackager )
					)
					( objectStatus "C5G17.1" )
				)
				( pin "b"
					( attribute "PN" "2"
						( Origin gPackager )
					)
					( objectStatus "C5G17.2" )
				)
			)
			( gate "@baseboard_fab2_lib.baseboard_fab2(sch_1):page217_i227"
				( attribute "CDS_LIB" "dev_discrete"
					( Origin gPackager )
				)
				( attribute "CDS_LOCATION" "C5G18"
					( Origin gPackager )
				)
				( attribute "CDS_SEC" "1"
					( Origin gPackager )
				)
				( attribute "LOCATION" "C5G18"
					( Origin gFrontEnd )
				)
				( attribute "MATERIAL" "X6S"
					( Origin gFrontEnd )
				)
				( attribute "PACK_TYPE" "0603V"
					( Origin gFrontEnd )
				)
				( attribute "PART_NUMBER" "E15431-004"
					( Origin gFrontEnd )
				)
				( attribute "PHYS_PAGE" "217"
					( Origin gFrontEnd )
				)
				( attribute "ROOM" "PVDDQ_ABC"
					( Origin gFrontEnd )
				)
				( attribute "ROT" "0"
					( Origin gFrontEnd )
				)
				( attribute "SEC" "1"
					( Origin gPackager )
				)
				( attribute "TOLERANCE" "20%"
					( Origin gFrontEnd )
				)
				( attribute "VALUE" "22.0UF"
					( Origin gFrontEnd )
				)
				( attribute "VER" "1"
					( Origin gFrontEnd )
				)
				( attribute "VOLTAGE" "4V"
					( Units "uVoltage" "V" 1.000000)
					( Origin gFrontEnd )
				)
				( attribute "XY" "(1100,-650)"
					( Origin gFrontEnd )
				)
				( attribute "CHIPS_PART_NAME" "CAP_A"
					( Origin gPackager )
				)
				( attribute "CDS_PART_NAME" "CAP_A_0603V-22.0UF,4V,20%,X6S,A"
					( Origin gPackager )
				)
				( objectStatus "C5G18" )
				( pin "a"
					( attribute "PN" "1"
						( Origin gPackager )
					)
					( objectStatus "C5G18.1" )
				)
				( pin "b"
					( attribute "PN" "2"
						( Origin gPackager )
					)
					( objectStatus "C5G18.2" )
				)
			)
			( gate "@baseboard_fab2_lib.baseboard_fab2(sch_1):page217_i228"
				( attribute "CDS_LIB" "dev_discrete"
					( Origin gPackager )
				)
				( attribute "CDS_LOCATION" "C5T11"
					( Origin gPackager )
				)
				( attribute "CDS_SEC" "1"
					( Origin gPackager )
				)
				( attribute "LOCATION" "C5T11"
					( Origin gFrontEnd )
				)
				( attribute "MATERIAL" "X6S"
					( Origin gFrontEnd )
				)
				( attribute "PACK_TYPE" "0603V"
					( Origin gFrontEnd )
				)
				( attribute "PART_NUMBER" "E15431-004"
					( Origin gFrontEnd )
				)
				( attribute "PHYS_PAGE" "217"
					( Origin gFrontEnd )
				)
				( attribute "ROOM" "PVDDQ_ABC"
					( Origin gFrontEnd )
				)
				( attribute "ROT" "0"
					( Origin gFrontEnd )
				)
				( attribute "SEC" "1"
					( Origin gPackager )
				)
				( attribute "TOLERANCE" "20%"
					( Origin gFrontEnd )
				)
				( attribute "VALUE" "22.0UF"
					( Origin gFrontEnd )
				)
				( attribute "VER" "1"
					( Origin gFrontEnd )
				)
				( attribute "VOLTAGE" "4V"
					( Units "uVoltage" "V" 1.000000)
					( Origin gFrontEnd )
				)
				( attribute "XY" "(825,50)"
					( Origin gFrontEnd )
				)
				( attribute "CHIPS_PART_NAME" "CAP_A"
					( Origin gPackager )
				)
				( attribute "CDS_PART_NAME" "CAP_A_0603V-22.0UF,4V,20%,X6S,A"
					( Origin gPackager )
				)
				( objectStatus "C5T11" )
				( pin "a"
					( attribute "PN" "1"
						( Origin gPackager )
					)
					( objectStatus "C5T11.1" )
				)
				( pin "b"
					( attribute "PN" "2"
						( Origin gPackager )
					)
					( objectStatus "C5T11.2" )
				)
			)
			( gate "@baseboard_fab2_lib.baseboard_fab2(sch_1):page217_i229"
				( attribute "CDS_LIB" "dev_discrete"
					( Origin gPackager )
				)
				( attribute "CDS_LOCATION" "C5T12"
					( Origin gPackager )
				)
				( attribute "CDS_SEC" "1"
					( Origin gPackager )
				)
				( attribute "LOCATION" "C5T12"
					( Origin gFrontEnd )
				)
				( attribute "MATERIAL" "X6S"
					( Origin gFrontEnd )
				)
				( attribute "PACK_TYPE" "0603V"
					( Origin gFrontEnd )
				)
				( attribute "PART_NUMBER" "E15431-004"
					( Origin gFrontEnd )
				)
				( attribute "PHYS_PAGE" "217"
					( Origin gFrontEnd )
				)
				( attribute "ROOM" "PVDDQ_ABC"
					( Origin gFrontEnd )
				)
				( attribute "ROT" "0"
					( Origin gFrontEnd )
				)
				( attribute "SEC" "1"
					( Origin gPackager )
				)
				( attribute "TOLERANCE" "20%"
					( Origin gFrontEnd )
				)
				( attribute "VALUE" "22.0UF"
					( Origin gFrontEnd )
				)
				( attribute "VER" "1"
					( Origin gFrontEnd )
				)
				( attribute "VOLTAGE" "4V"
					( Units "uVoltage" "V" 1.000000)
					( Origin gFrontEnd )
				)
				( attribute "XY" "(525,50)"
					( Origin gFrontEnd )
				)
				( attribute "CHIPS_PART_NAME" "CAP_A"
					( Origin gPackager )
				)
				( attribute "CDS_PART_NAME" "CAP_A_0603V-22.0UF,4V,20%,X6S,A"
					( Origin gPackager )
				)
				( objectStatus "C5T12" )
				( pin "a"
					( attribute "PN" "1"
						( Origin gPackager )
					)
					( objectStatus "C5T12.1" )
				)
				( pin "b"
					( attribute "PN" "2"
						( Origin gPackager )
					)
					( objectStatus "C5T12.2" )
				)
			)
			( gate "@baseboard_fab2_lib.baseboard_fab2(sch_1):page217_i230"
				( attribute "CDS_LIB" "dev_discrete"
					( Origin gPackager )
				)
				( attribute "CDS_LOCATION" "C5G8"
					( Origin gPackager )
				)
				( attribute "CDS_SEC" "1"
					( Origin gPackager )
				)
				( attribute "LOCATION" "C5G8"
					( Origin gFrontEnd )
				)
				( attribute "MATERIAL" "X6S"
					( Origin gFrontEnd )
				)
				( attribute "PACK_TYPE" "0603V"
					( Origin gFrontEnd )
				)
				( attribute "PART_NUMBER" "E15431-004"
					( Origin gFrontEnd )
				)
				( attribute "PHYS_PAGE" "217"
					( Origin gFrontEnd )
				)
				( attribute "ROOM" "PVDDQ_ABC"
					( Origin gFrontEnd )
				)
				( attribute "ROT" "0"
					( Origin gFrontEnd )
				)
				( attribute "SEC" "1"
					( Origin gPackager )
				)
				( attribute "TOLERANCE" "20%"
					( Origin gFrontEnd )
				)
				( attribute "VALUE" "22.0UF"
					( Origin gFrontEnd )
				)
				( attribute "VER" "1"
					( Origin gFrontEnd )
				)
				( attribute "VOLTAGE" "4V"
					( Units "uVoltage" "V" 1.000000)
					( Origin gFrontEnd )
				)
				( attribute "XY" "(800,-650)"
					( Origin gFrontEnd )
				)
				( attribute "CHIPS_PART_NAME" "CAP_A"
					( Origin gPackager )
				)
				( attribute "CDS_PART_NAME" "CAP_A_0603V-22.0UF,4V,20%,X6S,A"
					( Origin gPackager )
				)
				( objectStatus "C5G8" )
				( pin "a"
					( attribute "PN" "1"
						( Origin gPackager )
					)
					( objectStatus "C5G8.1" )
				)
				( pin "b"
					( attribute "PN" "2"
						( Origin gPackager )
					)
					( objectStatus "C5G8.2" )
				)
			)
			( gate "@baseboard_fab2_lib.baseboard_fab2(sch_1):page217_i231"
				( attribute "CDS_LIB" "dev_discrete"
					( Origin gPackager )
				)
				( attribute "CDS_LOCATION" "C5G1"
					( Origin gPackager )
				)
				( attribute "CDS_SEC" "1"
					( Origin gPackager )
				)
				( attribute "LOCATION" "C5G1"
					( Origin gFrontEnd )
				)
				( attribute "MATERIAL" "X6S"
					( Origin gFrontEnd )
				)
				( attribute "PACK_TYPE" "0603V"
					( Origin gFrontEnd )
				)
				( attribute "PART_NUMBER" "E15431-004"
					( Origin gFrontEnd )
				)
				( attribute "PHYS_PAGE" "217"
					( Origin gFrontEnd )
				)
				( attribute "ROOM" "PVDDQ_ABC"
					( Origin gFrontEnd )
				)
				( attribute "ROT" "0"
					( Origin gFrontEnd )
				)
				( attribute "SEC" "1"
					( Origin gFrontEnd )
				)
				( attribute "SEC_TYPE" "0603V"
					( Origin gFrontEnd )
				)
				( attribute "TOLERANCE" "20%"
					( Origin gFrontEnd )
				)
				( attribute "VALUE" "22.0UF"
					( Origin gFrontEnd )
				)
				( attribute "VER" "1"
					( Origin gFrontEnd )
				)
				( attribute "VOLTAGE" "4V"
					( Units "uVoltage" "V" 1.000000)
					( Origin gFrontEnd )
				)
				( attribute "XY" "(500,-650)"
					( Origin gFrontEnd )
				)
				( attribute "CHIPS_PART_NAME" "CAP_A"
					( Origin gPackager )
				)
				( attribute "CDS_PART_NAME" "CAP_A_0603V-22.0UF,4V,20%,X6S,A"
					( Origin gPackager )
				)
				( objectStatus "C5G1" )
				( pin "a"
					( attribute "PN" "1"
						( Origin gPackager )
					)
					( objectStatus "C5G1.1" )
				)
				( pin "b"
					( attribute "PN" "2"
						( Origin gPackager )
					)
					( objectStatus "C5G1.2" )
				)
			)
			( gate "@baseboard_fab2_lib.baseboard_fab2(sch_1):page217_i232"
				( attribute "CDS_LIB" "dev_discrete"
					( Origin gPackager )
				)
				( attribute "CDS_LOCATION" "C5U9"
					( Origin gPackager )
				)
				( attribute "CDS_SEC" "1"
					( Origin gPackager )
				)
				( attribute "LOCATION" "C5U9"
					( Origin gFrontEnd )
				)
				( attribute "MATERIAL" "X6S"
					( Origin gFrontEnd )
				)
				( attribute "PACK_TYPE" "0603V"
					( Origin gFrontEnd )
				)
				( attribute "PART_NUMBER" "E15431-004"
					( Origin gFrontEnd )
				)
				( attribute "PHYS_PAGE" "217"
					( Origin gFrontEnd )
				)
				( attribute "ROOM" "PVDDQ_ABC"
					( Origin gFrontEnd )
				)
				( attribute "ROT" "0"
					( Origin gFrontEnd )
				)
				( attribute "SEC" "1"
					( Origin gPackager )
				)
				( attribute "TOLERANCE" "20%"
					( Origin gFrontEnd )
				)
				( attribute "VALUE" "22.0UF"
					( Origin gFrontEnd )
				)
				( attribute "VER" "1"
					( Origin gFrontEnd )
				)
				( attribute "VOLTAGE" "4V"
					( Units "uVoltage" "V" 1.000000)
					( Origin gFrontEnd )
				)
				( attribute "XY" "(200,50)"
					( Origin gFrontEnd )
				)
				( attribute "CHIPS_PART_NAME" "CAP_A"
					( Origin gPackager )
				)
				( attribute "CDS_PART_NAME" "CAP_A_0603V-22.0UF,4V,20%,X6S,A"
					( Origin gPackager )
				)
				( objectStatus "C5U9" )
				( pin "a"
					( attribute "PN" "1"
						( Origin gPackager )
					)
					( objectStatus "C5U9.1" )
				)
				( pin "b"
					( attribute "PN" "2"
						( Origin gPackager )
					)
					( objectStatus "C5U9.2" )
				)
			)
			( gate "@baseboard_fab2_lib.baseboard_fab2(sch_1):page217_i233"
				( attribute "CDS_LIB" "dev_discrete"
					( Origin gPackager )
				)
				( attribute "CDS_LOCATION" "C5U8"
					( Origin gPackager )
				)
				( attribute "CDS_SEC" "1"
					( Origin gPackager )
				)
				( attribute "LOCATION" "C5U8"
					( Origin gFrontEnd )
				)
				( attribute "MATERIAL" "X6S"
					( Origin gFrontEnd )
				)
				( attribute "PACK_TYPE" "0603V"
					( Origin gFrontEnd )
				)
				( attribute "PART_NUMBER" "E15431-004"
					( Origin gFrontEnd )
				)
				( attribute "PHYS_PAGE" "217"
					( Origin gFrontEnd )
				)
				( attribute "ROOM" "PVDDQ_ABC"
					( Origin gFrontEnd )
				)
				( attribute "ROT" "0"
					( Origin gFrontEnd )
				)
				( attribute "SEC" "1"
					( Origin gPackager )
				)
				( attribute "TOLERANCE" "20%"
					( Origin gFrontEnd )
				)
				( attribute "VALUE" "22.0UF"
					( Origin gFrontEnd )
				)
				( attribute "VER" "1"
					( Origin gFrontEnd )
				)
				( attribute "VOLTAGE" "4V"
					( Units "uVoltage" "V" 1.000000)
					( Origin gFrontEnd )
				)
				( attribute "XY" "(-75,50)"
					( Origin gFrontEnd )
				)
				( attribute "CHIPS_PART_NAME" "CAP_A"
					( Origin gPackager )
				)
				( attribute "CDS_PART_NAME" "CAP_A_0603V-22.0UF,4V,20%,X6S,A"
					( Origin gPackager )
				)
				( objectStatus "C5U8" )
				( pin "a"
					( attribute "PN" "1"
						( Origin gPackager )
					)
					( objectStatus "C5U8.1" )
				)
				( pin "b"
					( attribute "PN" "2"
						( Origin gPackager )
					)
					( objectStatus "C5U8.2" )
				)
			)
			( gate "@baseboard_fab2_lib.baseboard_fab2(sch_1):page217_i234"
				( attribute "CDS_LIB" "dev_discrete"
					( Origin gPackager )
				)
				( attribute "CDS_LOCATION" "C5G7"
					( Origin gPackager )
				)
				( attribute "CDS_SEC" "1"
					( Origin gPackager )
				)
				( attribute "LOCATION" "C5G7"
					( Origin gFrontEnd )
				)
				( attribute "MATERIAL" "X6S"
					( Origin gFrontEnd )
				)
				( attribute "PACK_TYPE" "0603V"
					( Origin gFrontEnd )
				)
				( attribute "PART_NUMBER" "E15431-004"
					( Origin gFrontEnd )
				)
				( attribute "PHYS_PAGE" "217"
					( Origin gFrontEnd )
				)
				( attribute "ROOM" "PVDDQ_ABC"
					( Origin gFrontEnd )
				)
				( attribute "ROT" "0"
					( Origin gFrontEnd )
				)
				( attribute "SEC" "1"
					( Origin gPackager )
				)
				( attribute "TOLERANCE" "20%"
					( Origin gFrontEnd )
				)
				( attribute "VALUE" "22.0UF"
					( Origin gFrontEnd )
				)
				( attribute "VER" "1"
					( Origin gFrontEnd )
				)
				( attribute "VOLTAGE" "4V"
					( Units "uVoltage" "V" 1.000000)
					( Origin gFrontEnd )
				)
				( attribute "XY" "(175,-650)"
					( Origin gFrontEnd )
				)
				( attribute "CHIPS_PART_NAME" "CAP_A"
					( Origin gPackager )
				)
				( attribute "CDS_PART_NAME" "CAP_A_0603V-22.0UF,4V,20%,X6S,A"
					( Origin gPackager )
				)
				( objectStatus "C5G7" )
				( pin "a"
					( attribute "PN" "1"
						( Origin gPackager )
					)
					( objectStatus "C5G7.1" )
				)
				( pin "b"
					( attribute "PN" "2"
						( Origin gPackager )
					)
					( objectStatus "C5G7.2" )
				)
			)
			( gate "@baseboard_fab2_lib.baseboard_fab2(sch_1):page217_i235"
				( attribute "CDS_LIB" "dev_discrete"
					( Origin gPackager )
				)
				( attribute "CDS_LOCATION" "C5G5"
					( Origin gPackager )
				)
				( attribute "CDS_SEC" "1"
					( Origin gPackager )
				)
				( attribute "LOCATION" "C5G5"
					( Origin gFrontEnd )
				)
				( attribute "MATERIAL" "X6S"
					( Origin gFrontEnd )
				)
				( attribute "PACK_TYPE" "0603V"
					( Origin gFrontEnd )
				)
				( attribute "PART_NUMBER" "E15431-004"
					( Origin gFrontEnd )
				)
				( attribute "PHYS_PAGE" "217"
					( Origin gFrontEnd )
				)
				( attribute "ROOM" "PVDDQ_ABC"
					( Origin gFrontEnd )
				)
				( attribute "ROT" "0"
					( Origin gFrontEnd )
				)
				( attribute "SEC" "1"
					( Origin gPackager )
				)
				( attribute "TOLERANCE" "20%"
					( Origin gFrontEnd )
				)
				( attribute "VALUE" "22.0UF"
					( Origin gFrontEnd )
				)
				( attribute "VER" "1"
					( Origin gFrontEnd )
				)
				( attribute "VOLTAGE" "4V"
					( Units "uVoltage" "V" 1.000000)
					( Origin gFrontEnd )
				)
				( attribute "XY" "(-100,-650)"
					( Origin gFrontEnd )
				)
				( attribute "CHIPS_PART_NAME" "CAP_A"
					( Origin gPackager )
				)
				( attribute "CDS_PART_NAME" "CAP_A_0603V-22.0UF,4V,20%,X6S,A"
					( Origin gPackager )
				)
				( objectStatus "C5G5" )
				( pin "a"
					( attribute "PN" "1"
						( Origin gPackager )
					)
					( objectStatus "C5G5.1" )
				)
				( pin "b"
					( attribute "PN" "2"
						( Origin gPackager )
					)
					( objectStatus "C5G5.2" )
				)
			)
			( gate "@baseboard_fab2_lib.baseboard_fab2(sch_1):page217_i236"
				( attribute "CDS_LIB" "dev_discrete"
					( Origin gPackager )
				)
				( attribute "CDS_LOCATION" "C5U7"
					( Origin gPackager )
				)
				( attribute "CDS_SEC" "1"
					( Origin gPackager )
				)
				( attribute "LOCATION" "C5U7"
					( Origin gFrontEnd )
				)
				( attribute "MATERIAL" "X6S"
					( Origin gFrontEnd )
				)
				( attribute "PACK_TYPE" "0603V"
					( Origin gFrontEnd )
				)
				( attribute "PART_NUMBER" "E15431-004"
					( Origin gFrontEnd )
				)
				( attribute "PHYS_PAGE" "217"
					( Origin gFrontEnd )
				)
				( attribute "ROOM" "PVDDQ_ABC"
					( Origin gFrontEnd )
				)
				( attribute "ROT" "0"
					( Origin gFrontEnd )
				)
				( attribute "SEC" "1"
					( Origin gPackager )
				)
				( attribute "TOLERANCE" "20%"
					( Origin gFrontEnd )
				)
				( attribute "VALUE" "22.0UF"
					( Origin gFrontEnd )
				)
				( attribute "VER" "1"
					( Origin gFrontEnd )
				)
				( attribute "VOLTAGE" "4V"
					( Units "uVoltage" "V" 1.000000)
					( Origin gFrontEnd )
				)
				( attribute "XY" "(-375,50)"
					( Origin gFrontEnd )
				)
				( attribute "CHIPS_PART_NAME" "CAP_A"
					( Origin gPackager )
				)
				( attribute "CDS_PART_NAME" "CAP_A_0603V-22.0UF,4V,20%,X6S,A"
					( Origin gPackager )
				)
				( objectStatus "C5U7" )
				( pin "a"
					( attribute "PN" "1"
						( Origin gPackager )
					)
					( objectStatus "C5U7.1" )
				)
				( pin "b"
					( attribute "PN" "2"
						( Origin gPackager )
					)
					( objectStatus "C5U7.2" )
				)
			)
			( gate "@baseboard_fab2_lib.baseboard_fab2(sch_1):page217_i237"
				( attribute "CDS_LIB" "dev_discrete"
					( Origin gPackager )
				)
				( attribute "CDS_LOCATION" "C5G6"
					( Origin gPackager )
				)
				( attribute "CDS_SEC" "1"
					( Origin gPackager )
				)
				( attribute "LOCATION" "C5G6"
					( Origin gFrontEnd )
				)
				( attribute "MATERIAL" "X6S"
					( Origin gFrontEnd )
				)
				( attribute "PACK_TYPE" "0603V"
					( Origin gFrontEnd )
				)
				( attribute "PART_NUMBER" "E15431-004"
					( Origin gFrontEnd )
				)
				( attribute "PHYS_PAGE" "217"
					( Origin gFrontEnd )
				)
				( attribute "ROOM" "PVDDQ_ABC"
					( Origin gFrontEnd )
				)
				( attribute "ROT" "0"
					( Origin gFrontEnd )
				)
				( attribute "SEC" "1"
					( Origin gPackager )
				)
				( attribute "TOLERANCE" "20%"
					( Origin gFrontEnd )
				)
				( attribute "VALUE" "22.0UF"
					( Origin gFrontEnd )
				)
				( attribute "VER" "1"
					( Origin gFrontEnd )
				)
				( attribute "VOLTAGE" "4V"
					( Units "uVoltage" "V" 1.000000)
					( Origin gFrontEnd )
				)
				( attribute "XY" "(-400,-650)"
					( Origin gFrontEnd )
				)
				( attribute "CHIPS_PART_NAME" "CAP_A"
					( Origin gPackager )
				)
				( attribute "CDS_PART_NAME" "CAP_A_0603V-22.0UF,4V,20%,X6S,A"
					( Origin gPackager )
				)
				( objectStatus "C5G6" )
				( pin "a"
					( attribute "PN" "1"
						( Origin gPackager )
					)
					( objectStatus "C5G6.1" )
				)
				( pin "b"
					( attribute "PN" "2"
						( Origin gPackager )
					)
					( objectStatus "C5G6.2" )
				)
			)
			( gate "@baseboard_fab2_lib.baseboard_fab2(sch_1):page217_i238"
				( attribute "CDS_LIB" "dev_discrete"
					( Origin gPackager )
				)
				( attribute "CDS_LOCATION" "C5U6"
					( Origin gPackager )
				)
				( attribute "CDS_SEC" "1"
					( Origin gPackager )
				)
				( attribute "LOCATION" "C5U6"
					( Origin gFrontEnd )
				)
				( attribute "MATERIAL" "X6S"
					( Origin gFrontEnd )
				)
				( attribute "PACK_TYPE" "0603V"
					( Origin gFrontEnd )
				)
				( attribute "PART_NUMBER" "E15431-004"
					( Origin gFrontEnd )
				)
				( attribute "PHYS_PAGE" "217"
					( Origin gFrontEnd )
				)
				( attribute "ROOM" "PVDDQ_ABC"
					( Origin gFrontEnd )
				)
				( attribute "ROT" "0"
					( Origin gFrontEnd )
				)
				( attribute "SEC" "1"
					( Origin gPackager )
				)
				( attribute "TOLERANCE" "20%"
					( Origin gFrontEnd )
				)
				( attribute "VALUE" "22.0UF"
					( Origin gFrontEnd )
				)
				( attribute "VER" "1"
					( Origin gFrontEnd )
				)
				( attribute "VOLTAGE" "4V"
					( Units "uVoltage" "V" 1.000000)
					( Origin gFrontEnd )
				)
				( attribute "XY" "(-675,50)"
					( Origin gFrontEnd )
				)
				( attribute "CHIPS_PART_NAME" "CAP_A"
					( Origin gPackager )
				)
				( attribute "CDS_PART_NAME" "CAP_A_0603V-22.0UF,4V,20%,X6S,A"
					( Origin gPackager )
				)
				( objectStatus "C5U6" )
				( pin "a"
					( attribute "PN" "1"
						( Origin gPackager )
					)
					( objectStatus "C5U6.1" )
				)
				( pin "b"
					( attribute "PN" "2"
						( Origin gPackager )
					)
					( objectStatus "C5U6.2" )
				)
			)
			( gate "@baseboard_fab2_lib.baseboard_fab2(sch_1):page217_i239"
				( attribute "CDS_LIB" "dev_discrete"
					( Origin gPackager )
				)
				( attribute "CDS_LOCATION" "C5U5"
					( Origin gPackager )
				)
				( attribute "CDS_SEC" "1"
					( Origin gPackager )
				)
				( attribute "LOCATION" "C5U5"
					( Origin gFrontEnd )
				)
				( attribute "MATERIAL" "X6S"
					( Origin gFrontEnd )
				)
				( attribute "PACK_TYPE" "0603V"
					( Origin gFrontEnd )
				)
				( attribute "PART_NUMBER" "E15431-004"
					( Origin gFrontEnd )
				)
				( attribute "PHYS_PAGE" "217"
					( Origin gFrontEnd )
				)
				( attribute "ROOM" "PVDDQ_ABC"
					( Origin gFrontEnd )
				)
				( attribute "ROT" "0"
					( Origin gFrontEnd )
				)
				( attribute "SEC" "1"
					( Origin gPackager )
				)
				( attribute "TOLERANCE" "20%"
					( Origin gFrontEnd )
				)
				( attribute "VALUE" "22.0UF"
					( Origin gFrontEnd )
				)
				( attribute "VER" "1"
					( Origin gFrontEnd )
				)
				( attribute "VOLTAGE" "4V"
					( Units "uVoltage" "V" 1.000000)
					( Origin gFrontEnd )
				)
				( attribute "XY" "(-950,50)"
					( Origin gFrontEnd )
				)
				( attribute "CHIPS_PART_NAME" "CAP_A"
					( Origin gPackager )
				)
				( attribute "CDS_PART_NAME" "CAP_A_0603V-22.0UF,4V,20%,X6S,A"
					( Origin gPackager )
				)
				( objectStatus "C5U5" )
				( pin "a"
					( attribute "PN" "1"
						( Origin gPackager )
					)
					( objectStatus "C5U5.1" )
				)
				( pin "b"
					( attribute "PN" "2"
						( Origin gPackager )
					)
					( objectStatus "C5U5.2" )
				)
			)
			( gate "@baseboard_fab2_lib.baseboard_fab2(sch_1):page217_i240"
				( attribute "CDS_LIB" "dev_discrete"
					( Origin gPackager )
				)
				( attribute "CDS_LOCATION" "C5G13"
					( Origin gPackager )
				)
				( attribute "CDS_SEC" "1"
					( Origin gPackager )
				)
				( attribute "LOCATION" "C5G13"
					( Origin gFrontEnd )
				)
				( attribute "MATERIAL" "X6S"
					( Origin gFrontEnd )
				)
				( attribute "PACK_TYPE" "0603V"
					( Origin gFrontEnd )
				)
				( attribute "PART_NUMBER" "E15431-004"
					( Origin gFrontEnd )
				)
				( attribute "PHYS_PAGE" "217"
					( Origin gFrontEnd )
				)
				( attribute "ROOM" "PVDDQ_ABC"
					( Origin gFrontEnd )
				)
				( attribute "ROT" "0"
					( Origin gFrontEnd )
				)
				( attribute "SEC" "1"
					( Origin gFrontEnd )
				)
				( attribute "SEC_TYPE" "0603V"
					( Origin gFrontEnd )
				)
				( attribute "TOLERANCE" "20%"
					( Origin gFrontEnd )
				)
				( attribute "VALUE" "22.0UF"
					( Origin gFrontEnd )
				)
				( attribute "VER" "1"
					( Origin gFrontEnd )
				)
				( attribute "VOLTAGE" "4V"
					( Units "uVoltage" "V" 1.000000)
					( Origin gFrontEnd )
				)
				( attribute "XY" "(-700,-650)"
					( Origin gFrontEnd )
				)
				( attribute "CHIPS_PART_NAME" "CAP_A"
					( Origin gPackager )
				)
				( attribute "CDS_PART_NAME" "CAP_A_0603V-22.0UF,4V,20%,X6S,A"
					( Origin gPackager )
				)
				( objectStatus "C5G13" )
				( pin "a"
					( attribute "PN" "1"
						( Origin gPackager )
					)
					( objectStatus "C5G13.1" )
				)
				( pin "b"
					( attribute "PN" "2"
						( Origin gPackager )
					)
					( objectStatus "C5G13.2" )
				)
			)
			( gate "@baseboard_fab2_lib.baseboard_fab2(sch_1):page217_i241"
				( attribute "CDS_LIB" "dev_discrete"
					( Origin gPackager )
				)
				( attribute "CDS_LOCATION" "C5G4"
					( Origin gPackager )
				)
				( attribute "CDS_SEC" "1"
					( Origin gPackager )
				)
				( attribute "LOCATION" "C5G4"
					( Origin gFrontEnd )
				)
				( attribute "MATERIAL" "X6S"
					( Origin gFrontEnd )
				)
				( attribute "PACK_TYPE" "0603V"
					( Origin gFrontEnd )
				)
				( attribute "PART_NUMBER" "E15431-004"
					( Origin gFrontEnd )
				)
				( attribute "PHYS_PAGE" "217"
					( Origin gFrontEnd )
				)
				( attribute "ROOM" "PVDDQ_ABC"
					( Origin gFrontEnd )
				)
				( attribute "ROT" "0"
					( Origin gFrontEnd )
				)
				( attribute "SEC" "1"
					( Origin gPackager )
				)
				( attribute "TOLERANCE" "20%"
					( Origin gFrontEnd )
				)
				( attribute "VALUE" "22.0UF"
					( Origin gFrontEnd )
				)
				( attribute "VER" "1"
					( Origin gFrontEnd )
				)
				( attribute "VOLTAGE" "4V"
					( Units "uVoltage" "V" 1.000000)
					( Origin gFrontEnd )
				)
				( attribute "XY" "(-975,-650)"
					( Origin gFrontEnd )
				)
				( attribute "CHIPS_PART_NAME" "CAP_A"
					( Origin gPackager )
				)
				( attribute "CDS_PART_NAME" "CAP_A_0603V-22.0UF,4V,20%,X6S,A"
					( Origin gPackager )
				)
				( objectStatus "C5G4" )
				( pin "a"
					( attribute "PN" "1"
						( Origin gPackager )
					)
					( objectStatus "C5G4.1" )
				)
				( pin "b"
					( attribute "PN" "2"
						( Origin gPackager )
					)
					( objectStatus "C5G4.2" )
				)
			)
			( gate "@baseboard_fab2_lib.baseboard_fab2(sch_1):page217_i243"
				( attribute "CDS_LIB" "dev_discrete"
					( Origin gPackager )
				)
				( attribute "CDS_LOCATION" "C5U4"
					( Origin gPackager )
				)
				( attribute "CDS_SEC" "1"
					( Origin gPackager )
				)
				( attribute "LOCATION" "C5U4"
					( Origin gFrontEnd )
				)
				( attribute "MATERIAL" "X6S"
					( Origin gFrontEnd )
				)
				( attribute "PACK_TYPE" "0603V"
					( Origin gFrontEnd )
				)
				( attribute "PART_NUMBER" "E15431-004"
					( Origin gFrontEnd )
				)
				( attribute "PHYS_PAGE" "217"
					( Origin gFrontEnd )
				)
				( attribute "ROOM" "PVDDQ_ABC"
					( Origin gFrontEnd )
				)
				( attribute "ROT" "0"
					( Origin gFrontEnd )
				)
				( attribute "SEC" "1"
					( Origin gPackager )
				)
				( attribute "TOLERANCE" "20%"
					( Origin gFrontEnd )
				)
				( attribute "VALUE" "22.0UF"
					( Origin gFrontEnd )
				)
				( attribute "VER" "1"
					( Origin gFrontEnd )
				)
				( attribute "VOLTAGE" "4V"
					( Units "uVoltage" "V" 1.000000)
					( Origin gFrontEnd )
				)
				( attribute "XY" "(-1225,50)"
					( Origin gFrontEnd )
				)
				( attribute "CHIPS_PART_NAME" "CAP_A"
					( Origin gPackager )
				)
				( attribute "CDS_PART_NAME" "CAP_A_0603V-22.0UF,4V,20%,X6S,A"
					( Origin gPackager )
				)
				( objectStatus "C5U4" )
				( pin "a"
					( attribute "PN" "1"
						( Origin gPackager )
					)
					( objectStatus "C5U4.1" )
				)
				( pin "b"
					( attribute "PN" "2"
						( Origin gPackager )
					)
					( objectStatus "C5U4.2" )
				)
			)
			( gate "@baseboard_fab2_lib.baseboard_fab2(sch_1):page217_i244"
				( attribute "CDS_LIB" "dev_discrete"
					( Origin gPackager )
				)
				( attribute "CDS_LOCATION" "C5U3"
					( Origin gPackager )
				)
				( attribute "CDS_SEC" "1"
					( Origin gPackager )
				)
				( attribute "LOCATION" "C5U3"
					( Origin gFrontEnd )
				)
				( attribute "MATERIAL" "X6S"
					( Origin gFrontEnd )
				)
				( attribute "PACK_TYPE" "0603V"
					( Origin gFrontEnd )
				)
				( attribute "PART_NUMBER" "E15431-004"
					( Origin gFrontEnd )
				)
				( attribute "PHYS_PAGE" "217"
					( Origin gFrontEnd )
				)
				( attribute "ROOM" "PVDDQ_ABC"
					( Origin gFrontEnd )
				)
				( attribute "ROT" "0"
					( Origin gFrontEnd )
				)
				( attribute "SEC" "1"
					( Origin gPackager )
				)
				( attribute "TOLERANCE" "20%"
					( Origin gFrontEnd )
				)
				( attribute "VALUE" "22.0UF"
					( Origin gFrontEnd )
				)
				( attribute "VER" "1"
					( Origin gFrontEnd )
				)
				( attribute "VOLTAGE" "4V"
					( Units "uVoltage" "V" 1.000000)
					( Origin gFrontEnd )
				)
				( attribute "XY" "(-1525,50)"
					( Origin gFrontEnd )
				)
				( attribute "CHIPS_PART_NAME" "CAP_A"
					( Origin gPackager )
				)
				( attribute "CDS_PART_NAME" "CAP_A_0603V-22.0UF,4V,20%,X6S,A"
					( Origin gPackager )
				)
				( objectStatus "C5U3" )
				( pin "a"
					( attribute "PN" "1"
						( Origin gPackager )
					)
					( objectStatus "C5U3.1" )
				)
				( pin "b"
					( attribute "PN" "2"
						( Origin gPackager )
					)
					( objectStatus "C5U3.2" )
				)
			)
			( gate "@baseboard_fab2_lib.baseboard_fab2(sch_1):page217_i245"
				( attribute "CDS_LIB" "dev_discrete"
					( Origin gPackager )
				)
				( attribute "CDS_LOCATION" "C5G2"
					( Origin gPackager )
				)
				( attribute "CDS_SEC" "1"
					( Origin gPackager )
				)
				( attribute "LOCATION" "C5G2"
					( Origin gFrontEnd )
				)
				( attribute "MATERIAL" "X6S"
					( Origin gFrontEnd )
				)
				( attribute "PACK_TYPE" "0603V"
					( Origin gFrontEnd )
				)
				( attribute "PART_NUMBER" "E15431-004"
					( Origin gFrontEnd )
				)
				( attribute "PHYS_PAGE" "217"
					( Origin gFrontEnd )
				)
				( attribute "ROOM" "PVDDQ_ABC"
					( Origin gFrontEnd )
				)
				( attribute "ROT" "0"
					( Origin gFrontEnd )
				)
				( attribute "SEC" "1"
					( Origin gPackager )
				)
				( attribute "TOLERANCE" "20%"
					( Origin gFrontEnd )
				)
				( attribute "VALUE" "22.0UF"
					( Origin gFrontEnd )
				)
				( attribute "VER" "1"
					( Origin gFrontEnd )
				)
				( attribute "VOLTAGE" "4V"
					( Units "uVoltage" "V" 1.000000)
					( Origin gFrontEnd )
				)
				( attribute "XY" "(-1250,-650)"
					( Origin gFrontEnd )
				)
				( attribute "CHIPS_PART_NAME" "CAP_A"
					( Origin gPackager )
				)
				( attribute "CDS_PART_NAME" "CAP_A_0603V-22.0UF,4V,20%,X6S,A"
					( Origin gPackager )
				)
				( objectStatus "C5G2" )
				( pin "a"
					( attribute "PN" "1"
						( Origin gPackager )
					)
					( objectStatus "C5G2.1" )
				)
				( pin "b"
					( attribute "PN" "2"
						( Origin gPackager )
					)
					( objectStatus "C5G2.2" )
				)
			)
			( gate "@baseboard_fab2_lib.baseboard_fab2(sch_1):page217_i246"
				( attribute "CDS_LIB" "dev_discrete"
					( Origin gPackager )
				)
				( attribute "CDS_LOCATION" "C5G12"
					( Origin gPackager )
				)
				( attribute "CDS_SEC" "1"
					( Origin gPackager )
				)
				( attribute "LOCATION" "C5G12"
					( Origin gFrontEnd )
				)
				( attribute "MATERIAL" "X6S"
					( Origin gFrontEnd )
				)
				( attribute "PACK_TYPE" "0603V"
					( Origin gFrontEnd )
				)
				( attribute "PART_NUMBER" "E15431-004"
					( Origin gFrontEnd )
				)
				( attribute "PHYS_PAGE" "217"
					( Origin gFrontEnd )
				)
				( attribute "ROOM" "PVDDQ_ABC"
					( Origin gFrontEnd )
				)
				( attribute "ROT" "0"
					( Origin gFrontEnd )
				)
				( attribute "SEC" "1"
					( Origin gPackager )
				)
				( attribute "TOLERANCE" "20%"
					( Origin gFrontEnd )
				)
				( attribute "VALUE" "22.0UF"
					( Origin gFrontEnd )
				)
				( attribute "VER" "1"
					( Origin gFrontEnd )
				)
				( attribute "VOLTAGE" "4V"
					( Units "uVoltage" "V" 1.000000)
					( Origin gFrontEnd )
				)
				( attribute "XY" "(-1550,-650)"
					( Origin gFrontEnd )
				)
				( attribute "CHIPS_PART_NAME" "CAP_A"
					( Origin gPackager )
				)
				( attribute "CDS_PART_NAME" "CAP_A_0603V-22.0UF,4V,20%,X6S,A"
					( Origin gPackager )
				)
				( objectStatus "C5G12" )
				( pin "a"
					( attribute "PN" "1"
						( Origin gPackager )
					)
					( objectStatus "C5G12.1" )
				)
				( pin "b"
					( attribute "PN" "2"
						( Origin gPackager )
					)
					( objectStatus "C5G12.2" )
				)
			)
			( gate "@baseboard_fab2_lib.baseboard_fab2(sch_1):page217_i247"
				( attribute "CDS_LIB" "dev_discrete"
					( Origin gPackager )
				)
				( attribute "CDS_LOCATION" "C5U2"
					( Origin gPackager )
				)
				( attribute "CDS_SEC" "1"
					( Origin gPackager )
				)
				( attribute "LOCATION" "C5U2"
					( Origin gFrontEnd )
				)
				( attribute "MATERIAL" "X6S"
					( Origin gFrontEnd )
				)
				( attribute "PACK_TYPE" "0603V"
					( Origin gFrontEnd )
				)
				( attribute "PART_NUMBER" "E15431-004"
					( Origin gFrontEnd )
				)
				( attribute "PHYS_PAGE" "217"
					( Origin gFrontEnd )
				)
				( attribute "ROOM" "PVDDQ_ABC"
					( Origin gFrontEnd )
				)
				( attribute "ROT" "0"
					( Origin gFrontEnd )
				)
				( attribute "SEC" "1"
					( Origin gPackager )
				)
				( attribute "TOLERANCE" "20%"
					( Origin gFrontEnd )
				)
				( attribute "VALUE" "22.0UF"
					( Origin gFrontEnd )
				)
				( attribute "VER" "1"
					( Origin gFrontEnd )
				)
				( attribute "VOLTAGE" "4V"
					( Units "uVoltage" "V" 1.000000)
					( Origin gFrontEnd )
				)
				( attribute "XY" "(-1825,50)"
					( Origin gFrontEnd )
				)
				( attribute "CHIPS_PART_NAME" "CAP_A"
					( Origin gPackager )
				)
				( attribute "CDS_PART_NAME" "CAP_A_0603V-22.0UF,4V,20%,X6S,A"
					( Origin gPackager )
				)
				( objectStatus "C5U2" )
				( pin "a"
					( attribute "PN" "1"
						( Origin gPackager )
					)
					( objectStatus "C5U2.1" )
				)
				( pin "b"
					( attribute "PN" "2"
						( Origin gPackager )
					)
					( objectStatus "C5U2.2" )
				)
			)
			( gate "@baseboard_fab2_lib.baseboard_fab2(sch_1):page217_i250"
				( attribute "CDS_LIB" "dev_discrete"
					( Origin gPackager )
				)
				( attribute "CDS_LOCATION" "C5G11"
					( Origin gPackager )
				)
				( attribute "CDS_SEC" "1"
					( Origin gPackager )
				)
				( attribute "LOCATION" "C5G11"
					( Origin gFrontEnd )
				)
				( attribute "MATERIAL" "X6S"
					( Origin gFrontEnd )
				)
				( attribute "PACK_TYPE" "0603V"
					( Origin gFrontEnd )
				)
				( attribute "PART_NUMBER" "E15431-004"
					( Origin gFrontEnd )
				)
				( attribute "PHYS_PAGE" "217"
					( Origin gFrontEnd )
				)
				( attribute "ROOM" "PVDDQ_ABC"
					( Origin gFrontEnd )
				)
				( attribute "ROT" "0"
					( Origin gFrontEnd )
				)
				( attribute "SEC" "1"
					( Origin gFrontEnd )
				)
				( attribute "SEC_TYPE" "0603V"
					( Origin gFrontEnd )
				)
				( attribute "TOLERANCE" "20%"
					( Origin gFrontEnd )
				)
				( attribute "VALUE" "22.0UF"
					( Origin gFrontEnd )
				)
				( attribute "VER" "1"
					( Origin gFrontEnd )
				)
				( attribute "VOLTAGE" "4V"
					( Units "uVoltage" "V" 1.000000)
					( Origin gFrontEnd )
				)
				( attribute "XY" "(-1850,-650)"
					( Origin gFrontEnd )
				)
				( attribute "CHIPS_PART_NAME" "CAP_A"
					( Origin gPackager )
				)
				( attribute "CDS_PART_NAME" "CAP_A_0603V-22.0UF,4V,20%,X6S,A"
					( Origin gPackager )
				)
				( objectStatus "C5G11" )
				( pin "a"
					( attribute "PN" "1"
						( Origin gPackager )
					)
					( objectStatus "C5G11.1" )
				)
				( pin "b"
					( attribute "PN" "2"
						( Origin gPackager )
					)
					( objectStatus "C5G11.2" )
				)
			)
			( gate "@baseboard_fab2_lib.baseboard_fab2(sch_1):page217_i259"
				( attribute "CDS_LIB" "mstr_misc"
					( Origin gPackager )
				)
				( attribute "CDS_LOCATION" "SH4U1"
					( Origin gPackager )
				)
				( attribute "CDS_SEC" "1"
					( Origin gPackager )
				)
				( attribute "LOCATION" "SH4U1"
					( Origin gFrontEnd )
				)
				( attribute "MATERIAL" "EMPTY"
					( Origin gFrontEnd )
				)
				( attribute "PACK_TYPE" "SH0201"
					( Origin gFrontEnd )
				)
				( attribute "PART_NUMBER" "N_A"
					( Origin gFrontEnd )
				)
				( attribute "PHYS_PAGE" "217"
					( Origin gFrontEnd )
				)
				( attribute "PIN_SHORT" "A:B"
					( Origin gFrontEnd )
				)
				( attribute "ROT" "0"
					( Origin gFrontEnd )
				)
				( attribute "SEC" "1"
					( Origin gFrontEnd )
				)
				( attribute "SEC_TYPE" "SH0201"
					( Origin gFrontEnd )
				)
				( attribute "VER" "1"
					( Origin gFrontEnd )
				)
				( attribute "XY" "(125,1500)"
					( Origin gFrontEnd )
				)
				( attribute "CHIPS_PART_NAME" "SHUNT"
					( Origin gPackager )
				)
				( attribute "CDS_PART_NAME" "SHUNT_SH0201-EMPTY,N_A"
					( Origin gPackager )
				)
				( objectStatus "SH4U1" )
				( pin "a"
					( attribute "PN" "1"
						( Origin gPackager )
					)
					( objectStatus "SH4U1.1" )
				)
				( pin "b"
					( attribute "PN" "2"
						( Origin gPackager )
					)
					( objectStatus "SH4U1.2" )
				)
			)
			( gate "@baseboard_fab2_lib.baseboard_fab2(sch_1):page217_i260"
				( attribute "CDS_LIB" "mstr_misc"
					( Origin gPackager )
				)
				( attribute "CDS_LOCATION" "SH4U2"
					( Origin gPackager )
				)
				( attribute "CDS_SEC" "1"
					( Origin gPackager )
				)
				( attribute "LOCATION" "SH4U2"
					( Origin gFrontEnd )
				)
				( attribute "MATERIAL" "EMPTY"
					( Origin gFrontEnd )
				)
				( attribute "PACK_TYPE" "SH0201"
					( Origin gFrontEnd )
				)
				( attribute "PART_NUMBER" "N_A"
					( Origin gFrontEnd )
				)
				( attribute "PHYS_PAGE" "217"
					( Origin gFrontEnd )
				)
				( attribute "PIN_SHORT" "A:B"
					( Origin gFrontEnd )
				)
				( attribute "ROT" "0"
					( Origin gFrontEnd )
				)
				( attribute "SEC" "1"
					( Origin gFrontEnd )
				)
				( attribute "SEC_TYPE" "SH0201"
					( Origin gFrontEnd )
				)
				( attribute "VER" "1"
					( Origin gFrontEnd )
				)
				( attribute "XY" "(150,1950)"
					( Origin gFrontEnd )
				)
				( attribute "CHIPS_PART_NAME" "SHUNT"
					( Origin gPackager )
				)
				( attribute "CDS_PART_NAME" "SHUNT_SH0201-EMPTY,N_A"
					( Origin gPackager )
				)
				( objectStatus "SH4U2" )
				( pin "a"
					( attribute "PN" "1"
						( Origin gPackager )
					)
					( objectStatus "SH4U2.1" )
				)
				( pin "b"
					( attribute "PN" "2"
						( Origin gPackager )
					)
					( objectStatus "SH4U2.2" )
				)
			)
			( gate "@baseboard_fab2_lib.baseboard_fab2(sch_1):page218_i7"
				( attribute "CDS_LIB" "mstr_discrete"
					( Origin gPackager )
				)
				( attribute "CDS_LOCATION" "R3L11"
					( Origin gPackager )
				)
				( attribute "CDS_SEC" "1"
					( Origin gPackager )
				)
				( attribute "LOCATION" "R3L11"
					( Origin gFrontEnd )
				)
				( attribute "MATERIAL" "EMPTY"
					( Origin gFrontEnd )
				)
				( attribute "PACK_TYPE" "0402"
					( Origin gFrontEnd )
				)
				( attribute "PART_NUMBER" "G21796-017"
					( Origin gFrontEnd )
				)
				( attribute "PHYS_PAGE" "218"
					( Origin gFrontEnd )
				)
				( attribute "ROOM" "VDDQ_DEF_PWR_VR"
					( Origin gFrontEnd )
				)
				( attribute "ROT" "0"
					( Origin gFrontEnd )
				)
				( attribute "SEC" "1"
					( Origin gFrontEnd )
				)
				( attribute "SEC_TYPE" "0402"
					( Origin gFrontEnd )
				)
				( attribute "TOLERANCE" "1%"
					( Origin gFrontEnd )
				)
				( attribute "VALUE" "100.0"
					( Origin gFrontEnd )
				)
				( attribute "VER" "2"
					( Origin gFrontEnd )
				)
				( attribute "WATTAGE" "1/16W"
					( Origin gFrontEnd )
				)
				( attribute "XY" "(3700,2725)"
					( Origin gFrontEnd )
				)
				( attribute "CHIPS_PART_NAME" "RES"
					( Origin gPackager )
				)
				( attribute "CDS_PART_NAME" "RES_0402-100.0,1%,1/16W,EMPTY,A"
					( Origin gPackager )
				)
				( objectStatus "R3L11" )
				( pin "a"
					( attribute "PN" "1"
						( Origin gPackager )
					)
					( objectStatus "R3L11.1" )
				)
				( pin "b"
					( attribute "PN" "2"
						( Origin gPackager )
					)
					( objectStatus "R3L11.2" )
				)
			)
			( gate "@baseboard_fab2_lib.baseboard_fab2(sch_1):page218_i11"
				( attribute "CDS_LIB" "mstr_discrete"
					( Origin gPackager )
				)
				( attribute "CDS_LOCATION" "R3M3"
					( Origin gPackager )
				)
				( attribute "CDS_SEC" "1"
					( Origin gPackager )
				)
				( attribute "LOCATION" "R3M3"
					( Origin gFrontEnd )
				)
				( attribute "MATERIAL" "CHIP"
					( Origin gFrontEnd )
				)
				( attribute "PACK_TYPE" "0402"
					( Origin gFrontEnd )
				)
				( attribute "PART_NUMBER" "G21796-250"
					( Origin gFrontEnd )
				)
				( attribute "PHYS_PAGE" "218"
					( Origin gFrontEnd )
				)
				( attribute "ROOM" "VDDQ_DEF_PWR_VR"
					( Origin gFrontEnd )
				)
				( attribute "ROT" "0"
					( Origin gFrontEnd )
				)
				( attribute "SEC" "1"
					( Origin gPackager )
				)
				( attribute "TOLERANCE" "1.0%"
					( Origin gFrontEnd )
				)
				( attribute "VALUE" "22.1"
					( Origin gFrontEnd )
				)
				( attribute "VER" "1"
					( Origin gFrontEnd )
				)
				( attribute "WATTAGE" "1/16W"
					( Origin gFrontEnd )
				)
				( attribute "XY" "(3100,2350)"
					( Origin gFrontEnd )
				)
				( attribute "CHIPS_PART_NAME" "RES"
					( Origin gPackager )
				)
				( attribute "CDS_PART_NAME" "RES_0402-22.1,1.0%,1/16W,CHIP,A"
					( Origin gPackager )
				)
				( objectStatus "R3M3" )
				( pin "a"
					( attribute "PN" "1"
						( Origin gPackager )
					)
					( objectStatus "R3M3.1" )
				)
				( pin "b"
					( attribute "PN" "2"
						( Origin gPackager )
					)
					( objectStatus "R3M3.2" )
				)
			)
			( gate "@baseboard_fab2_lib.baseboard_fab2(sch_1):page218_i12"
				( attribute "CDS_LIB" "mstr_discrete"
					( Origin gPackager )
				)
				( attribute "CDS_LOCATION" "R7B1"
					( Origin gPackager )
				)
				( attribute "CDS_SEC" "1"
					( Origin gPackager )
				)
				( attribute "LOCATION" "R7B1"
					( Origin gFrontEnd )
				)
				( attribute "MATERIAL" "CHIP"
					( Origin gFrontEnd )
				)
				( attribute "PACK_TYPE" "0402"
					( Origin gFrontEnd )
				)
				( attribute "PART_NUMBER" "G21796-074"
					( Origin gFrontEnd )
				)
				( attribute "PHYS_PAGE" "218"
					( Origin gFrontEnd )
				)
				( attribute "ROT" "0"
					( Origin gFrontEnd )
				)
				( attribute "SEC" "1"
					( Origin gPackager )
				)
				( attribute "TOLERANCE" "1%"
					( Origin gFrontEnd )
				)
				( attribute "VALUE" "33.2"
					( Origin gFrontEnd )
				)
				( attribute "VER" "1"
					( Origin gFrontEnd )
				)
				( attribute "WATTAGE" "1/16W"
					( Origin gFrontEnd )
				)
				( attribute "XY" "(3075,2250)"
					( Origin gFrontEnd )
				)
				( attribute "CHIPS_PART_NAME" "RES"
					( Origin gPackager )
				)
				( attribute "CDS_PART_NAME" "RES_0402-33.2,1%,1/16W,CHIP,G2A"
					( Origin gPackager )
				)
				( objectStatus "R7B1" )
				( pin "a"
					( attribute "PN" "1"
						( Origin gPackager )
					)
					( objectStatus "R7B1.1" )
				)
				( pin "b"
					( attribute "PN" "2"
						( Origin gPackager )
					)
					( objectStatus "R7B1.2" )
				)
			)
			( gate "@baseboard_fab2_lib.baseboard_fab2(sch_1):page218_i14"
				( attribute "CDS_LIB" "mstr_discrete"
					( Origin gPackager )
				)
				( attribute "CDS_LOCATION" "R7A9"
					( Origin gPackager )
				)
				( attribute "CDS_SEC" "1"
					( Origin gPackager )
				)
				( attribute "LOCATION" "R7A9"
					( Origin gFrontEnd )
				)
				( attribute "MATERIAL" "EMPTY"
					( Origin gFrontEnd )
				)
				( attribute "PACK_TYPE" "0402"
					( Origin gFrontEnd )
				)
				( attribute "PART_NUMBER" "G21796-311"
					( Origin gFrontEnd )
				)
				( attribute "PHYS_PAGE" "218"
					( Origin gFrontEnd )
				)
				( attribute "ROOM" "VDDQ_DEF_PWR_VR"
					( Origin gFrontEnd )
				)
				( attribute "ROT" "0"
					( Origin gFrontEnd )
				)
				( attribute "SEC" "1"
					( Origin gFrontEnd )
				)
				( attribute "SEC_TYPE" "0402"
					( Origin gFrontEnd )
				)
				( attribute "TOLERANCE" "1.0%"
					( Origin gFrontEnd )
				)
				( attribute "VALUE" "2.26K"
					( Origin gFrontEnd )
				)
				( attribute "VER" "2"
					( Origin gFrontEnd )
				)
				( attribute "WATTAGE" "1/16W"
					( Origin gFrontEnd )
				)
				( attribute "XY" "(2650,2725)"
					( Origin gFrontEnd )
				)
				( attribute "CHIPS_PART_NAME" "RES"
					( Origin gPackager )
				)
				( attribute "CDS_PART_NAME" "RES_0402-2.26K,1.0%,1/16W,EMPTA"
					( Origin gPackager )
				)
				( objectStatus "R7A9" )
				( pin "a"
					( attribute "PN" "1"
						( Origin gPackager )
					)
					( objectStatus "R7A9.1" )
				)
				( pin "b"
					( attribute "PN" "2"
						( Origin gPackager )
					)
					( objectStatus "R7A9.2" )
				)
			)
			( gate "@baseboard_fab2_lib.baseboard_fab2(sch_1):page218_i15"
				( attribute "CDS_LIB" "mstr_discrete"
					( Origin gPackager )
				)
				( attribute "CDS_LOCATION" "R7A11"
					( Origin gPackager )
				)
				( attribute "CDS_SEC" "1"
					( Origin gPackager )
				)
				( attribute "LOCATION" "R7A11"
					( Origin gFrontEnd )
				)
				( attribute "MATERIAL" "CHIP"
					( Origin gFrontEnd )
				)
				( attribute "PACK_TYPE" "0402"
					( Origin gFrontEnd )
				)
				( attribute "PART_NUMBER" "G21497-005"
					( Origin gFrontEnd )
				)
				( attribute "PHYS_PAGE" "218"
					( Origin gFrontEnd )
				)
				( attribute "ROOM" "VDDQ_DEF_PWR_VR"
					( Origin gFrontEnd )
				)
				( attribute "ROT" "0"
					( Origin gFrontEnd )
				)
				( attribute "SEC" "1"
					( Origin gFrontEnd )
				)
				( attribute "SEC_TYPE" "0402"
					( Origin gFrontEnd )
				)
				( attribute "TOLERANCE" "5%"
					( Origin gFrontEnd )
				)
				( attribute "VALUE" "0.0"
					( Origin gFrontEnd )
				)
				( attribute "VER" "1"
					( Origin gFrontEnd )
				)
				( attribute "WATTAGE" "1/16W"
					( Origin gFrontEnd )
				)
				( attribute "XY" "(2525,2200)"
					( Origin gFrontEnd )
				)
				( attribute "CHIPS_PART_NAME" "RES"
					( Origin gPackager )
				)
				( attribute "CDS_PART_NAME" "RES_0402-0.0,5%,1/16W,CHIP,G21A"
					( Origin gPackager )
				)
				( objectStatus "R7A11" )
				( pin "a"
					( attribute "PN" "1"
						( Origin gPackager )
					)
					( objectStatus "R7A11.1" )
				)
				( pin "b"
					( attribute "PN" "2"
						( Origin gPackager )
					)
					( objectStatus "R7A11.2" )
				)
			)
			( gate "@baseboard_fab2_lib.baseboard_fab2(sch_1):page218_i16"
				( attribute "CDS_LIB" "mstr_discrete"
					( Origin gPackager )
				)
				( attribute "CDS_LOCATION" "R7B5"
					( Origin gPackager )
				)
				( attribute "CDS_SEC" "1"
					( Origin gPackager )
				)
				( attribute "LOCATION" "R7B5"
					( Origin gFrontEnd )
				)
				( attribute "MATERIAL" "CHIP"
					( Origin gFrontEnd )
				)
				( attribute "PACK_TYPE" "0402"
					( Origin gFrontEnd )
				)
				( attribute "PART_NUMBER" "G21796-026"
					( Origin gFrontEnd )
				)
				( attribute "PHYS_PAGE" "218"
					( Origin gFrontEnd )
				)
				( attribute "ROOM" "VDDQ_DEF_PWR_VR"
					( Origin gFrontEnd )
				)
				( attribute "ROT" "0"
					( Origin gFrontEnd )
				)
				( attribute "SEC" "1"
					( Origin gFrontEnd )
				)
				( attribute "SEC_TYPE" "0402"
					( Origin gFrontEnd )
				)
				( attribute "TOLERANCE" "1%"
					( Origin gFrontEnd )
				)
				( attribute "VALUE" "1.00K"
					( Origin gFrontEnd )
				)
				( attribute "VER" "2"
					( Origin gFrontEnd )
				)
				( attribute "WATTAGE" "1/16W"
					( Origin gFrontEnd )
				)
				( attribute "XY" "(2350,2900)"
					( Origin gFrontEnd )
				)
				( attribute "CHIPS_PART_NAME" "RES"
					( Origin gPackager )
				)
				( attribute "CDS_PART_NAME" "RES_0402-1.00K,1%,1/16W,CHIP,GA"
					( Origin gPackager )
				)
				( objectStatus "R7B5" )
				( pin "a"
					( attribute "PN" "1"
						( Origin gPackager )
					)
					( objectStatus "R7B5.1" )
				)
				( pin "b"
					( attribute "PN" "2"
						( Origin gPackager )
					)
					( objectStatus "R7B5.2" )
				)
			)
			( gate "@baseboard_fab2_lib.baseboard_fab2(sch_1):page218_i17"
				( attribute "CDS_LIB" "mstr_discrete"
					( Origin gPackager )
				)
				( attribute "CDS_LOCATION" "R7B4"
					( Origin gPackager )
				)
				( attribute "CDS_SEC" "1"
					( Origin gPackager )
				)
				( attribute "LOCATION" "R7B4"
					( Origin gFrontEnd )
				)
				( attribute "MATERIAL" "CHIP"
					( Origin gFrontEnd )
				)
				( attribute "PACK_TYPE" "0402"
					( Origin gFrontEnd )
				)
				( attribute "PART_NUMBER" "G21796-026"
					( Origin gFrontEnd )
				)
				( attribute "PHYS_PAGE" "218"
					( Origin gFrontEnd )
				)
				( attribute "ROOM" "VDDQ_DEF_PWR_VR"
					( Origin gFrontEnd )
				)
				( attribute "ROT" "0"
					( Origin gFrontEnd )
				)
				( attribute "SEC" "1"
					( Origin gFrontEnd )
				)
				( attribute "SEC_TYPE" "0402"
					( Origin gFrontEnd )
				)
				( attribute "TOLERANCE" "1%"
					( Origin gFrontEnd )
				)
				( attribute "VALUE" "1.00K"
					( Origin gFrontEnd )
				)
				( attribute "VER" "2"
					( Origin gFrontEnd )
				)
				( attribute "WATTAGE" "1/16W"
					( Origin gFrontEnd )
				)
				( attribute "XY" "(2150,2900)"
					( Origin gFrontEnd )
				)
				( attribute "CHIPS_PART_NAME" "RES"
					( Origin gPackager )
				)
				( attribute "CDS_PART_NAME" "RES_0402-1.00K,1%,1/16W,CHIP,GA"
					( Origin gPackager )
				)
				( objectStatus "R7B4" )
				( pin "a"
					( attribute "PN" "1"
						( Origin gPackager )
					)
					( objectStatus "R7B4.1" )
				)
				( pin "b"
					( attribute "PN" "2"
						( Origin gPackager )
					)
					( objectStatus "R7B4.2" )
				)
			)
			( gate "@baseboard_fab2_lib.baseboard_fab2(sch_1):page218_i21"
				( attribute "CDS_LIB" "mstr_discrete"
					( Origin gPackager )
				)
				( attribute "CDS_LOCATION" "R7B3"
					( Origin gPackager )
				)
				( attribute "CDS_SEC" "1"
					( Origin gPackager )
				)
				( attribute "LOCATION" "R7B3"
					( Origin gFrontEnd )
				)
				( attribute "MATERIAL" "CHIP"
					( Origin gFrontEnd )
				)
				( attribute "PACK_TYPE" "0402"
					( Origin gFrontEnd )
				)
				( attribute "PART_NUMBER" "G21796-173"
					( Origin gFrontEnd )
				)
				( attribute "PHYS_PAGE" "218"
					( Origin gFrontEnd )
				)
				( attribute "ROOM" "VDDQ_DEF_PWR_VR"
					( Origin gFrontEnd )
				)
				( attribute "ROT" "0"
					( Origin gFrontEnd )
				)
				( attribute "SEC" "1"
					( Origin gPackager )
				)
				( attribute "TOLERANCE" "1%"
					( Origin gFrontEnd )
				)
				( attribute "VALUE" "20.0"
					( Origin gFrontEnd )
				)
				( attribute "VER" "1"
					( Origin gFrontEnd )
				)
				( attribute "WATTAGE" "1/16W"
					( Origin gFrontEnd )
				)
				( attribute "XY" "(3000,1850)"
					( Origin gFrontEnd )
				)
				( attribute "CHIPS_PART_NAME" "RES"
					( Origin gPackager )
				)
				( attribute "CDS_PART_NAME" "RES_0402-20.0,1%,1/16W,CHIP,G2A"
					( Origin gPackager )
				)
				( objectStatus "R7B3" )
				( pin "a"
					( attribute "PN" "1"
						( Origin gPackager )
					)
					( objectStatus "R7B3.1" )
				)
				( pin "b"
					( attribute "PN" "2"
						( Origin gPackager )
					)
					( objectStatus "R7B3.2" )
				)
			)
			( gate "@baseboard_fab2_lib.baseboard_fab2(sch_1):page218_i22"
				( attribute "CDS_LIB" "dev_discrete"
					( Origin gPackager )
				)
				( attribute "CDS_LOCATION" "C7B1"
					( Origin gPackager )
				)
				( attribute "CDS_SEC" "1"
					( Origin gPackager )
				)
				( attribute "LOCATION" "C7B1"
					( Origin gFrontEnd )
				)
				( attribute "MATERIAL" "X6S"
					( Origin gFrontEnd )
				)
				( attribute "PACK_TYPE" "0402V"
					( Origin gFrontEnd )
				)
				( attribute "PART_NUMBER" "D97712-004"
					( Origin gFrontEnd )
				)
				( attribute "PHYS_PAGE" "218"
					( Origin gFrontEnd )
				)
				( attribute "ROOM" "VDDQ_DEF_PWR_VR"
					( Origin gFrontEnd )
				)
				( attribute "ROT" "0"
					( Origin gFrontEnd )
				)
				( attribute "SEC" "1"
					( Origin gFrontEnd )
				)
				( attribute "SEC_TYPE" "0402V"
					( Origin gFrontEnd )
				)
				( attribute "TOLERANCE" "10%"
					( Origin gFrontEnd )
				)
				( attribute "VALUE" "1.0UF"
					( Origin gFrontEnd )
				)
				( attribute "VER" "1"
					( Origin gFrontEnd )
				)
				( attribute "VOLTAGE" "6.3V"
					( Units "uVoltage" "V" 1.000000)
					( Origin gFrontEnd )
				)
				( attribute "XY" "(3525,0)"
					( Origin gFrontEnd )
				)
				( attribute "CHIPS_PART_NAME" "CAP_A"
					( Origin gPackager )
				)
				( attribute "CDS_PART_NAME" "CAP_A_0402V-1.0UF,6.3V,10%,X6SA"
					( Origin gPackager )
				)
				( objectStatus "C7B1" )
				( pin "a"
					( attribute "PN" "1"
						( Origin gPackager )
					)
					( objectStatus "C7B1.1" )
				)
				( pin "b"
					( attribute "PN" "2"
						( Origin gPackager )
					)
					( objectStatus "C7B1.2" )
				)
			)
			( gate "@baseboard_fab2_lib.baseboard_fab2(sch_1):page218_i23"
				( attribute "CDS_LIB" "dev_discrete"
					( Origin gPackager )
				)
				( attribute "CDS_LOCATION" "C7B2"
					( Origin gPackager )
				)
				( attribute "CDS_SEC" "1"
					( Origin gPackager )
				)
				( attribute "LOCATION" "C7B2"
					( Origin gFrontEnd )
				)
				( attribute "MATERIAL" "X7R"
					( Origin gFrontEnd )
				)
				( attribute "PACK_TYPE" "0402V"
					( Origin gFrontEnd )
				)
				( attribute "PART_NUMBER" "A36096-030"
					( Origin gFrontEnd )
				)
				( attribute "PHYS_PAGE" "218"
					( Origin gFrontEnd )
				)
				( attribute "ROOM" "VDDQ_DEF_PWR_VR"
					( Origin gFrontEnd )
				)
				( attribute "ROT" "0"
					( Origin gFrontEnd )
				)
				( attribute "SEC" "1"
					( Origin gFrontEnd )
				)
				( attribute "SEC_TYPE" "0402V"
					( Origin gFrontEnd )
				)
				( attribute "TOLERANCE" "10%"
					( Origin gFrontEnd )
				)
				( attribute "VALUE" "0.1UF"
					( Origin gFrontEnd )
				)
				( attribute "VER" "1"
					( Origin gFrontEnd )
				)
				( attribute "VOLTAGE" "16V"
					( Units "uVoltage" "V" 1.000000)
					( Origin gFrontEnd )
				)
				( attribute "XY" "(3125,0)"
					( Origin gFrontEnd )
				)
				( attribute "CHIPS_PART_NAME" "CAP_A"
					( Origin gPackager )
				)
				( attribute "CDS_PART_NAME" "CAP_A_0402V-0.1UF,16V,10%,X7R,A"
					( Origin gPackager )
				)
				( objectStatus "C7B2" )
				( pin "a"
					( attribute "PN" "1"
						( Origin gPackager )
					)
					( objectStatus "C7B2.1" )
				)
				( pin "b"
					( attribute "PN" "2"
						( Origin gPackager )
					)
					( objectStatus "C7B2.2" )
				)
			)
			( gate "@baseboard_fab2_lib.baseboard_fab2(sch_1):page218_i24"
				( attribute "CDS_LIB" "mstr_discrete"
					( Origin gPackager )
				)
				( attribute "CDS_LOCATION" "R7B2"
					( Origin gPackager )
				)
				( attribute "CDS_SEC" "1"
					( Origin gPackager )
				)
				( attribute "LOCATION" "R7B2"
					( Origin gFrontEnd )
				)
				( attribute "MATERIAL" "CHIP"
					( Origin gFrontEnd )
				)
				( attribute "PACK_TYPE" "0402"
					( Origin gFrontEnd )
				)
				( attribute "PART_NUMBER" "G21796-173"
					( Origin gFrontEnd )
				)
				( attribute "PHYS_PAGE" "218"
					( Origin gFrontEnd )
				)
				( attribute "ROOM" "VDDQ_DEF_PWR_VR"
					( Origin gFrontEnd )
				)
				( attribute "ROT" "0"
					( Origin gFrontEnd )
				)
				( attribute "SEC" "1"
					( Origin gPackager )
				)
				( attribute "TOLERANCE" "1%"
					( Origin gFrontEnd )
				)
				( attribute "VALUE" "20.0"
					( Origin gFrontEnd )
				)
				( attribute "VER" "1"
					( Origin gFrontEnd )
				)
				( attribute "WATTAGE" "1/16W"
					( Origin gFrontEnd )
				)
				( attribute "XY" "(2675,1800)"
					( Origin gFrontEnd )
				)
				( attribute "CHIPS_PART_NAME" "RES"
					( Origin gPackager )
				)
				( attribute "CDS_PART_NAME" "RES_0402-20.0,1%,1/16W,CHIP,G2A"
					( Origin gPackager )
				)
				( objectStatus "R7B2" )
				( pin "a"
					( attribute "PN" "1"
						( Origin gPackager )
					)
					( objectStatus "R7B2.1" )
				)
				( pin "b"
					( attribute "PN" "2"
						( Origin gPackager )
					)
					( objectStatus "R7B2.2" )
				)
			)
			( gate "@baseboard_fab2_lib.baseboard_fab2(sch_1):page218_i25"
				( attribute "CDS_LIB" "mstr_discrete"
					( Origin gPackager )
				)
				( attribute "CDS_LOCATION" "R7A12"
					( Origin gPackager )
				)
				( attribute "CDS_SEC" "1"
					( Origin gPackager )
				)
				( attribute "LOCATION" "R7A12"
					( Origin gFrontEnd )
				)
				( attribute "MATERIAL" "CHIP"
					( Origin gFrontEnd )
				)
				( attribute "PACK_TYPE" "0402"
					( Origin gFrontEnd )
				)
				( attribute "PART_NUMBER" "G21497-005"
					( Origin gFrontEnd )
				)
				( attribute "PHYS_PAGE" "218"
					( Origin gFrontEnd )
				)
				( attribute "ROOM" "VDDQ_DEF_PWR_VR"
					( Origin gFrontEnd )
				)
				( attribute "ROT" "0"
					( Origin gFrontEnd )
				)
				( attribute "SEC" "1"
					( Origin gFrontEnd )
				)
				( attribute "SEC_TYPE" "0402"
					( Origin gFrontEnd )
				)
				( attribute "TOLERANCE" "5%"
					( Origin gFrontEnd )
				)
				( attribute "VALUE" "0.0"
					( Origin gFrontEnd )
				)
				( attribute "VER" "1"
					( Origin gFrontEnd )
				)
				( attribute "WATTAGE" "1/16W"
					( Origin gFrontEnd )
				)
				( attribute "XY" "(2675,1500)"
					( Origin gFrontEnd )
				)
				( attribute "CHIPS_PART_NAME" "RES"
					( Origin gPackager )
				)
				( attribute "CDS_PART_NAME" "RES_0402-0.0,5%,1/16W,CHIP,G21A"
					( Origin gPackager )
				)
				( objectStatus "R7A12" )
				( pin "a"
					( attribute "PN" "1"
						( Origin gPackager )
					)
					( objectStatus "R7A12.1" )
				)
				( pin "b"
					( attribute "PN" "2"
						( Origin gPackager )
					)
					( objectStatus "R7A12.2" )
				)
			)
			( gate "@baseboard_fab2_lib.baseboard_fab2(sch_1):page218_i26"
				( attribute "CDS_LIB" "mstr_discrete"
					( Origin gPackager )
				)
				( attribute "CDS_LOCATION" "C7B3"
					( Origin gPackager )
				)
				( attribute "CDS_SEC" "1"
					( Origin gPackager )
				)
				( attribute "LOCATION" "C7B3"
					( Origin gFrontEnd )
				)
				( attribute "MATERIAL" "X7R"
					( Origin gFrontEnd )
				)
				( attribute "PACK_TYPE" "0402LF"
					( Origin gFrontEnd )
				)
				( attribute "PART_NUMBER" "A36096-046"
					( Origin gFrontEnd )
				)
				( attribute "PHYS_PAGE" "218"
					( Origin gFrontEnd )
				)
				( attribute "ROOM" "VDDQ_DEF_PWR_VR"
					( Origin gFrontEnd )
				)
				( attribute "ROT" "0"
					( Origin gFrontEnd )
				)
				( attribute "SEC" "1"
					( Origin gFrontEnd )
				)
				( attribute "SEC_TYPE" "0402LF"
					( Origin gFrontEnd )
				)
				( attribute "TOLERANCE" "10%"
					( Origin gFrontEnd )
				)
				( attribute "VALUE" "1000PF"
					( Origin gFrontEnd )
				)
				( attribute "VER" "1"
					( Origin gFrontEnd )
				)
				( attribute "VOLTAGE" "50V"
					( Units "uVoltage" "V" 1.000000)
					( Origin gFrontEnd )
				)
				( attribute "XY" "(2800,1025)"
					( Origin gFrontEnd )
				)
				( attribute "CHIPS_PART_NAME" "CAP"
					( Origin gPackager )
				)
				( attribute "CDS_PART_NAME" "CAP_0402LF-1000PF,50V,10%,X7R,A"
					( Origin gPackager )
				)
				( objectStatus "C7B3" )
				( pin "a"
					( attribute "PN" "1"
						( Origin gPackager )
					)
					( objectStatus "C7B3.1" )
				)
				( pin "b"
					( attribute "PN" "2"
						( Origin gPackager )
					)
					( objectStatus "C7B3.2" )
				)
			)
			( gate "@baseboard_fab2_lib.baseboard_fab2(sch_1):page218_i29"
				( attribute "CDS_LIB" "dev_discrete"
					( Origin gPackager )
				)
				( attribute "CDS_LOCATION" "C7A37"
					( Origin gPackager )
				)
				( attribute "CDS_SEC" "1"
					( Origin gPackager )
				)
				( attribute "LOCATION" "C7A37"
					( Origin gFrontEnd )
				)
				( attribute "MATERIAL" "X6S"
					( Origin gFrontEnd )
				)
				( attribute "PACK_TYPE" "0402V"
					( Origin gFrontEnd )
				)
				( attribute "PART_NUMBER" "D97712-004"
					( Origin gFrontEnd )
				)
				( attribute "PHYS_PAGE" "218"
					( Origin gFrontEnd )
				)
				( attribute "ROOM" "VDDQ_DEF_PWR_VR"
					( Origin gFrontEnd )
				)
				( attribute "ROT" "0"
					( Origin gFrontEnd )
				)
				( attribute "SEC" "1"
					( Origin gFrontEnd )
				)
				( attribute "SEC_TYPE" "0402V"
					( Origin gFrontEnd )
				)
				( attribute "TOLERANCE" "10%"
					( Origin gFrontEnd )
				)
				( attribute "VALUE" "1.0UF"
					( Origin gFrontEnd )
				)
				( attribute "VER" "1"
					( Origin gFrontEnd )
				)
				( attribute "VOLTAGE" "6.3V"
					( Units "uVoltage" "V" 1.000000)
					( Origin gFrontEnd )
				)
				( attribute "XY" "(1425,2900)"
					( Origin gFrontEnd )
				)
				( attribute "CHIPS_PART_NAME" "CAP_A"
					( Origin gPackager )
				)
				( attribute "CDS_PART_NAME" "CAP_A_0402V-1.0UF,6.3V,10%,X6SA"
					( Origin gPackager )
				)
				( objectStatus "C7A37" )
				( pin "a"
					( attribute "PN" "1"
						( Origin gPackager )
					)
					( objectStatus "C7A37.1" )
				)
				( pin "b"
					( attribute "PN" "2"
						( Origin gPackager )
					)
					( objectStatus "C7A37.2" )
				)
			)
			( gate "@baseboard_fab2_lib.baseboard_fab2(sch_1):page218_i31"
				( attribute "CDS_LIB" "dev_discrete"
					( Origin gPackager )
				)
				( attribute "CDS_LOCATION" "C7A38"
					( Origin gPackager )
				)
				( attribute "CDS_SEC" "1"
					( Origin gPackager )
				)
				( attribute "LOCATION" "C7A38"
					( Origin gFrontEnd )
				)
				( attribute "MATERIAL" "X7R"
					( Origin gFrontEnd )
				)
				( attribute "PACK_TYPE" "0402V"
					( Origin gFrontEnd )
				)
				( attribute "PART_NUMBER" "A36096-030"
					( Origin gFrontEnd )
				)
				( attribute "PHYS_PAGE" "218"
					( Origin gFrontEnd )
				)
				( attribute "ROOM" "VDDQ_DEF_PWR_VR"
					( Origin gFrontEnd )
				)
				( attribute "ROT" "0"
					( Origin gFrontEnd )
				)
				( attribute "SEC" "1"
					( Origin gFrontEnd )
				)
				( attribute "SEC_TYPE" "0402V"
					( Origin gFrontEnd )
				)
				( attribute "TOLERANCE" "10%"
					( Origin gFrontEnd )
				)
				( attribute "VALUE" "0.1UF"
					( Origin gFrontEnd )
				)
				( attribute "VER" "1"
					( Origin gFrontEnd )
				)
				( attribute "VOLTAGE" "16V"
					( Units "uVoltage" "V" 1.000000)
					( Origin gFrontEnd )
				)
				( attribute "XY" "(1025,2900)"
					( Origin gFrontEnd )
				)
				( attribute "CHIPS_PART_NAME" "CAP_A"
					( Origin gPackager )
				)
				( attribute "CDS_PART_NAME" "CAP_A_0402V-0.1UF,16V,10%,X7R,A"
					( Origin gPackager )
				)
				( objectStatus "C7A38" )
				( pin "a"
					( attribute "PN" "1"
						( Origin gPackager )
					)
					( objectStatus "C7A38.1" )
				)
				( pin "b"
					( attribute "PN" "2"
						( Origin gPackager )
					)
					( objectStatus "C7A38.2" )
				)
			)
			( gate "@baseboard_fab2_lib.baseboard_fab2(sch_1):page218_i34"
				( attribute "CDS_LIB" "mstr_discrete"
					( Origin gPackager )
				)
				( attribute "CDS_LOCATION" "R3M1"
					( Origin gPackager )
				)
				( attribute "CDS_SEC" "1"
					( Origin gPackager )
				)
				( attribute "LOCATION" "R3M1"
					( Origin gFrontEnd )
				)
				( attribute "MATERIAL" "CHIP"
					( Origin gFrontEnd )
				)
				( attribute "PACK_TYPE" "0402"
					( Origin gFrontEnd )
				)
				( attribute "PART_NUMBER" "G21497-005"
					( Origin gFrontEnd )
				)
				( attribute "PHYS_PAGE" "218"
					( Origin gFrontEnd )
				)
				( attribute "ROOM" "VDDQ_DEF_PWR_VR"
					( Origin gFrontEnd )
				)
				( attribute "ROT" "0"
					( Origin gFrontEnd )
				)
				( attribute "SEC" "1"
					( Origin gFrontEnd )
				)
				( attribute "SEC_TYPE" "0402"
					( Origin gFrontEnd )
				)
				( attribute "TOLERANCE" "5%"
					( Origin gFrontEnd )
				)
				( attribute "VALUE" "0.0"
					( Origin gFrontEnd )
				)
				( attribute "VER" "2"
					( Origin gFrontEnd )
				)
				( attribute "WATTAGE" "1/16W"
					( Origin gFrontEnd )
				)
				( attribute "XY" "(725,3250)"
					( Origin gFrontEnd )
				)
				( attribute "CHIPS_PART_NAME" "RES"
					( Origin gPackager )
				)
				( attribute "CDS_PART_NAME" "RES_0402-0.0,5%,1/16W,CHIP,G21A"
					( Origin gPackager )
				)
				( objectStatus "R3M1" )
				( pin "a"
					( attribute "PN" "1"
						( Origin gPackager )
					)
					( objectStatus "R3M1.1" )
				)
				( pin "b"
					( attribute "PN" "2"
						( Origin gPackager )
					)
					( objectStatus "R3M1.2" )
				)
			)
			( gate "@baseboard_fab2_lib.baseboard_fab2(sch_1):page218_i35"
				( attribute "BOM_COST" "SM_CONTROLLER"
					( Origin gFrontEnd )
				)
				( attribute "CDS_LIB" "mstr_discrete"
					( Origin gPackager )
				)
				( attribute "CDS_LOCATION" "R3M5"
					( Origin gPackager )
				)
				( attribute "CDS_SEC" "1"
					( Origin gPackager )
				)
				( attribute "LOCATION" "R3M5"
					( Origin gFrontEnd )
				)
				( attribute "MATERIAL" "EMPTY"
					( Origin gFrontEnd )
				)
				( attribute "PACK_TYPE" "0402"
					( Origin gFrontEnd )
				)
				( attribute "PART_NUMBER" "G21796-010"
					( Origin gFrontEnd )
				)
				( attribute "PHYS_PAGE" "218"
					( Origin gFrontEnd )
				)
				( attribute "ROOM" "VDDQ_DEF_PWR_VR"
					( Origin gFrontEnd )
				)
				( attribute "ROT" "0"
					( Origin gFrontEnd )
				)
				( attribute "SEC" "1"
					( Origin gPackager )
				)
				( attribute "TOLERANCE" "1%"
					( Origin gFrontEnd )
				)
				( attribute "VALUE" "100.0K"
					( Origin gFrontEnd )
				)
				( attribute "VER" "2"
					( Origin gFrontEnd )
				)
				( attribute "WATTAGE" "1/16W"
					( Origin gFrontEnd )
				)
				( attribute "XY" "(25,3325)"
					( Origin gFrontEnd )
				)
				( attribute "CHIPS_PART_NAME" "RES"
					( Origin gPackager )
				)
				( attribute "CDS_PART_NAME" "RES_0402-100.0K,1%,1/16W,EMPTYA"
					( Origin gPackager )
				)
				( objectStatus "R3M5" )
				( pin "a"
					( attribute "PN" "1"
						( Origin gPackager )
					)
					( objectStatus "R3M5.1" )
				)
				( pin "b"
					( attribute "PN" "2"
						( Origin gPackager )
					)
					( objectStatus "R3M5.2" )
				)
			)
			( gate "@baseboard_fab2_lib.baseboard_fab2(sch_1):page218_i37"
				( attribute "CDS_LIB" "mstr_discrete"
					( Origin gPackager )
				)
				( attribute "CDS_LOCATION" "R7A8"
					( Origin gPackager )
				)
				( attribute "CDS_SEC" "1"
					( Origin gPackager )
				)
				( attribute "LOCATION" "R7A8"
					( Origin gFrontEnd )
				)
				( attribute "MATERIAL" "CHIP"
					( Origin gFrontEnd )
				)
				( attribute "PACK_TYPE" "0402"
					( Origin gFrontEnd )
				)
				( attribute "PART_NUMBER" "G21796-078"
					( Origin gFrontEnd )
				)
				( attribute "PHYS_PAGE" "218"
					( Origin gFrontEnd )
				)
				( attribute "ROOM" "VDDQ_DEF_PWR_VR"
					( Origin gFrontEnd )
				)
				( attribute "ROT" "0"
					( Origin gFrontEnd )
				)
				( attribute "SEC" "1"
					( Origin gPackager )
				)
				( attribute "TOLERANCE" "1%"
					( Origin gFrontEnd )
				)
				( attribute "VALUE" "8.06K"
					( Origin gFrontEnd )
				)
				( attribute "VER" "2"
					( Origin gFrontEnd )
				)
				( attribute "WATTAGE" "1/16W"
					( Origin gFrontEnd )
				)
				( attribute "XY" "(400,100)"
					( Origin gFrontEnd )
				)
				( attribute "CHIPS_PART_NAME" "RES"
					( Origin gPackager )
				)
				( attribute "CDS_PART_NAME" "RES_0402-8.06K,1%,1/16W,CHIP,GA"
					( Origin gPackager )
				)
				( objectStatus "R7A8" )
				( pin "a"
					( attribute "PN" "1"
						( Origin gPackager )
					)
					( objectStatus "R7A8.1" )
				)
				( pin "b"
					( attribute "PN" "2"
						( Origin gPackager )
					)
					( objectStatus "R7A8.2" )
				)
			)
			( gate "@baseboard_fab2_lib.baseboard_fab2(sch_1):page218_i39"
				( attribute "CDS_LIB" "mstr_discrete"
					( Origin gPackager )
				)
				( attribute "CDS_LOCATION" "C7A29"
					( Origin gPackager )
				)
				( attribute "CDS_SEC" "1"
					( Origin gPackager )
				)
				( attribute "LOCATION" "C7A29"
					( Origin gFrontEnd )
				)
				( attribute "MATERIAL" "X7R"
					( Origin gFrontEnd )
				)
				( attribute "PACK_TYPE" "0402LF"
					( Origin gFrontEnd )
				)
				( attribute "PART_NUMBER" "A36096-050"
					( Origin gFrontEnd )
				)
				( attribute "PHYS_PAGE" "218"
					( Origin gFrontEnd )
				)
				( attribute "ROOM" "VDDQ_DEF_PWR_VR"
					( Origin gFrontEnd )
				)
				( attribute "ROT" "2"
					( Origin gFrontEnd )
				)
				( attribute "SEC" "1"
					( Origin gFrontEnd )
				)
				( attribute "SEC_TYPE" "0402LF"
					( Origin gFrontEnd )
				)
				( attribute "TOLERANCE" "10%"
					( Origin gFrontEnd )
				)
				( attribute "VALUE" "220PF"
					( Origin gFrontEnd )
				)
				( attribute "VER" "1"
					( Origin gFrontEnd )
				)
				( attribute "VOLTAGE" "50V"
					( Units "uVoltage" "V" 1.000000)
					( Origin gFrontEnd )
				)
				( attribute "XY" "(-75,550)"
					( Origin gFrontEnd )
				)
				( attribute "CHIPS_PART_NAME" "CAP"
					( Origin gPackager )
				)
				( attribute "CDS_PART_NAME" "CAP_0402LF-220PF,50V,10%,X7R,AA"
					( Origin gPackager )
				)
				( objectStatus "C7A29" )
				( pin "a"
					( attribute "PN" "1"
						( Origin gPackager )
					)
					( objectStatus "C7A29.1" )
				)
				( pin "b"
					( attribute "PN" "2"
						( Origin gPackager )
					)
					( objectStatus "C7A29.2" )
				)
			)
			( gate "@baseboard_fab2_lib.baseboard_fab2(sch_1):page218_i40"
				( attribute "CDS_LIB" "mstr_discrete"
					( Origin gPackager )
				)
				( attribute "CDS_LOCATION" "R7A10"
					( Origin gPackager )
				)
				( attribute "CDS_SEC" "1"
					( Origin gPackager )
				)
				( attribute "LOCATION" "R7A10"
					( Origin gFrontEnd )
				)
				( attribute "MATERIAL" "CHIP"
					( Origin gFrontEnd )
				)
				( attribute "PACK_TYPE" "0402"
					( Origin gFrontEnd )
				)
				( attribute "PART_NUMBER" "G21796-043"
					( Origin gFrontEnd )
				)
				( attribute "PHYS_PAGE" "218"
					( Origin gFrontEnd )
				)
				( attribute "ROOM" "VDDQ_DEF_PWR_VR"
					( Origin gFrontEnd )
				)
				( attribute "ROT" "0"
					( Origin gFrontEnd )
				)
				( attribute "SEC" "1"
					( Origin gPackager )
				)
				( attribute "TOLERANCE" "1%"
					( Origin gFrontEnd )
				)
				( attribute "VALUE" "3.16K"
					( Origin gFrontEnd )
				)
				( attribute "VER" "2"
					( Origin gFrontEnd )
				)
				( attribute "WATTAGE" "1/16W"
					( Origin gFrontEnd )
				)
				( attribute "XY" "(100,100)"
					( Origin gFrontEnd )
				)
				( attribute "CHIPS_PART_NAME" "RES"
					( Origin gPackager )
				)
				( attribute "CDS_PART_NAME" "RES_0402-3.16K,1%,1/16W,CHIP,GA"
					( Origin gPackager )
				)
				( objectStatus "R7A10" )
				( pin "a"
					( attribute "PN" "1"
						( Origin gPackager )
					)
					( objectStatus "R7A10.1" )
				)
				( pin "b"
					( attribute "PN" "2"
						( Origin gPackager )
					)
					( objectStatus "R7A10.2" )
				)
			)
			( gate "@baseboard_fab2_lib.baseboard_fab2(sch_1):page218_i47"
				( attribute "CDS_LIB" "mstr_discrete"
					( Origin gPackager )
				)
				( attribute "CDS_LOCATION" "R3L13"
					( Origin gPackager )
				)
				( attribute "CDS_SEC" "1"
					( Origin gPackager )
				)
				( attribute "LOCATION" "R3L13"
					( Origin gFrontEnd )
				)
				( attribute "MATERIAL" "CHIP"
					( Origin gFrontEnd )
				)
				( attribute "PACK_TYPE" "0402"
					( Origin gFrontEnd )
				)
				( attribute "PART_NUMBER" "G21796-047"
					( Origin gFrontEnd )
				)
				( attribute "PHYS_PAGE" "218"
					( Origin gFrontEnd )
				)
				( attribute "ROOM" "VDDQ_DEF_PWR_VR"
					( Origin gFrontEnd )
				)
				( attribute "ROT" "0"
					( Origin gFrontEnd )
				)
				( attribute "SEC" "1"
					( Origin gFrontEnd )
				)
				( attribute "SEC_TYPE" "0402"
					( Origin gFrontEnd )
				)
				( attribute "TOLERANCE" "1%"
					( Origin gFrontEnd )
				)
				( attribute "VALUE" "49.9"
					( Origin gFrontEnd )
				)
				( attribute "VER" "2"
					( Origin gFrontEnd )
				)
				( attribute "WATTAGE" "1/16W"
					( Origin gFrontEnd )
				)
				( attribute "XY" "(-725,3350)"
					( Origin gFrontEnd )
				)
				( attribute "CHIPS_PART_NAME" "RES"
					( Origin gPackager )
				)
				( attribute "CDS_PART_NAME" "RES_0402-49.9,1%,1/16W,CHIP,G2A"
					( Origin gPackager )
				)
				( objectStatus "R3L13" )
				( pin "a"
					( attribute "PN" "1"
						( Origin gPackager )
					)
					( objectStatus "R3L13.1" )
				)
				( pin "b"
					( attribute "PN" "2"
						( Origin gPackager )
					)
					( objectStatus "R3L13.2" )
				)
			)
			( gate "@baseboard_fab2_lib.baseboard_fab2(sch_1):page218_i48"
				( attribute "CDS_LIB" "mstr_discrete"
					( Origin gPackager )
				)
				( attribute "CDS_LOCATION" "R7A17"
					( Origin gPackager )
				)
				( attribute "CDS_SEC" "1"
					( Origin gPackager )
				)
				( attribute "LOCATION" "R7A17"
					( Origin gFrontEnd )
				)
				( attribute "MATERIAL" "CHIP"
					( Origin gFrontEnd )
				)
				( attribute "PACK_TYPE" "0402"
					( Origin gFrontEnd )
				)
				( attribute "PART_NUMBER" "G21796-009"
					( Origin gFrontEnd )
				)
				( attribute "PHYS_PAGE" "218"
					( Origin gFrontEnd )
				)
				( attribute "ROOM" "VDDQ_DEF_PWR_VR"
					( Origin gFrontEnd )
				)
				( attribute "ROT" "0"
					( Origin gFrontEnd )
				)
				( attribute "SEC" "1"
					( Origin gFrontEnd )
				)
				( attribute "SEC_TYPE" "0402"
					( Origin gFrontEnd )
				)
				( attribute "TOLERANCE" "1%"
					( Origin gFrontEnd )
				)
				( attribute "VALUE" "150.0"
					( Origin gFrontEnd )
				)
				( attribute "VER" "1"
					( Origin gFrontEnd )
				)
				( attribute "WATTAGE" "1/16W"
					( Origin gFrontEnd )
				)
				( attribute "XY" "(-300,2825)"
					( Origin gFrontEnd )
				)
				( attribute "CHIPS_PART_NAME" "RES"
					( Origin gPackager )
				)
				( attribute "CDS_PART_NAME" "RES_0402-150.0,1%,1/16W,CHIP,GA"
					( Origin gPackager )
				)
				( objectStatus "R7A17" )
				( pin "a"
					( attribute "PN" "1"
						( Origin gPackager )
					)
					( objectStatus "R7A17.1" )
				)
				( pin "b"
					( attribute "PN" "2"
						( Origin gPackager )
					)
					( objectStatus "R7A17.2" )
				)
			)
			( gate "@baseboard_fab2_lib.baseboard_fab2(sch_1):page218_i50"
				( attribute "CDS_LIB" "mstr_discrete"
					( Origin gPackager )
				)
				( attribute "CDS_LOCATION" "R3L10"
					( Origin gPackager )
				)
				( attribute "CDS_SEC" "1"
					( Origin gPackager )
				)
				( attribute "LOCATION" "R3L10"
					( Origin gFrontEnd )
				)
				( attribute "MATERIAL" "CHIP"
					( Origin gFrontEnd )
				)
				( attribute "PACK_TYPE" "0402"
					( Origin gFrontEnd )
				)
				( attribute "PART_NUMBER" "G21497-005"
					( Origin gFrontEnd )
				)
				( attribute "PHYS_PAGE" "218"
					( Origin gFrontEnd )
				)
				( attribute "ROOM" "VDDQ_DEF_PWR_VR"
					( Origin gFrontEnd )
				)
				( attribute "ROT" "0"
					( Origin gFrontEnd )
				)
				( attribute "SEC" "1"
					( Origin gPackager )
				)
				( attribute "TOLERANCE" "5%"
					( Origin gFrontEnd )
				)
				( attribute "VALUE" "0.0"
					( Origin gFrontEnd )
				)
				( attribute "VER" "1"
					( Origin gFrontEnd )
				)
				( attribute "WATTAGE" "1/16W"
					( Origin gFrontEnd )
				)
				( attribute "XY" "(-825,2650)"
					( Origin gFrontEnd )
				)
				( attribute "CHIPS_PART_NAME" "RES"
					( Origin gPackager )
				)
				( attribute "CDS_PART_NAME" "RES_0402-0.0,5%,1/16W,CHIP,G21A"
					( Origin gPackager )
				)
				( objectStatus "R3L10" )
				( pin "a"
					( attribute "PN" "1"
						( Origin gPackager )
					)
					( objectStatus "R3L10.1" )
				)
				( pin "b"
					( attribute "PN" "2"
						( Origin gPackager )
					)
					( objectStatus "R3L10.2" )
				)
			)
			( gate "@baseboard_fab2_lib.baseboard_fab2(sch_1):page218_i53"
				( attribute "CDS_LIB" "mstr_discrete"
					( Origin gPackager )
				)
				( attribute "CDS_LOCATION" "R3L12"
					( Origin gPackager )
				)
				( attribute "CDS_SEC" "1"
					( Origin gPackager )
				)
				( attribute "LOCATION" "R3L12"
					( Origin gFrontEnd )
				)
				( attribute "MATERIAL" "CHIP"
					( Origin gFrontEnd )
				)
				( attribute "PACK_TYPE" "0402"
					( Origin gFrontEnd )
				)
				( attribute "PART_NUMBER" "G21796-160"
					( Origin gFrontEnd )
				)
				( attribute "PHYS_PAGE" "218"
					( Origin gFrontEnd )
				)
				( attribute "ROOM" "VDDQ_DEF_PWR_VR"
					( Origin gFrontEnd )
				)
				( attribute "ROT" "0"
					( Origin gFrontEnd )
				)
				( attribute "SEC" "1"
					( Origin gFrontEnd )
				)
				( attribute "SEC_TYPE" "0402"
					( Origin gFrontEnd )
				)
				( attribute "TOLERANCE" "1%"
					( Origin gFrontEnd )
				)
				( attribute "VALUE" "100.0K"
					( Origin gFrontEnd )
				)
				( attribute "VER" "2"
					( Origin gFrontEnd )
				)
				( attribute "WATTAGE" "1/16W"
					( Origin gFrontEnd )
				)
				( attribute "XY" "(-1350,3550)"
					( Origin gFrontEnd )
				)
				( attribute "CHIPS_PART_NAME" "RES"
					( Origin gPackager )
				)
				( attribute "CDS_PART_NAME" "RES_0402-100.0K,1%,1/16W,CHIP,B"
					( Origin gPackager )
				)
				( objectStatus "R3L12" )
				( pin "a"
					( attribute "PN" "1"
						( Origin gPackager )
					)
					( objectStatus "R3L12.1" )
				)
				( pin "b"
					( attribute "PN" "2"
						( Origin gPackager )
					)
					( objectStatus "R3L12.2" )
				)
			)
			( gate "@baseboard_fab2_lib.baseboard_fab2(sch_1):page218_i54"
				( attribute "CDS_LIB" "mstr_discrete"
					( Origin gPackager )
				)
				( attribute "CDS_LOCATION" "R7A16"
					( Origin gPackager )
				)
				( attribute "CDS_SEC" "1"
					( Origin gPackager )
				)
				( attribute "LOCATION" "R7A16"
					( Origin gFrontEnd )
				)
				( attribute "MATERIAL" "CHIP"
					( Origin gFrontEnd )
				)
				( attribute "PACK_TYPE" "0402"
					( Origin gFrontEnd )
				)
				( attribute "PART_NUMBER" "G21796-003"
					( Origin gFrontEnd )
				)
				( attribute "PHYS_PAGE" "218"
					( Origin gFrontEnd )
				)
				( attribute "ROOM" "VDDQ_DEF_PWR_VR"
					( Origin gFrontEnd )
				)
				( attribute "ROT" "0"
					( Origin gFrontEnd )
				)
				( attribute "SEC" "1"
					( Origin gFrontEnd )
				)
				( attribute "SEC_TYPE" "0402"
					( Origin gFrontEnd )
				)
				( attribute "TOLERANCE" "1%"
					( Origin gFrontEnd )
				)
				( attribute "VALUE" "1.5K"
					( Origin gFrontEnd )
				)
				( attribute "VER" "2"
					( Origin gFrontEnd )
				)
				( attribute "WATTAGE" "1/16W"
					( Origin gFrontEnd )
				)
				( attribute "XY" "(-1350,3175)"
					( Origin gFrontEnd )
				)
				( attribute "CHIPS_PART_NAME" "RES"
					( Origin gPackager )
				)
				( attribute "CDS_PART_NAME" "RES_0402-1.5K,1%,1/16W,CHIP,G2A"
					( Origin gPackager )
				)
				( objectStatus "R7A16" )
				( pin "a"
					( attribute "PN" "1"
						( Origin gPackager )
					)
					( objectStatus "R7A16.1" )
				)
				( pin "b"
					( attribute "PN" "2"
						( Origin gPackager )
					)
					( objectStatus "R7A16.2" )
				)
			)
			( gate "@baseboard_fab2_lib.baseboard_fab2(sch_1):page218_i55"
				( attribute "CDS_LIB" "mstr_discrete"
					( Origin gPackager )
				)
				( attribute "CDS_LOCATION" "C7A35"
					( Origin gPackager )
				)
				( attribute "CDS_SEC" "1"
					( Origin gPackager )
				)
				( attribute "LOCATION" "C7A35"
					( Origin gFrontEnd )
				)
				( attribute "MATERIAL" "X7R"
					( Origin gFrontEnd )
				)
				( attribute "PACK_TYPE" "0402LF"
					( Origin gFrontEnd )
				)
				( attribute "PART_NUMBER" "A36096-046"
					( Origin gFrontEnd )
				)
				( attribute "PHYS_PAGE" "218"
					( Origin gFrontEnd )
				)
				( attribute "ROOM" "VDDQ_DEF_PWR_VR"
					( Origin gFrontEnd )
				)
				( attribute "ROT" "2"
					( Origin gFrontEnd )
				)
				( attribute "SEC" "1"
					( Origin gFrontEnd )
				)
				( attribute "SEC_TYPE" "0402LF"
					( Origin gFrontEnd )
				)
				( attribute "TOLERANCE" "10%"
					( Origin gFrontEnd )
				)
				( attribute "VALUE" "1000PF"
					( Origin gFrontEnd )
				)
				( attribute "VER" "1"
					( Origin gFrontEnd )
				)
				( attribute "VOLTAGE" "50V"
					( Units "uVoltage" "V" 1.000000)
					( Origin gFrontEnd )
				)
				( attribute "XY" "(-1575,3175)"
					( Origin gFrontEnd )
				)
				( attribute "CHIPS_PART_NAME" "CAP"
					( Origin gPackager )
				)
				( attribute "CDS_PART_NAME" "CAP_0402LF-1000PF,50V,10%,X7R,A"
					( Origin gPackager )
				)
				( objectStatus "C7A35" )
				( pin "a"
					( attribute "PN" "1"
						( Origin gPackager )
					)
					( objectStatus "C7A35.1" )
				)
				( pin "b"
					( attribute "PN" "2"
						( Origin gPackager )
					)
					( objectStatus "C7A35.2" )
				)
			)
			( gate "@baseboard_fab2_lib.baseboard_fab2(sch_1):page218_i57"
				( attribute "CDS_LIB" "mstr_discrete"
					( Origin gPackager )
				)
				( attribute "CDS_LOCATION" "R3L9"
					( Origin gPackager )
				)
				( attribute "CDS_SEC" "1"
					( Origin gPackager )
				)
				( attribute "LOCATION" "R3L9"
					( Origin gFrontEnd )
				)
				( attribute "MATERIAL" "CHIP"
					( Origin gFrontEnd )
				)
				( attribute "PACK_TYPE" "0402"
					( Origin gFrontEnd )
				)
				( attribute "PART_NUMBER" "G21497-005"
					( Origin gFrontEnd )
				)
				( attribute "PHYS_PAGE" "218"
					( Origin gFrontEnd )
				)
				( attribute "ROOM" "VDDQ_DEF_PWR_VR"
					( Origin gFrontEnd )
				)
				( attribute "ROT" "0"
					( Origin gFrontEnd )
				)
				( attribute "SEC" "1"
					( Origin gPackager )
				)
				( attribute "TOLERANCE" "5%"
					( Origin gFrontEnd )
				)
				( attribute "VALUE" "0.0"
					( Origin gFrontEnd )
				)
				( attribute "VER" "1"
					( Origin gFrontEnd )
				)
				( attribute "WATTAGE" "1/16W"
					( Origin gFrontEnd )
				)
				( attribute "XY" "(-1400,2475)"
					( Origin gFrontEnd )
				)
				( attribute "CHIPS_PART_NAME" "RES"
					( Origin gPackager )
				)
				( attribute "CDS_PART_NAME" "RES_0402-0.0,5%,1/16W,CHIP,G21A"
					( Origin gPackager )
				)
				( objectStatus "R3L9" )
				( pin "a"
					( attribute "PN" "1"
						( Origin gPackager )
					)
					( objectStatus "R3L9.1" )
				)
				( pin "b"
					( attribute "PN" "2"
						( Origin gPackager )
					)
					( objectStatus "R3L9.2" )
				)
			)
			( gate "@baseboard_fab2_lib.baseboard_fab2(sch_1):page218_i59"
				( attribute "CDS_LIB" "mstr_discrete"
					( Origin gPackager )
				)
				( attribute "CDS_LOCATION" "R3M6"
					( Origin gPackager )
				)
				( attribute "CDS_SEC" "1"
					( Origin gPackager )
				)
				( attribute "LOCATION" "R3M6"
					( Origin gFrontEnd )
				)
				( attribute "MATERIAL" "CHIP"
					( Origin gFrontEnd )
				)
				( attribute "PACK_TYPE" "0402"
					( Origin gFrontEnd )
				)
				( attribute "PART_NUMBER" "G21497-005"
					( Origin gFrontEnd )
				)
				( attribute "PHYS_PAGE" "218"
					( Origin gFrontEnd )
				)
				( attribute "ROOM" "VDDQ_DEF_PWR_VR"
					( Origin gFrontEnd )
				)
				( attribute "ROT" "0"
					( Origin gFrontEnd )
				)
				( attribute "SEC" "1"
					( Origin gPackager )
				)
				( attribute "TOLERANCE" "5%"
					( Origin gFrontEnd )
				)
				( attribute "VALUE" "0.0"
					( Origin gFrontEnd )
				)
				( attribute "VER" "1"
					( Origin gFrontEnd )
				)
				( attribute "WATTAGE" "1/16W"
					( Origin gFrontEnd )
				)
				( attribute "XY" "(-1725,1300)"
					( Origin gFrontEnd )
				)
				( attribute "CHIPS_PART_NAME" "RES"
					( Origin gPackager )
				)
				( attribute "CDS_PART_NAME" "RES_0402-0.0,5%,1/16W,CHIP,G21A"
					( Origin gPackager )
				)
				( objectStatus "R3M6" )
				( pin "a"
					( attribute "PN" "1"
						( Origin gPackager )
					)
					( objectStatus "R3M6.1" )
				)
				( pin "b"
					( attribute "PN" "2"
						( Origin gPackager )
					)
					( objectStatus "R3M6.2" )
				)
			)
			( gate "@baseboard_fab2_lib.baseboard_fab2(sch_1):page218_i60"
				( attribute "CDS_LIB" "mstr_discrete"
					( Origin gPackager )
				)
				( attribute "CDS_LOCATION" "R7A7"
					( Origin gPackager )
				)
				( attribute "CDS_SEC" "1"
					( Origin gPackager )
				)
				( attribute "LOCATION" "R7A7"
					( Origin gFrontEnd )
				)
				( attribute "MATERIAL" "CHIP"
					( Origin gFrontEnd )
				)
				( attribute "PACK_TYPE" "0402"
					( Origin gFrontEnd )
				)
				( attribute "PART_NUMBER" "G21796-066"
					( Origin gFrontEnd )
				)
				( attribute "PHYS_PAGE" "218"
					( Origin gFrontEnd )
				)
				( attribute "ROOM" "VDDQ_DEF_PWR_VR"
					( Origin gFrontEnd )
				)
				( attribute "ROT" "0"
					( Origin gFrontEnd )
				)
				( attribute "SEC" "1"
					( Origin gFrontEnd )
				)
				( attribute "SEC_TYPE" "0402"
					( Origin gFrontEnd )
				)
				( attribute "TOLERANCE" "1%"
					( Origin gFrontEnd )
				)
				( attribute "VALUE" "10.0"
					( Origin gFrontEnd )
				)
				( attribute "VER" "1"
					( Origin gFrontEnd )
				)
				( attribute "WATTAGE" "1/16W"
					( Origin gFrontEnd )
				)
				( attribute "XY" "(-1750,975)"
					( Origin gFrontEnd )
				)
				( attribute "CHIPS_PART_NAME" "RES"
					( Origin gPackager )
				)
				( attribute "CDS_PART_NAME" "RES_0402-10.0,1%,1/16W,CHIP,G2A"
					( Origin gPackager )
				)
				( objectStatus "R7A7" )
				( pin "a"
					( attribute "PN" "1"
						( Origin gPackager )
					)
					( objectStatus "R7A7.1" )
				)
				( pin "b"
					( attribute "PN" "2"
						( Origin gPackager )
					)
					( objectStatus "R7A7.2" )
				)
			)
			( gate "@baseboard_fab2_lib.baseboard_fab2(sch_1):page218_i61"
				( attribute "CDS_LIB" "mstr_discrete"
					( Origin gPackager )
				)
				( attribute "CDS_LOCATION" "C7A28"
					( Origin gPackager )
				)
				( attribute "CDS_SEC" "1"
					( Origin gPackager )
				)
				( attribute "LOCATION" "C7A28"
					( Origin gFrontEnd )
				)
				( attribute "MATERIAL" "X7R"
					( Origin gFrontEnd )
				)
				( attribute "PACK_TYPE" "0402LF"
					( Origin gFrontEnd )
				)
				( attribute "PART_NUMBER" "A36096-050"
					( Origin gFrontEnd )
				)
				( attribute "PHYS_PAGE" "218"
					( Origin gFrontEnd )
				)
				( attribute "ROOM" "VDDQ_DEF_PWR_VR"
					( Origin gFrontEnd )
				)
				( attribute "ROT" "0"
					( Origin gFrontEnd )
				)
				( attribute "SEC" "1"
					( Origin gFrontEnd )
				)
				( attribute "SEC_TYPE" "0402LF"
					( Origin gFrontEnd )
				)
				( attribute "TOLERANCE" "10%"
					( Origin gFrontEnd )
				)
				( attribute "VALUE" "220PF"
					( Origin gFrontEnd )
				)
				( attribute "VER" "1"
					( Origin gFrontEnd )
				)
				( attribute "VOLTAGE" "50V"
					( Units "uVoltage" "V" 1.000000)
					( Origin gFrontEnd )
				)
				( attribute "XY" "(-1475,825)"
					( Origin gFrontEnd )
				)
				( attribute "CHIPS_PART_NAME" "CAP"
					( Origin gPackager )
				)
				( attribute "CDS_PART_NAME" "CAP_0402LF-220PF,50V,10%,X7R,AA"
					( Origin gPackager )
				)
				( objectStatus "C7A28" )
				( pin "a"
					( attribute "PN" "1"
						( Origin gPackager )
					)
					( objectStatus "C7A28.1" )
				)
				( pin "b"
					( attribute "PN" "2"
						( Origin gPackager )
					)
					( objectStatus "C7A28.2" )
				)
			)
			( gate "@baseboard_fab2_lib.baseboard_fab2(sch_1):page218_i75"
				( attribute "CDS_LIB" "mstr_controller"
					( Origin gPackager )
				)
				( attribute "CDS_LMAN_SYM_OUTLINE" "-400,900,400,-900"
					( Origin gPackager )
				)
				( attribute "CDS_LOCATION" "EU7A5"
					( Origin gPackager )
				)
				( attribute "CDS_SEC" "1"
					( Origin gPackager )
				)
				( attribute "LOCATION" "EU7A5"
					( Origin gFrontEnd )
				)
				( attribute "MATERIAL" "IC"
					( Origin gFrontEnd )
				)
				( attribute "PACK_TYPE" "QFN"
					( Origin gFrontEnd )
				)
				( attribute "PART_NUMBER" "H89186-001"
					( Origin gFrontEnd )
				)
				( attribute "PHYS_PAGE" "218"
					( Origin gFrontEnd )
				)
				( attribute "ROT" "0"
					( Origin gFrontEnd )
				)
				( attribute "SEC" "1"
					( Origin gFrontEnd )
				)
				( attribute "SEC_TYPE" "QFN"
					( Origin gFrontEnd )
				)
				( attribute "VER" "2"
					( Origin gFrontEnd )
				)
				( attribute "XY" "(1325,1600)"
					( Origin gFrontEnd )
				)
				( attribute "CHIPS_PART_NAME" "PXM1310B"
					( Origin gPackager )
				)
				( attribute "CDS_PART_NAME" "PXM1310B_QFN-IC,H89186-001"
					( Origin gPackager )
				)
				( objectStatus "EU7A5" )
				( pin "airef1"
					( attribute "PN" "21"
						( Origin gPackager )
					)
					( objectStatus "EU7A5.21" )
				)
				( pin "airef2"
					( attribute "PN" "23"
						( Origin gPackager )
					)
					( objectStatus "EU7A5.23" )
				)
				( pin "airef3"
					( attribute "PN" "25"
						( Origin gPackager )
					)
					( objectStatus "EU7A5.25" )
				)
				( pin "aisen1"
					( attribute "PN" "22"
						( Origin gPackager )
					)
					( objectStatus "EU7A5.22" )
				)
				( pin "aisen2"
					( attribute "PN" "24"
						( Origin gPackager )
					)
					( objectStatus "EU7A5.24" )
				)
				( pin "aisen3"
					( attribute "PN" "26"
						( Origin gPackager )
					)
					( objectStatus "EU7A5.26" )
				)
				( pin "apwm1"
					( attribute "PN" "5"
						( Origin gPackager )
					)
					( objectStatus "EU7A5.5" )
				)
				( pin "apwm2"
					( attribute "PN" "4"
						( Origin gPackager )
					)
					( objectStatus "EU7A5.4" )
				)
				( pin "apwm3"
					( attribute "PN" "3"
						( Origin gPackager )
					)
					( objectStatus "EU7A5.3" )
				)
				( pin "atsen"
					( attribute "PN" "35"
						( Origin gPackager )
					)
					( objectStatus "EU7A5.35" )
				)
				( pin "avref"
					( attribute "PN" "20"
						( Origin gPackager )
					)
					( objectStatus "EU7A5.20" )
				)
				( pin "avren"
					( attribute "PN" "10"
						( Origin gPackager )
					)
					( objectStatus "EU7A5.10" )
				)
				( pin "avrrdy"
					( attribute "PN" "9"
						( Origin gPackager )
					)
					( objectStatus "EU7A5.9" )
				)
				( pin "avsen"
					( attribute "PN" "19"
						( Origin gPackager )
					)
					( objectStatus "EU7A5.19" )
				)
				( pin "biref1"
					( attribute "PN" "31"
						( Origin gPackager )
					)
					( objectStatus "EU7A5.31" )
				)
				( pin "bisen1"
					( attribute "PN" "32"
						( Origin gPackager )
					)
					( objectStatus "EU7A5.32" )
				)
				( pin "bpwm1"
					( attribute "PN" "1"
						( Origin gPackager )
					)
					( objectStatus "EU7A5.1" )
				)
				( pin "btsen"
					( attribute "PN" "34"
						( Origin gPackager )
					)
					( objectStatus "EU7A5.34" )
				)
				( pin "bvref"
					( attribute "PN" "30"
						( Origin gPackager )
					)
					( objectStatus "EU7A5.30" )
				)
				( pin "bvsen"
					( attribute "PN" "29"
						( Origin gPackager )
					)
					( objectStatus "EU7A5.29" )
				)
				( pin "dnc(0)"
					( attribute "PN" "2"
						( Origin gPackager )
					)
					( objectStatus "EU7A5.2" )
				)
				( pin "dnc(1)"
					( attribute "PN" "28"
						( Origin gPackager )
					)
					( objectStatus "EU7A5.28" )
				)
				( pin "gnd"
					( attribute "PN" "27"
						( Origin gPackager )
					)
					( objectStatus "EU7A5.27" )
				)
				( pin "iinsen"
					( attribute "PN" "38"
						( Origin gPackager )
					)
					( objectStatus "EU7A5.38" )
				)
				( pin "mp0"
					( attribute "PN" "13"
						( Origin gPackager )
					)
					( objectStatus "EU7A5.13" )
				)
				( pin "mp1"
					( attribute "PN" "14"
						( Origin gPackager )
					)
					( objectStatus "EU7A5.14" )
				)
				( pin "mp2"
					( attribute "PN" "18"
						( Origin gPackager )
					)
					( objectStatus "EU7A5.18" )
				)
				( pin "pinalrt_n"
					( attribute "PN" "12"
						( Origin gPackager )
					)
					( objectStatus "EU7A5.12" )
				)
				( pin "reset_n"
					( attribute "PN" "8"
						( Origin gPackager )
					)
					( objectStatus "EU7A5.8" )
				)
				( pin "scl"
					( attribute "PN" "7"
						( Origin gPackager )
					)
					( objectStatus "EU7A5.7" )
				)
				( pin "sda"
					( attribute "PN" "6"
						( Origin gPackager )
					)
					( objectStatus "EU7A5.6" )
				)
				( pin "thpad"
					( attribute "PN" "41"
						( Origin gPackager )
					)
					( objectStatus "EU7A5.41" )
				)
				( pin "valrt_n"
					( attribute "PN" "17"
						( Origin gPackager )
					)
					( objectStatus "EU7A5.17" )
				)
				( pin "vclk"
					( attribute "PN" "15"
						( Origin gPackager )
					)
					( objectStatus "EU7A5.15" )
				)
				( pin "vd12"
					( attribute "PN" "40"
						( Origin gPackager )
					)
					( objectStatus "EU7A5.40" )
				)
				( pin "vdd"
					( attribute "PN" "39"
						( Origin gPackager )
					)
					( objectStatus "EU7A5.39" )
				)
				( pin "vdio"
					( attribute "PN" "16"
						( Origin gPackager )
					)
					( objectStatus "EU7A5.16" )
				)
				( pin "vinsen"
					( attribute "PN" "37"
						( Origin gPackager )
					)
					( objectStatus "EU7A5.37" )
				)
				( pin "vrhot_n"
					( attribute "PN" "11"
						( Origin gPackager )
					)
					( objectStatus "EU7A5.11" )
				)
				( pin "xaddr1"
					( attribute "PN" "36"
						( Origin gPackager )
					)
					( objectStatus "EU7A5.36" )
				)
				( pin "xaddr2"
					( attribute "PN" "33"
						( Origin gPackager )
					)
					( objectStatus "EU7A5.33" )
				)
			)
			( gate "@baseboard_fab2_lib.baseboard_fab2(sch_1):page218_i77"
				( attribute "CDS_LIB" "dev_discrete"
					( Origin gPackager )
				)
				( attribute "CDS_LOCATION" "C3L31"
					( Origin gPackager )
				)
				( attribute "CDS_SEC" "1"
					( Origin gPackager )
				)
				( attribute "LOCATION" "C3L31"
					( Origin gFrontEnd )
				)
				( attribute "MATERIAL" "X7R"
					( Origin gFrontEnd )
				)
				( attribute "PACK_TYPE" "0402V"
					( Origin gFrontEnd )
				)
				( attribute "PART_NUMBER" "A36096-030"
					( Origin gFrontEnd )
				)
				( attribute "PHYS_PAGE" "218"
					( Origin gFrontEnd )
				)
				( attribute "ROOM" "VDDQ_DEF_PWR_VR"
					( Origin gFrontEnd )
				)
				( attribute "ROT" "2"
					( Origin gFrontEnd )
				)
				( attribute "SEC" "1"
					( Origin gFrontEnd )
				)
				( attribute "SEC_TYPE" "0402V"
					( Origin gFrontEnd )
				)
				( attribute "TOLERANCE" "10%"
					( Origin gFrontEnd )
				)
				( attribute "VALUE" "0.1UF"
					( Origin gFrontEnd )
				)
				( attribute "VER" "1"
					( Origin gFrontEnd )
				)
				( attribute "VOLTAGE" "16V"
					( Units "uVoltage" "V" 1.000000)
					( Origin gFrontEnd )
				)
				( attribute "XY" "(-800,350)"
					( Origin gFrontEnd )
				)
				( attribute "CHIPS_PART_NAME" "CAP_A"
					( Origin gPackager )
				)
				( attribute "CDS_PART_NAME" "CAP_A_0402V-0.1UF,16V,10%,X7R,A"
					( Origin gPackager )
				)
				( objectStatus "C3L31" )
				( pin "a"
					( attribute "PN" "1"
						( Origin gPackager )
					)
					( objectStatus "C3L31.1" )
				)
				( pin "b"
					( attribute "PN" "2"
						( Origin gPackager )
					)
					( objectStatus "C3L31.2" )
				)
			)
			( gate "@baseboard_fab2_lib.baseboard_fab2(sch_1):page219_i44"
				( attribute "CDS_LIB" "mstr_discrete"
					( Origin gPackager )
				)
				( attribute "CDS_LOCATION" "C7A12"
					( Origin gPackager )
				)
				( attribute "CDS_SEC" "1"
					( Origin gPackager )
				)
				( attribute "LOCATION" "C7A12"
					( Origin gFrontEnd )
				)
				( attribute "MATERIAL" "X7R"
					( Origin gFrontEnd )
				)
				( attribute "PACK_TYPE" "0402"
					( Origin gFrontEnd )
				)
				( attribute "PART_NUMBER" "A36096-104"
					( Origin gFrontEnd )
				)
				( attribute "PHYS_PAGE" "219"
					( Origin gFrontEnd )
				)
				( attribute "ROOM" "VDDQ_DEF_PWR_VR"
					( Origin gFrontEnd )
				)
				( attribute "ROT" "2"
					( Origin gFrontEnd )
				)
				( attribute "SEC" "1"
					( Origin gPackager )
				)
				( attribute "SPOF" "TRUE"
					( Origin gFrontEnd )
				)
				( attribute "TOLERANCE" "10%"
					( Origin gFrontEnd )
				)
				( attribute "VALUE" "0.220UF"
					( Origin gFrontEnd )
				)
				( attribute "VER" "1"
					( Origin gFrontEnd )
				)
				( attribute "VOLTAGE" "16V"
					( Units "uVoltage" "V" 1.000000)
					( Origin gFrontEnd )
				)
				( attribute "XY" "(-1300,1725)"
					( Origin gFrontEnd )
				)
				( attribute "CHIPS_PART_NAME" "CAP"
					( Origin gPackager )
				)
				( attribute "CDS_PART_NAME" "CAP_0402-0.220UF,16V,10%,X7R,AA"
					( Origin gPackager )
				)
				( objectStatus "C7A12" )
				( pin "a"
					( attribute "PN" "1"
						( Origin gPackager )
					)
					( objectStatus "C7A12.1" )
				)
				( pin "b"
					( attribute "PN" "2"
						( Origin gPackager )
					)
					( objectStatus "C7A12.2" )
				)
			)
			( gate "@baseboard_fab2_lib.baseboard_fab2(sch_1):page219_i45"
				( attribute "CDS_LIB" "mstr_discrete"
					( Origin gPackager )
				)
				( attribute "CDS_LOCATION" "C3L2"
					( Origin gPackager )
				)
				( attribute "CDS_SEC" "1"
					( Origin gPackager )
				)
				( attribute "LOCATION" "C3L2"
					( Origin gFrontEnd )
				)
				( attribute "MATERIAL" "X6S"
					( Origin gFrontEnd )
				)
				( attribute "PACK_TYPE" "0805"
					( Origin gFrontEnd )
				)
				( attribute "PART_NUMBER" "C95333-007"
					( Origin gFrontEnd )
				)
				( attribute "PHYS_PAGE" "219"
					( Origin gFrontEnd )
				)
				( attribute "ROOM" "VDDQ_DEF_PWR_VR"
					( Origin gFrontEnd )
				)
				( attribute "ROT" "0"
					( Origin gFrontEnd )
				)
				( attribute "SEC" "1"
					( Origin gPackager )
				)
				( attribute "TOLERANCE" "10%"
					( Origin gFrontEnd )
				)
				( attribute "VALUE" "10UF"
					( Origin gFrontEnd )
				)
				( attribute "VER" "1"
					( Origin gFrontEnd )
				)
				( attribute "VOLTAGE" "16V"
					( Units "uVoltage" "V" 1.000000)
					( Origin gFrontEnd )
				)
				( attribute "XY" "(-2500,2400)"
					( Origin gFrontEnd )
				)
				( attribute "CHIPS_PART_NAME" "CAP"
					( Origin gPackager )
				)
				( attribute "CDS_PART_NAME" "CAP_0805-10UF,16V,10%,X6S,C953A"
					( Origin gPackager )
				)
				( objectStatus "C3L2" )
				( pin "a"
					( attribute "PN" "1"
						( Origin gPackager )
					)
					( objectStatus "C3L2.1" )
				)
				( pin "b"
					( attribute "PN" "2"
						( Origin gPackager )
					)
					( objectStatus "C3L2.2" )
				)
			)
			( gate "@baseboard_fab2_lib.baseboard_fab2(sch_1):page219_i46"
				( attribute "CDS_LIB" "mstr_discrete"
					( Origin gPackager )
				)
				( attribute "CDS_LOCATION" "C3L4"
					( Origin gPackager )
				)
				( attribute "CDS_SEC" "1"
					( Origin gPackager )
				)
				( attribute "LOCATION" "C3L4"
					( Origin gFrontEnd )
				)
				( attribute "MATERIAL" "X6S"
					( Origin gFrontEnd )
				)
				( attribute "PACK_TYPE" "0805"
					( Origin gFrontEnd )
				)
				( attribute "PART_NUMBER" "C95333-007"
					( Origin gFrontEnd )
				)
				( attribute "PHYS_PAGE" "219"
					( Origin gFrontEnd )
				)
				( attribute "ROOM" "VDDQ_DEF_PWR_VR"
					( Origin gFrontEnd )
				)
				( attribute "ROT" "0"
					( Origin gFrontEnd )
				)
				( attribute "SEC" "1"
					( Origin gPackager )
				)
				( attribute "TOLERANCE" "10%"
					( Origin gFrontEnd )
				)
				( attribute "VALUE" "10UF"
					( Origin gFrontEnd )
				)
				( attribute "VER" "1"
					( Origin gFrontEnd )
				)
				( attribute "VOLTAGE" "16V"
					( Units "uVoltage" "V" 1.000000)
					( Origin gFrontEnd )
				)
				( attribute "XY" "(-2250,2375)"
					( Origin gFrontEnd )
				)
				( attribute "CHIPS_PART_NAME" "CAP"
					( Origin gPackager )
				)
				( attribute "CDS_PART_NAME" "CAP_0805-10UF,16V,10%,X6S,C953A"
					( Origin gPackager )
				)
				( objectStatus "C3L4" )
				( pin "a"
					( attribute "PN" "1"
						( Origin gPackager )
					)
					( objectStatus "C3L4.1" )
				)
				( pin "b"
					( attribute "PN" "2"
						( Origin gPackager )
					)
					( objectStatus "C3L4.2" )
				)
			)
			( gate "@baseboard_fab2_lib.baseboard_fab2(sch_1):page219_i47"
				( attribute "CDS_LIB" "mstr_discrete"
					( Origin gPackager )
				)
				( attribute "CDS_LOCATION" "C3L13"
					( Origin gPackager )
				)
				( attribute "CDS_SEC" "1"
					( Origin gPackager )
				)
				( attribute "LOCATION" "C3L13"
					( Origin gFrontEnd )
				)
				( attribute "MATERIAL" "X6S"
					( Origin gFrontEnd )
				)
				( attribute "PACK_TYPE" "0805"
					( Origin gFrontEnd )
				)
				( attribute "PART_NUMBER" "C95333-007"
					( Origin gFrontEnd )
				)
				( attribute "PHYS_PAGE" "219"
					( Origin gFrontEnd )
				)
				( attribute "ROOM" "VDDQ_DEF_PWR_VR"
					( Origin gFrontEnd )
				)
				( attribute "ROT" "0"
					( Origin gFrontEnd )
				)
				( attribute "SEC" "1"
					( Origin gPackager )
				)
				( attribute "TOLERANCE" "10%"
					( Origin gFrontEnd )
				)
				( attribute "VALUE" "10UF"
					( Origin gFrontEnd )
				)
				( attribute "VER" "1"
					( Origin gFrontEnd )
				)
				( attribute "VOLTAGE" "16V"
					( Units "uVoltage" "V" 1.000000)
					( Origin gFrontEnd )
				)
				( attribute "XY" "(-2000,2375)"
					( Origin gFrontEnd )
				)
				( attribute "CHIPS_PART_NAME" "CAP"
					( Origin gPackager )
				)
				( attribute "CDS_PART_NAME" "CAP_0805-10UF,16V,10%,X6S,C953A"
					( Origin gPackager )
				)
				( objectStatus "C3L13" )
				( pin "a"
					( attribute "PN" "1"
						( Origin gPackager )
					)
					( objectStatus "C3L13.1" )
				)
				( pin "b"
					( attribute "PN" "2"
						( Origin gPackager )
					)
					( objectStatus "C3L13.2" )
				)
			)
			( gate "@baseboard_fab2_lib.baseboard_fab2(sch_1):page219_i48"
				( attribute "CDS_LIB" "mstr_discrete"
					( Origin gPackager )
				)
				( attribute "CDS_LOCATION" "C7A11"
					( Origin gPackager )
				)
				( attribute "CDS_SEC" "1"
					( Origin gPackager )
				)
				( attribute "LOCATION" "C7A11"
					( Origin gFrontEnd )
				)
				( attribute "MATERIAL" "X6S"
					( Origin gFrontEnd )
				)
				( attribute "PACK_TYPE" "0402"
					( Origin gFrontEnd )
				)
				( attribute "PART_NUMBER" "D97712-011"
					( Origin gFrontEnd )
				)
				( attribute "PHYS_PAGE" "219"
					( Origin gFrontEnd )
				)
				( attribute "ROOM" "VDDQ_DEF_PWR_VR"
					( Origin gFrontEnd )
				)
				( attribute "ROT" "0"
					( Origin gFrontEnd )
				)
				( attribute "SEC" "1"
					( Origin gPackager )
				)
				( attribute "TOLERANCE" "10%"
					( Origin gFrontEnd )
				)
				( attribute "VALUE" "1.0UF"
					( Origin gFrontEnd )
				)
				( attribute "VER" "1"
					( Origin gFrontEnd )
				)
				( attribute "VOLTAGE" "16V"
					( Units "uVoltage" "V" 1.000000)
					( Origin gFrontEnd )
				)
				( attribute "XY" "(-1725,2375)"
					( Origin gFrontEnd )
				)
				( attribute "CHIPS_PART_NAME" "CAP"
					( Origin gPackager )
				)
				( attribute "CDS_PART_NAME" "CAP_0402-1.0UF,16V,10%,X6S,D97A"
					( Origin gPackager )
				)
				( objectStatus "C7A11" )
				( pin "a"
					( attribute "PN" "1"
						( Origin gPackager )
					)
					( objectStatus "C7A11.1" )
				)
				( pin "b"
					( attribute "PN" "2"
						( Origin gPackager )
					)
					( objectStatus "C7A11.2" )
				)
			)
			( gate "@baseboard_fab2_lib.baseboard_fab2(sch_1):page219_i50"
				( attribute "CDS_LIB" "mstr_discrete"
					( Origin gPackager )
				)
				( attribute "CDS_LOCATION" "C7A16"
					( Origin gPackager )
				)
				( attribute "CDS_SEC" "1"
					( Origin gPackager )
				)
				( attribute "LOCATION" "C7A16"
					( Origin gFrontEnd )
				)
				( attribute "MATERIAL" "X6S"
					( Origin gFrontEnd )
				)
				( attribute "PACK_TYPE" "0402"
					( Origin gFrontEnd )
				)
				( attribute "PART_NUMBER" "D97712-011"
					( Origin gFrontEnd )
				)
				( attribute "PHYS_PAGE" "219"
					( Origin gFrontEnd )
				)
				( attribute "ROOM" "VDDQ_DEF_PWR_VR"
					( Origin gFrontEnd )
				)
				( attribute "ROT" "0"
					( Origin gFrontEnd )
				)
				( attribute "SEC" "1"
					( Origin gPackager )
				)
				( attribute "TOLERANCE" "10%"
					( Origin gFrontEnd )
				)
				( attribute "VALUE" "1.0UF"
					( Origin gFrontEnd )
				)
				( attribute "VER" "1"
					( Origin gFrontEnd )
				)
				( attribute "VOLTAGE" "16V"
					( Units "uVoltage" "V" 1.000000)
					( Origin gFrontEnd )
				)
				( attribute "XY" "(-1200,2350)"
					( Origin gFrontEnd )
				)
				( attribute "CHIPS_PART_NAME" "CAP"
					( Origin gPackager )
				)
				( attribute "CDS_PART_NAME" "CAP_0402-1.0UF,16V,10%,X6S,D97A"
					( Origin gPackager )
				)
				( objectStatus "C7A16" )
				( pin "a"
					( attribute "PN" "1"
						( Origin gPackager )
					)
					( objectStatus "C7A16.1" )
				)
				( pin "b"
					( attribute "PN" "2"
						( Origin gPackager )
					)
					( objectStatus "C7A16.2" )
				)
			)
			( gate "@baseboard_fab2_lib.baseboard_fab2(sch_1):page219_i51"
				( attribute "CDS_LIB" "dev_discrete"
					( Origin gPackager )
				)
				( attribute "CDS_LOCATION" "C7A5"
					( Origin gPackager )
				)
				( attribute "CDS_SEC" "1"
					( Origin gPackager )
				)
				( attribute "LOCATION" "C7A5"
					( Origin gFrontEnd )
				)
				( attribute "MATERIAL" "X7R"
					( Origin gFrontEnd )
				)
				( attribute "PACK_TYPE" "0402V"
					( Origin gFrontEnd )
				)
				( attribute "PART_NUMBER" "A36096-030"
					( Origin gFrontEnd )
				)
				( attribute "PHYS_PAGE" "219"
					( Origin gFrontEnd )
				)
				( attribute "ROOM" "VDDQ_DEF_PWR_VR"
					( Origin gFrontEnd )
				)
				( attribute "ROT" "0"
					( Origin gFrontEnd )
				)
				( attribute "SEC" "1"
					( Origin gPackager )
				)
				( attribute "TOLERANCE" "10%"
					( Origin gFrontEnd )
				)
				( attribute "VALUE" "0.1UF"
					( Origin gFrontEnd )
				)
				( attribute "VER" "1"
					( Origin gFrontEnd )
				)
				( attribute "VOLTAGE" "16V"
					( Units "uVoltage" "V" 1.000000)
					( Origin gFrontEnd )
				)
				( attribute "XY" "(-1475,2375)"
					( Origin gFrontEnd )
				)
				( attribute "CHIPS_PART_NAME" "CAP_A"
					( Origin gPackager )
				)
				( attribute "CDS_PART_NAME" "CAP_A_0402V-0.1UF,16V,10%,X7R,A"
					( Origin gPackager )
				)
				( objectStatus "C7A5" )
				( pin "a"
					( attribute "PN" "1"
						( Origin gPackager )
					)
					( objectStatus "C7A5.1" )
				)
				( pin "b"
					( attribute "PN" "2"
						( Origin gPackager )
					)
					( objectStatus "C7A5.2" )
				)
			)
			( gate "@baseboard_fab2_lib.baseboard_fab2(sch_1):page219_i52"
				( attribute "CDS_LIB" "mstr_discrete"
					( Origin gPackager )
				)
				( attribute "CDS_LOCATION" "R3L6"
					( Origin gPackager )
				)
				( attribute "CDS_SEC" "1"
					( Origin gPackager )
				)
				( attribute "LOCATION" "R3L6"
					( Origin gFrontEnd )
				)
				( attribute "MATERIAL" "CHIP"
					( Origin gFrontEnd )
				)
				( attribute "PACK_TYPE" "0402"
					( Origin gFrontEnd )
				)
				( attribute "PART_NUMBER" "G21796-090"
					( Origin gFrontEnd )
				)
				( attribute "PHYS_PAGE" "219"
					( Origin gFrontEnd )
				)
				( attribute "ROOM" "VDDQ_DEF_PWR_VR"
					( Origin gFrontEnd )
				)
				( attribute "ROT" "0"
					( Origin gFrontEnd )
				)
				( attribute "SEC" "1"
					( Origin gPackager )
				)
				( attribute "TOLERANCE" "1%"
					( Origin gFrontEnd )
				)
				( attribute "VALUE" "1.0"
					( Origin gFrontEnd )
				)
				( attribute "VER" "1"
					( Origin gFrontEnd )
				)
				( attribute "WATTAGE" "1/16W"
					( Origin gFrontEnd )
				)
				( attribute "XY" "(-975,2950)"
					( Origin gFrontEnd )
				)
				( attribute "CHIPS_PART_NAME" "RES"
					( Origin gPackager )
				)
				( attribute "CDS_PART_NAME" "RES_0402-1.0,1%,1/16W,CHIP,G21A"
					( Origin gPackager )
				)
				( objectStatus "R3L6" )
				( pin "a"
					( attribute "PN" "1"
						( Origin gPackager )
					)
					( objectStatus "R3L6.1" )
				)
				( pin "b"
					( attribute "PN" "2"
						( Origin gPackager )
					)
					( objectStatus "R3L6.2" )
				)
			)
			( gate "@baseboard_fab2_lib.baseboard_fab2(sch_1):page219_i53"
				( attribute "CDS_LIB" "dev_discrete"
					( Origin gPackager )
				)
				( attribute "CDS_LOCATION" "C7A18"
					( Origin gPackager )
				)
				( attribute "CDS_SEC" "1"
					( Origin gPackager )
				)
				( attribute "LOCATION" "C7A18"
					( Origin gFrontEnd )
				)
				( attribute "MATERIAL" "X6S"
					( Origin gFrontEnd )
				)
				( attribute "PACK_TYPE" "0402V"
					( Origin gFrontEnd )
				)
				( attribute "PART_NUMBER" "D97712-004"
					( Origin gFrontEnd )
				)
				( attribute "PHYS_PAGE" "219"
					( Origin gFrontEnd )
				)
				( attribute "ROOM" "VDDQ_DEF_PWR_VR"
					( Origin gFrontEnd )
				)
				( attribute "ROT" "2"
					( Origin gFrontEnd )
				)
				( attribute "SEC" "1"
					( Origin gPackager )
				)
				( attribute "TOLERANCE" "10%"
					( Origin gFrontEnd )
				)
				( attribute "VALUE" "1.0UF"
					( Origin gFrontEnd )
				)
				( attribute "VER" "1"
					( Origin gFrontEnd )
				)
				( attribute "VOLTAGE" "6.3V"
					( Units "uVoltage" "V" 1.000000)
					( Origin gFrontEnd )
				)
				( attribute "XY" "(-575,2375)"
					( Origin gFrontEnd )
				)
				( attribute "CHIPS_PART_NAME" "CAP_A"
					( Origin gPackager )
				)
				( attribute "CDS_PART_NAME" "CAP_A_0402V-1.0UF,6.3V,10%,X6SA"
					( Origin gPackager )
				)
				( objectStatus "C7A18" )
				( pin "a"
					( attribute "PN" "1"
						( Origin gPackager )
					)
					( objectStatus "C7A18.1" )
				)
				( pin "b"
					( attribute "PN" "2"
						( Origin gPackager )
					)
					( objectStatus "C7A18.2" )
				)
			)
			( gate "@baseboard_fab2_lib.baseboard_fab2(sch_1):page219_i54"
				( attribute "CDS_LIB" "mstr_discrete"
					( Origin gPackager )
				)
				( attribute "CDS_LOCATION" "C7A17"
					( Origin gPackager )
				)
				( attribute "CDS_SEC" "1"
					( Origin gPackager )
				)
				( attribute "LOCATION" "C7A17"
					( Origin gFrontEnd )
				)
				( attribute "MATERIAL" "X7R"
					( Origin gFrontEnd )
				)
				( attribute "PACK_TYPE" "0402"
					( Origin gFrontEnd )
				)
				( attribute "PART_NUMBER" "A36096-155"
					( Origin gFrontEnd )
				)
				( attribute "PHYS_PAGE" "219"
					( Origin gFrontEnd )
				)
				( attribute "ROOM" "VDDQ_DEF_PWR_VR"
					( Origin gFrontEnd )
				)
				( attribute "ROT" "0"
					( Origin gFrontEnd )
				)
				( attribute "SEC" "1"
					( Origin gPackager )
				)
				( attribute "TOLERANCE" "10%"
					( Origin gFrontEnd )
				)
				( attribute "VALUE" "0.22UF"
					( Origin gFrontEnd )
				)
				( attribute "VER" "1"
					( Origin gFrontEnd )
				)
				( attribute "VOLTAGE" "16V"
					( Units "uVoltage" "V" 1.000000)
					( Origin gFrontEnd )
				)
				( attribute "XY" "(-475,2375)"
					( Origin gFrontEnd )
				)
				( attribute "CHIPS_PART_NAME" "CAP"
					( Origin gPackager )
				)
				( attribute "CDS_PART_NAME" "CAP_0402-0.22UF,16V,10%,X7R,A3A"
					( Origin gPackager )
				)
				( objectStatus "C7A17" )
				( pin "a"
					( attribute "PN" "1"
						( Origin gPackager )
					)
					( objectStatus "C7A17.1" )
				)
				( pin "b"
					( attribute "PN" "2"
						( Origin gPackager )
					)
					( objectStatus "C7A17.2" )
				)
			)
			( gate "@baseboard_fab2_lib.baseboard_fab2(sch_1):page219_i55"
				( attribute "CDS_LIB" "mstr_discrete"
					( Origin gPackager )
				)
				( attribute "CDS_LOCATION" "L7A1"
					( Origin gPackager )
				)
				( attribute "CDS_SEC" "1"
					( Origin gPackager )
				)
				( attribute "LOCATION" "L7A1"
					( Origin gFrontEnd )
				)
				( attribute "MATERIAL" "IND"
					( Origin gFrontEnd )
				)
				( attribute "PACK_TYPE" "SM"
					( Origin gFrontEnd )
				)
				( attribute "PART_NUMBER" "D92183-034"
					( Origin gFrontEnd )
				)
				( attribute "PHYS_PAGE" "219"
					( Origin gFrontEnd )
				)
				( attribute "ROOM" "VDDQ_DEF_PWR_VR"
					( Origin gFrontEnd )
				)
				( attribute "ROT" "0"
					( Origin gFrontEnd )
				)
				( attribute "SEC" "1"
					( Origin gPackager )
				)
				( attribute "VALUE" "0.12UH"
					( Origin gFrontEnd )
				)
				( attribute "VER" "1"
					( Origin gFrontEnd )
				)
				( attribute "XY" "(3400,1775)"
					( Origin gFrontEnd )
				)
				( attribute "CHIPS_PART_NAME" "INDUCTOR"
					( Origin gPackager )
				)
				( attribute "CDS_PART_NAME" "INDUCTOR_SM-0.12UH,IND,D92183-A"
					( Origin gPackager )
				)
				( objectStatus "L7A1" )
				( pin "ina"
					( attribute "PN" "1"
						( Origin gPackager )
					)
					( objectStatus "L7A1.1" )
				)
				( pin "inb"
					( attribute "PN" "2"
						( Origin gPackager )
					)
					( objectStatus "L7A1.2" )
				)
			)
			( gate "@baseboard_fab2_lib.baseboard_fab2(sch_1):page219_i65"
				( attribute "CDS_LIB" "mstr_discrete"
					( Origin gPackager )
				)
				( attribute "CDS_LOCATION" "L7A3"
					( Origin gPackager )
				)
				( attribute "CDS_SEC" "1"
					( Origin gPackager )
				)
				( attribute "LOCATION" "L7A3"
					( Origin gFrontEnd )
				)
				( attribute "MATERIAL" "IND"
					( Origin gFrontEnd )
				)
				( attribute "PACK_TYPE" "SM"
					( Origin gFrontEnd )
				)
				( attribute "PART_NUMBER" "D92183-034"
					( Origin gFrontEnd )
				)
				( attribute "PHYS_PAGE" "219"
					( Origin gFrontEnd )
				)
				( attribute "ROOM" "VDDQ_DEF_PWR_VR"
					( Origin gFrontEnd )
				)
				( attribute "ROT" "0"
					( Origin gFrontEnd )
				)
				( attribute "SEC" "1"
					( Origin gFrontEnd )
				)
				( attribute "SEC_TYPE" "SM"
					( Origin gFrontEnd )
				)
				( attribute "VALUE" "0.12UH"
					( Origin gFrontEnd )
				)
				( attribute "VER" "1"
					( Origin gFrontEnd )
				)
				( attribute "XY" "(3175,-350)"
					( Origin gFrontEnd )
				)
				( attribute "CHIPS_PART_NAME" "INDUCTOR"
					( Origin gPackager )
				)
				( attribute "CDS_PART_NAME" "INDUCTOR_SM-0.12UH,IND,D92183-A"
					( Origin gPackager )
				)
				( objectStatus "L7A3" )
				( pin "ina"
					( attribute "PN" "1"
						( Origin gPackager )
					)
					( objectStatus "L7A3.1" )
				)
				( pin "inb"
					( attribute "PN" "2"
						( Origin gPackager )
					)
					( objectStatus "L7A3.2" )
				)
			)
			( gate "@baseboard_fab2_lib.baseboard_fab2(sch_1):page219_i68"
				( attribute "BOM_COST" "PROC_VRD_VCCIN_CPU0"
					( Origin gFrontEnd )
				)
				( attribute "CDS_LIB" "mstr_discrete"
					( Origin gPackager )
				)
				( attribute "CDS_LOCATION" "C6A4"
					( Origin gPackager )
				)
				( attribute "CDS_SEC" "1"
					( Origin gPackager )
				)
				( attribute "LOCATION" "C6A4"
					( Origin gFrontEnd )
				)
				( attribute "MATERIAL" "X6S"
					( Origin gFrontEnd )
				)
				( attribute "PACK_TYPE" "0805LF"
					( Origin gFrontEnd )
				)
				( attribute "PART_NUMBER" "C95333-002"
					( Origin gFrontEnd )
				)
				( attribute "PHYS_PAGE" "219"
					( Origin gFrontEnd )
				)
				( attribute "ROOM" "VDDQ_DEF_PWR_VR"
					( Origin gFrontEnd )
				)
				( attribute "ROT" "0"
					( Origin gFrontEnd )
				)
				( attribute "SEC" "1"
					( Origin gFrontEnd )
				)
				( attribute "SEC_TYPE" "0805LF"
					( Origin gFrontEnd )
				)
				( attribute "TOLERANCE" "20%"
					( Origin gFrontEnd )
				)
				( attribute "VALUE" "22UF"
					( Origin gFrontEnd )
				)
				( attribute "VER" "1"
					( Origin gFrontEnd )
				)
				( attribute "VOLTAGE" "4V"
					( Units "uVoltage" "V" 1.000000)
					( Origin gFrontEnd )
				)
				( attribute "XY" "(4100,-550)"
					( Origin gFrontEnd )
				)
				( attribute "CHIPS_PART_NAME" "CAP"
					( Origin gPackager )
				)
				( attribute "CDS_PART_NAME" "CAP_0805LF-22UF,4V,20%,X6S,C95A"
					( Origin gPackager )
				)
				( objectStatus "C6A4" )
				( pin "a"
					( attribute "PN" "1"
						( Origin gPackager )
					)
					( objectStatus "C6A4.1" )
				)
				( pin "b"
					( attribute "PN" "2"
						( Origin gPackager )
					)
					( objectStatus "C6A4.2" )
				)
			)
			( gate "@baseboard_fab2_lib.baseboard_fab2(sch_1):page219_i72"
				( attribute "CDS_LIB" "mstr_discrete"
					( Origin gPackager )
				)
				( attribute "CDS_LOCATION" "C7A25"
					( Origin gPackager )
				)
				( attribute "CDS_SEC" "1"
					( Origin gPackager )
				)
				( attribute "LOCATION" "C7A25"
					( Origin gFrontEnd )
				)
				( attribute "MATERIAL" "X7R"
					( Origin gFrontEnd )
				)
				( attribute "PACK_TYPE" "0402"
					( Origin gFrontEnd )
				)
				( attribute "PART_NUMBER" "A36096-155"
					( Origin gFrontEnd )
				)
				( attribute "PHYS_PAGE" "219"
					( Origin gFrontEnd )
				)
				( attribute "ROOM" "VDDQ_DEF_PWR_VR"
					( Origin gFrontEnd )
				)
				( attribute "ROT" "0"
					( Origin gFrontEnd )
				)
				( attribute "SEC" "1"
					( Origin gFrontEnd )
				)
				( attribute "SEC_TYPE" "0402"
					( Origin gFrontEnd )
				)
				( attribute "TOLERANCE" "10%"
					( Origin gFrontEnd )
				)
				( attribute "VALUE" "0.22UF"
					( Origin gFrontEnd )
				)
				( attribute "VER" "1"
					( Origin gFrontEnd )
				)
				( attribute "VOLTAGE" "16V"
					( Units "uVoltage" "V" 1.000000)
					( Origin gFrontEnd )
				)
				( attribute "XY" "(-550,250)"
					( Origin gFrontEnd )
				)
				( attribute "CHIPS_PART_NAME" "CAP"
					( Origin gPackager )
				)
				( attribute "CDS_PART_NAME" "CAP_0402-0.22UF,16V,10%,X7R,A3A"
					( Origin gPackager )
				)
				( objectStatus "C7A25" )
				( pin "a"
					( attribute "PN" "1"
						( Origin gPackager )
					)
					( objectStatus "C7A25.1" )
				)
				( pin "b"
					( attribute "PN" "2"
						( Origin gPackager )
					)
					( objectStatus "C7A25.2" )
				)
			)
			( gate "@baseboard_fab2_lib.baseboard_fab2(sch_1):page219_i73"
				( attribute "CDS_LIB" "dev_discrete"
					( Origin gPackager )
				)
				( attribute "CDS_LOCATION" "C7A26"
					( Origin gPackager )
				)
				( attribute "CDS_SEC" "1"
					( Origin gPackager )
				)
				( attribute "LOCATION" "C7A26"
					( Origin gFrontEnd )
				)
				( attribute "MATERIAL" "X6S"
					( Origin gFrontEnd )
				)
				( attribute "PACK_TYPE" "0402V"
					( Origin gFrontEnd )
				)
				( attribute "PART_NUMBER" "D97712-004"
					( Origin gFrontEnd )
				)
				( attribute "PHYS_PAGE" "219"
					( Origin gFrontEnd )
				)
				( attribute "ROOM" "VDDQ_DEF_PWR_VR"
					( Origin gFrontEnd )
				)
				( attribute "ROT" "2"
					( Origin gFrontEnd )
				)
				( attribute "SEC" "1"
					( Origin gFrontEnd )
				)
				( attribute "SEC_TYPE" "0402V"
					( Origin gFrontEnd )
				)
				( attribute "TOLERANCE" "10%"
					( Origin gFrontEnd )
				)
				( attribute "VALUE" "1.0UF"
					( Origin gFrontEnd )
				)
				( attribute "VER" "1"
					( Origin gFrontEnd )
				)
				( attribute "VOLTAGE" "6.3V"
					( Units "uVoltage" "V" 1.000000)
					( Origin gFrontEnd )
				)
				( attribute "XY" "(-725,250)"
					( Origin gFrontEnd )
				)
				( attribute "CHIPS_PART_NAME" "CAP_A"
					( Origin gPackager )
				)
				( attribute "CDS_PART_NAME" "CAP_A_0402V-1.0UF,6.3V,10%,X6SA"
					( Origin gPackager )
				)
				( objectStatus "C7A26" )
				( pin "a"
					( attribute "PN" "1"
						( Origin gPackager )
					)
					( objectStatus "C7A26.1" )
				)
				( pin "b"
					( attribute "PN" "2"
						( Origin gPackager )
					)
					( objectStatus "C7A26.2" )
				)
			)
			( gate "@baseboard_fab2_lib.baseboard_fab2(sch_1):page219_i75"
				( attribute "CDS_LIB" "mstr_discrete"
					( Origin gPackager )
				)
				( attribute "CDS_LOCATION" "C7A22"
					( Origin gPackager )
				)
				( attribute "CDS_SEC" "1"
					( Origin gPackager )
				)
				( attribute "LOCATION" "C7A22"
					( Origin gFrontEnd )
				)
				( attribute "MATERIAL" "X7R"
					( Origin gFrontEnd )
				)
				( attribute "PACK_TYPE" "0402"
					( Origin gFrontEnd )
				)
				( attribute "PART_NUMBER" "A36096-104"
					( Origin gFrontEnd )
				)
				( attribute "PHYS_PAGE" "219"
					( Origin gFrontEnd )
				)
				( attribute "ROOM" "VDDQ_DEF_PWR_VR"
					( Origin gFrontEnd )
				)
				( attribute "ROT" "2"
					( Origin gFrontEnd )
				)
				( attribute "SEC" "1"
					( Origin gPackager )
				)
				( attribute "SPOF" "TRUE"
					( Origin gFrontEnd )
				)
				( attribute "TOLERANCE" "10%"
					( Origin gFrontEnd )
				)
				( attribute "VALUE" "0.220UF"
					( Origin gFrontEnd )
				)
				( attribute "VER" "1"
					( Origin gFrontEnd )
				)
				( attribute "VOLTAGE" "16V"
					( Units "uVoltage" "V" 1.000000)
					( Origin gFrontEnd )
				)
				( attribute "XY" "(-1000,-450)"
					( Origin gFrontEnd )
				)
				( attribute "CHIPS_PART_NAME" "CAP"
					( Origin gPackager )
				)
				( attribute "CDS_PART_NAME" "CAP_0402-0.220UF,16V,10%,X7R,AA"
					( Origin gPackager )
				)
				( objectStatus "C7A22" )
				( pin "a"
					( attribute "PN" "1"
						( Origin gPackager )
					)
					( objectStatus "C7A22.1" )
				)
				( pin "b"
					( attribute "PN" "2"
						( Origin gPackager )
					)
					( objectStatus "C7A22.2" )
				)
			)
			( gate "@baseboard_fab2_lib.baseboard_fab2(sch_1):page219_i76"
				( attribute "CDS_LIB" "mstr_discrete"
					( Origin gPackager )
				)
				( attribute "CDS_LOCATION" "R3L8"
					( Origin gPackager )
				)
				( attribute "CDS_SEC" "1"
					( Origin gPackager )
				)
				( attribute "LOCATION" "R3L8"
					( Origin gFrontEnd )
				)
				( attribute "MATERIAL" "CHIP"
					( Origin gFrontEnd )
				)
				( attribute "PACK_TYPE" "0402"
					( Origin gFrontEnd )
				)
				( attribute "PART_NUMBER" "G21796-090"
					( Origin gFrontEnd )
				)
				( attribute "PHYS_PAGE" "219"
					( Origin gFrontEnd )
				)
				( attribute "ROOM" "VDDQ_DEF_PWR_VR"
					( Origin gFrontEnd )
				)
				( attribute "ROT" "0"
					( Origin gFrontEnd )
				)
				( attribute "SEC" "1"
					( Origin gFrontEnd )
				)
				( attribute "SEC_TYPE" "0402"
					( Origin gFrontEnd )
				)
				( attribute "TOLERANCE" "1%"
					( Origin gFrontEnd )
				)
				( attribute "VALUE" "1.0"
					( Origin gFrontEnd )
				)
				( attribute "VER" "1"
					( Origin gFrontEnd )
				)
				( attribute "WATTAGE" "1/16W"
					( Origin gFrontEnd )
				)
				( attribute "XY" "(-1100,775)"
					( Origin gFrontEnd )
				)
				( attribute "CHIPS_PART_NAME" "RES"
					( Origin gPackager )
				)
				( attribute "CDS_PART_NAME" "RES_0402-1.0,1%,1/16W,CHIP,G21A"
					( Origin gPackager )
				)
				( objectStatus "R3L8" )
				( pin "a"
					( attribute "PN" "1"
						( Origin gPackager )
					)
					( objectStatus "R3L8.1" )
				)
				( pin "b"
					( attribute "PN" "2"
						( Origin gPackager )
					)
					( objectStatus "R3L8.2" )
				)
			)
			( gate "@baseboard_fab2_lib.baseboard_fab2(sch_1):page219_i77"
				( attribute "CDS_LIB" "mstr_discrete"
					( Origin gPackager )
				)
				( attribute "CDS_LOCATION" "C7A24"
					( Origin gPackager )
				)
				( attribute "CDS_SEC" "1"
					( Origin gPackager )
				)
				( attribute "LOCATION" "C7A24"
					( Origin gFrontEnd )
				)
				( attribute "MATERIAL" "X6S"
					( Origin gFrontEnd )
				)
				( attribute "PACK_TYPE" "0402"
					( Origin gFrontEnd )
				)
				( attribute "PART_NUMBER" "D97712-011"
					( Origin gFrontEnd )
				)
				( attribute "PHYS_PAGE" "219"
					( Origin gFrontEnd )
				)
				( attribute "ROOM" "VDDQ_DEF_PWR_VR"
					( Origin gFrontEnd )
				)
				( attribute "ROT" "0"
					( Origin gFrontEnd )
				)
				( attribute "SEC" "1"
					( Origin gFrontEnd )
				)
				( attribute "SEC_TYPE" "0402"
					( Origin gFrontEnd )
				)
				( attribute "TOLERANCE" "10%"
					( Origin gFrontEnd )
				)
				( attribute "VALUE" "1.0UF"
					( Origin gFrontEnd )
				)
				( attribute "VER" "1"
					( Origin gFrontEnd )
				)
				( attribute "VOLTAGE" "16V"
					( Units "uVoltage" "V" 1.000000)
					( Origin gFrontEnd )
				)
				( attribute "XY" "(-1400,150)"
					( Origin gFrontEnd )
				)
				( attribute "CHIPS_PART_NAME" "CAP"
					( Origin gPackager )
				)
				( attribute "CDS_PART_NAME" "CAP_0402-1.0UF,16V,10%,X6S,D97A"
					( Origin gPackager )
				)
				( objectStatus "C7A24" )
				( pin "a"
					( attribute "PN" "1"
						( Origin gPackager )
					)
					( objectStatus "C7A24.1" )
				)
				( pin "b"
					( attribute "PN" "2"
						( Origin gPackager )
					)
					( objectStatus "C7A24.2" )
				)
			)
			( gate "@baseboard_fab2_lib.baseboard_fab2(sch_1):page219_i78"
				( attribute "CDS_LIB" "dev_discrete"
					( Origin gPackager )
				)
				( attribute "CDS_LOCATION" "C7A20"
					( Origin gPackager )
				)
				( attribute "CDS_SEC" "1"
					( Origin gPackager )
				)
				( attribute "LOCATION" "C7A20"
					( Origin gFrontEnd )
				)
				( attribute "MATERIAL" "X7R"
					( Origin gFrontEnd )
				)
				( attribute "PACK_TYPE" "0402V"
					( Origin gFrontEnd )
				)
				( attribute "PART_NUMBER" "A36096-030"
					( Origin gFrontEnd )
				)
				( attribute "PHYS_PAGE" "219"
					( Origin gFrontEnd )
				)
				( attribute "ROOM" "VDDQ_DEF_PWR_VR"
					( Origin gFrontEnd )
				)
				( attribute "ROT" "0"
					( Origin gFrontEnd )
				)
				( attribute "SEC" "1"
					( Origin gFrontEnd )
				)
				( attribute "SEC_TYPE" "0402V"
					( Origin gFrontEnd )
				)
				( attribute "TOLERANCE" "10%"
					( Origin gFrontEnd )
				)
				( attribute "VALUE" "0.1UF"
					( Origin gFrontEnd )
				)
				( attribute "VER" "1"
					( Origin gFrontEnd )
				)
				( attribute "VOLTAGE" "16V"
					( Units "uVoltage" "V" 1.000000)
					( Origin gFrontEnd )
				)
				( attribute "XY" "(-1675,125)"
					( Origin gFrontEnd )
				)
				( attribute "CHIPS_PART_NAME" "CAP_A"
					( Origin gPackager )
				)
				( attribute "CDS_PART_NAME" "CAP_A_0402V-0.1UF,16V,10%,X7R,A"
					( Origin gPackager )
				)
				( objectStatus "C7A20" )
				( pin "a"
					( attribute "PN" "1"
						( Origin gPackager )
					)
					( objectStatus "C7A20.1" )
				)
				( pin "b"
					( attribute "PN" "2"
						( Origin gPackager )
					)
					( objectStatus "C7A20.2" )
				)
			)
			( gate "@baseboard_fab2_lib.baseboard_fab2(sch_1):page219_i79"
				( attribute "CDS_LIB" "mstr_discrete"
					( Origin gPackager )
				)
				( attribute "CDS_LOCATION" "C7A21"
					( Origin gPackager )
				)
				( attribute "CDS_SEC" "1"
					( Origin gPackager )
				)
				( attribute "LOCATION" "C7A21"
					( Origin gFrontEnd )
				)
				( attribute "MATERIAL" "X6S"
					( Origin gFrontEnd )
				)
				( attribute "PACK_TYPE" "0402"
					( Origin gFrontEnd )
				)
				( attribute "PART_NUMBER" "D97712-011"
					( Origin gFrontEnd )
				)
				( attribute "PHYS_PAGE" "219"
					( Origin gFrontEnd )
				)
				( attribute "ROOM" "VDDQ_DEF_PWR_VR"
					( Origin gFrontEnd )
				)
				( attribute "ROT" "0"
					( Origin gFrontEnd )
				)
				( attribute "SEC" "1"
					( Origin gFrontEnd )
				)
				( attribute "SEC_TYPE" "0402"
					( Origin gFrontEnd )
				)
				( attribute "TOLERANCE" "10%"
					( Origin gFrontEnd )
				)
				( attribute "VALUE" "1.0UF"
					( Origin gFrontEnd )
				)
				( attribute "VER" "1"
					( Origin gFrontEnd )
				)
				( attribute "VOLTAGE" "16V"
					( Units "uVoltage" "V" 1.000000)
					( Origin gFrontEnd )
				)
				( attribute "XY" "(-1925,125)"
					( Origin gFrontEnd )
				)
				( attribute "CHIPS_PART_NAME" "CAP"
					( Origin gPackager )
				)
				( attribute "CDS_PART_NAME" "CAP_0402-1.0UF,16V,10%,X6S,D97A"
					( Origin gPackager )
				)
				( objectStatus "C7A21" )
				( pin "a"
					( attribute "PN" "1"
						( Origin gPackager )
					)
					( objectStatus "C7A21.1" )
				)
				( pin "b"
					( attribute "PN" "2"
						( Origin gPackager )
					)
					( objectStatus "C7A21.2" )
				)
			)
			( gate "@baseboard_fab2_lib.baseboard_fab2(sch_1):page219_i80"
				( attribute "CDS_LIB" "mstr_discrete"
					( Origin gPackager )
				)
				( attribute "CDS_LOCATION" "C3L17"
					( Origin gPackager )
				)
				( attribute "CDS_SEC" "1"
					( Origin gPackager )
				)
				( attribute "LOCATION" "C3L17"
					( Origin gFrontEnd )
				)
				( attribute "MATERIAL" "X6S"
					( Origin gFrontEnd )
				)
				( attribute "PACK_TYPE" "0805"
					( Origin gFrontEnd )
				)
				( attribute "PART_NUMBER" "C95333-007"
					( Origin gFrontEnd )
				)
				( attribute "PHYS_PAGE" "219"
					( Origin gFrontEnd )
				)
				( attribute "ROOM" "VDDQ_DEF_PWR_VR"
					( Origin gFrontEnd )
				)
				( attribute "ROT" "0"
					( Origin gFrontEnd )
				)
				( attribute "SEC" "1"
					( Origin gFrontEnd )
				)
				( attribute "SEC_TYPE" "0805"
					( Origin gFrontEnd )
				)
				( attribute "TOLERANCE" "10%"
					( Origin gFrontEnd )
				)
				( attribute "VALUE" "10UF"
					( Origin gFrontEnd )
				)
				( attribute "VER" "1"
					( Origin gFrontEnd )
				)
				( attribute "VOLTAGE" "16V"
					( Units "uVoltage" "V" 1.000000)
					( Origin gFrontEnd )
				)
				( attribute "XY" "(-2175,125)"
					( Origin gFrontEnd )
				)
				( attribute "CHIPS_PART_NAME" "CAP"
					( Origin gPackager )
				)
				( attribute "CDS_PART_NAME" "CAP_0805-10UF,16V,10%,X6S,C953A"
					( Origin gPackager )
				)
				( objectStatus "C3L17" )
				( pin "a"
					( attribute "PN" "1"
						( Origin gPackager )
					)
					( objectStatus "C3L17.1" )
				)
				( pin "b"
					( attribute "PN" "2"
						( Origin gPackager )
					)
					( objectStatus "C3L17.2" )
				)
			)
			( gate "@baseboard_fab2_lib.baseboard_fab2(sch_1):page219_i81"
				( attribute "CDS_LIB" "mstr_discrete"
					( Origin gPackager )
				)
				( attribute "CDS_LOCATION" "C3L16"
					( Origin gPackager )
				)
				( attribute "CDS_SEC" "1"
					( Origin gPackager )
				)
				( attribute "LOCATION" "C3L16"
					( Origin gFrontEnd )
				)
				( attribute "MATERIAL" "X6S"
					( Origin gFrontEnd )
				)
				( attribute "PACK_TYPE" "0805"
					( Origin gFrontEnd )
				)
				( attribute "PART_NUMBER" "C95333-007"
					( Origin gFrontEnd )
				)
				( attribute "PHYS_PAGE" "219"
					( Origin gFrontEnd )
				)
				( attribute "ROOM" "VDDQ_DEF_PWR_VR"
					( Origin gFrontEnd )
				)
				( attribute "ROT" "0"
					( Origin gFrontEnd )
				)
				( attribute "SEC" "1"
					( Origin gFrontEnd )
				)
				( attribute "SEC_TYPE" "0805"
					( Origin gFrontEnd )
				)
				( attribute "TOLERANCE" "10%"
					( Origin gFrontEnd )
				)
				( attribute "VALUE" "10UF"
					( Origin gFrontEnd )
				)
				( attribute "VER" "1"
					( Origin gFrontEnd )
				)
				( attribute "VOLTAGE" "16V"
					( Units "uVoltage" "V" 1.000000)
					( Origin gFrontEnd )
				)
				( attribute "XY" "(-2425,125)"
					( Origin gFrontEnd )
				)
				( attribute "CHIPS_PART_NAME" "CAP"
					( Origin gPackager )
				)
				( attribute "CDS_PART_NAME" "CAP_0805-10UF,16V,10%,X6S,C953A"
					( Origin gPackager )
				)
				( objectStatus "C3L16" )
				( pin "a"
					( attribute "PN" "1"
						( Origin gPackager )
					)
					( objectStatus "C3L16.1" )
				)
				( pin "b"
					( attribute "PN" "2"
						( Origin gPackager )
					)
					( objectStatus "C3L16.2" )
				)
			)
			( gate "@baseboard_fab2_lib.baseboard_fab2(sch_1):page219_i84"
				( attribute "CDS_LIB" "mstr_discrete"
					( Origin gPackager )
				)
				( attribute "CDS_LOCATION" "C3L15"
					( Origin gPackager )
				)
				( attribute "CDS_SEC" "1"
					( Origin gPackager )
				)
				( attribute "LOCATION" "C3L15"
					( Origin gFrontEnd )
				)
				( attribute "MATERIAL" "X6S"
					( Origin gFrontEnd )
				)
				( attribute "PACK_TYPE" "0805"
					( Origin gFrontEnd )
				)
				( attribute "PART_NUMBER" "C95333-007"
					( Origin gFrontEnd )
				)
				( attribute "PHYS_PAGE" "219"
					( Origin gFrontEnd )
				)
				( attribute "ROOM" "VDDQ_DEF_PWR_VR"
					( Origin gFrontEnd )
				)
				( attribute "ROT" "0"
					( Origin gFrontEnd )
				)
				( attribute "SEC" "1"
					( Origin gFrontEnd )
				)
				( attribute "SEC_TYPE" "0805"
					( Origin gFrontEnd )
				)
				( attribute "TOLERANCE" "10%"
					( Origin gFrontEnd )
				)
				( attribute "VALUE" "10UF"
					( Origin gFrontEnd )
				)
				( attribute "VER" "1"
					( Origin gFrontEnd )
				)
				( attribute "VOLTAGE" "16V"
					( Units "uVoltage" "V" 1.000000)
					( Origin gFrontEnd )
				)
				( attribute "XY" "(-2675,125)"
					( Origin gFrontEnd )
				)
				( attribute "CHIPS_PART_NAME" "CAP"
					( Origin gPackager )
				)
				( attribute "CDS_PART_NAME" "CAP_0805-10UF,16V,10%,X6S,C953A"
					( Origin gPackager )
				)
				( objectStatus "C3L15" )
				( pin "a"
					( attribute "PN" "1"
						( Origin gPackager )
					)
					( objectStatus "C3L15.1" )
				)
				( pin "b"
					( attribute "PN" "2"
						( Origin gPackager )
					)
					( objectStatus "C3L15.2" )
				)
			)
			( gate "@baseboard_fab2_lib.baseboard_fab2(sch_1):page219_i87"
				( attribute "BOM_COST" "PROC_VRD_VCCIN_CPU0"
					( Origin gFrontEnd )
				)
				( attribute "CDS_LIB" "mstr_discrete"
					( Origin gPackager )
				)
				( attribute "CDS_LOCATION" "C6A1"
					( Origin gPackager )
				)
				( attribute "CDS_SEC" "1"
					( Origin gPackager )
				)
				( attribute "LOCATION" "C6A1"
					( Origin gFrontEnd )
				)
				( attribute "MATERIAL" "X6S"
					( Origin gFrontEnd )
				)
				( attribute "PACK_TYPE" "0805LF"
					( Origin gFrontEnd )
				)
				( attribute "PART_NUMBER" "C95333-002"
					( Origin gFrontEnd )
				)
				( attribute "PHYS_PAGE" "219"
					( Origin gFrontEnd )
				)
				( attribute "ROOM" "VDDQ_DEF_PWR_VR"
					( Origin gFrontEnd )
				)
				( attribute "ROT" "0"
					( Origin gFrontEnd )
				)
				( attribute "SEC" "1"
					( Origin gPackager )
				)
				( attribute "TOLERANCE" "20%"
					( Origin gFrontEnd )
				)
				( attribute "VALUE" "22UF"
					( Origin gFrontEnd )
				)
				( attribute "VER" "1"
					( Origin gFrontEnd )
				)
				( attribute "VOLTAGE" "4V"
					( Units "uVoltage" "V" 1.000000)
					( Origin gFrontEnd )
				)
				( attribute "XY" "(4075,1575)"
					( Origin gFrontEnd )
				)
				( attribute "CHIPS_PART_NAME" "CAP"
					( Origin gPackager )
				)
				( attribute "CDS_PART_NAME" "CAP_0805LF-22UF,4V,20%,X6S,C95A"
					( Origin gPackager )
				)
				( objectStatus "C6A1" )
				( pin "a"
					( attribute "PN" "1"
						( Origin gPackager )
					)
					( objectStatus "C6A1.1" )
				)
				( pin "b"
					( attribute "PN" "2"
						( Origin gPackager )
					)
					( objectStatus "C6A1.2" )
				)
			)
			( gate "@baseboard_fab2_lib.baseboard_fab2(sch_1):page219_i106"
				( attribute "CDS_LIB" "mstr_discrete"
					( Origin gPackager )
				)
				( attribute "CDS_LOCATION" "EU7A1"
					( Origin gPackager )
				)
				( attribute "CDS_SEC" "1"
					( Origin gPackager )
				)
				( attribute "LOCATION" "EU7A1"
					( Origin gFrontEnd )
				)
				( attribute "MATERIAL" "IC"
					( Origin gFrontEnd )
				)
				( attribute "NO_XNET_CONNECTION" "1"
					( Origin gFrontEnd )
				)
				( attribute "PACK_TYPE" "SM"
					( Origin gFrontEnd )
				)
				( attribute "PART_NUMBER" "H73688-001"
					( Origin gFrontEnd )
				)
				( attribute "PHYS_PAGE" "219"
					( Origin gFrontEnd )
				)
				( attribute "ROT" "0"
					( Origin gFrontEnd )
				)
				( attribute "SEC" "1"
					( Origin gFrontEnd )
				)
				( attribute "SEC_TYPE" "SM"
					( Origin gFrontEnd )
				)
				( attribute "VALUE" "IR35411"
					( Origin gFrontEnd )
				)
				( attribute "VER" "1"
					( Origin gFrontEnd )
				)
				( attribute "XY" "(1550,2075)"
					( Origin gFrontEnd )
				)
				( attribute "CHIPS_PART_NAME" "IR354XX"
					( Origin gPackager )
				)
				( attribute "CDS_PART_NAME" "IR354XX_SM-IR35411,IC,H73688-0A"
					( Origin gPackager )
				)
				( objectStatus "EU7A1" )
				( pin "boost"
					( attribute "PN" "33"
						( Origin gPackager )
					)
					( objectStatus "EU7A1.33" )
				)
				( pin "en"
					( attribute "PN" "35"
						( Origin gPackager )
					)
					( objectStatus "EU7A1.35" )
				)
				( pin "gl(0)"
					( attribute "PN" "6"
						( Origin gPackager )
					)
					( objectStatus "EU7A1.6" )
				)
				( pin "gl(1)"
					( attribute "PN" "41"
						( Origin gPackager )
					)
					( objectStatus "EU7A1.41" )
				)
				( pin "iout"
					( attribute "PN" "38"
						( Origin gPackager )
					)
					( objectStatus "EU7A1.38" )
				)
				( pin "lgnd"
					( attribute "PN" "2"
						( Origin gPackager )
					)
					( objectStatus "EU7A1.2" )
				)
				( pin "nc"
					( attribute "PN" "31"
						( Origin gPackager )
					)
					( objectStatus "EU7A1.31" )
				)
				( pin "ocset"
					( attribute "PN" "37"
						( Origin gPackager )
					)
					( objectStatus "EU7A1.37" )
				)
				( pin "pgnd(0)"
					( attribute "PN" "5"
						( Origin gPackager )
					)
					( objectStatus "EU7A1.5" )
				)
				( pin "pgnd(1)"
					( attribute "PN" "7"
						( Origin gPackager )
					)
					( objectStatus "EU7A1.7" )
				)
				( pin "pgnd(2)"
					( attribute "PN" "40"
						( Origin gPackager )
					)
					( objectStatus "EU7A1.40" )
				)
				( pin "phase"
					( attribute "PN" "32"
						( Origin gPackager )
					)
					( objectStatus "EU7A1.32" )
				)
				( pin "pwm"
					( attribute "PN" "34"
						( Origin gPackager )
					)
					( objectStatus "EU7A1.34" )
				)
				( pin "refin"
					( attribute "PN" "39"
						( Origin gPackager )
					)
					( objectStatus "EU7A1.39" )
				)
				( pin "sw"
					( attribute "PN" "10"
						( Origin gPackager )
					)
					( objectStatus "EU7A1.10" )
				)
				( pin "tout_flt"
					( attribute "PN" "36"
						( Origin gPackager )
					)
					( objectStatus "EU7A1.36" )
				)
				( pin "vcc"
					( attribute "PN" "3"
						( Origin gPackager )
					)
					( objectStatus "EU7A1.3" )
				)
				( pin "vdrv"
					( attribute "PN" "4"
						( Origin gPackager )
					)
					( objectStatus "EU7A1.4" )
				)
				( pin "vin(0)"
					( attribute "PN" "25"
						( Origin gPackager )
					)
					( objectStatus "EU7A1.25" )
				)
				( pin "vin(1)"
					( attribute "PN" "30"
						( Origin gPackager )
					)
					( objectStatus "EU7A1.30" )
				)
				( pin "vos"
					( attribute "PN" "1"
						( Origin gPackager )
					)
					( objectStatus "EU7A1.1" )
				)
			)
			( gate "@baseboard_fab2_lib.baseboard_fab2(sch_1):page219_i107"
				( attribute "CDS_LIB" "mstr_discrete"
					( Origin gPackager )
				)
				( attribute "CDS_LOCATION" "EU7A4"
					( Origin gPackager )
				)
				( attribute "CDS_SEC" "1"
					( Origin gPackager )
				)
				( attribute "LOCATION" "EU7A4"
					( Origin gFrontEnd )
				)
				( attribute "MATERIAL" "IC"
					( Origin gFrontEnd )
				)
				( attribute "NO_XNET_CONNECTION" "1"
					( Origin gFrontEnd )
				)
				( attribute "PACK_TYPE" "SM"
					( Origin gFrontEnd )
				)
				( attribute "PART_NUMBER" "H73688-001"
					( Origin gFrontEnd )
				)
				( attribute "PHYS_PAGE" "219"
					( Origin gFrontEnd )
				)
				( attribute "ROT" "0"
					( Origin gFrontEnd )
				)
				( attribute "SEC" "1"
					( Origin gFrontEnd )
				)
				( attribute "SEC_TYPE" "SM"
					( Origin gFrontEnd )
				)
				( attribute "VALUE" "IR35411"
					( Origin gFrontEnd )
				)
				( attribute "VER" "1"
					( Origin gFrontEnd )
				)
				( attribute "XY" "(1575,-50)"
					( Origin gFrontEnd )
				)
				( attribute "CHIPS_PART_NAME" "IR354XX"
					( Origin gPackager )
				)
				( attribute "CDS_PART_NAME" "IR354XX_SM-IR35411,IC,H73688-0A"
					( Origin gPackager )
				)
				( objectStatus "EU7A4" )
				( pin "boost"
					( attribute "PN" "33"
						( Origin gPackager )
					)
					( objectStatus "EU7A4.33" )
				)
				( pin "en"
					( attribute "PN" "35"
						( Origin gPackager )
					)
					( objectStatus "EU7A4.35" )
				)
				( pin "gl(0)"
					( attribute "PN" "6"
						( Origin gPackager )
					)
					( objectStatus "EU7A4.6" )
				)
				( pin "gl(1)"
					( attribute "PN" "41"
						( Origin gPackager )
					)
					( objectStatus "EU7A4.41" )
				)
				( pin "iout"
					( attribute "PN" "38"
						( Origin gPackager )
					)
					( objectStatus "EU7A4.38" )
				)
				( pin "lgnd"
					( attribute "PN" "2"
						( Origin gPackager )
					)
					( objectStatus "EU7A4.2" )
				)
				( pin "nc"
					( attribute "PN" "31"
						( Origin gPackager )
					)
					( objectStatus "EU7A4.31" )
				)
				( pin "ocset"
					( attribute "PN" "37"
						( Origin gPackager )
					)
					( objectStatus "EU7A4.37" )
				)
				( pin "pgnd(0)"
					( attribute "PN" "5"
						( Origin gPackager )
					)
					( objectStatus "EU7A4.5" )
				)
				( pin "pgnd(1)"
					( attribute "PN" "7"
						( Origin gPackager )
					)
					( objectStatus "EU7A4.7" )
				)
				( pin "pgnd(2)"
					( attribute "PN" "40"
						( Origin gPackager )
					)
					( objectStatus "EU7A4.40" )
				)
				( pin "phase"
					( attribute "PN" "32"
						( Origin gPackager )
					)
					( objectStatus "EU7A4.32" )
				)
				( pin "pwm"
					( attribute "PN" "34"
						( Origin gPackager )
					)
					( objectStatus "EU7A4.34" )
				)
				( pin "refin"
					( attribute "PN" "39"
						( Origin gPackager )
					)
					( objectStatus "EU7A4.39" )
				)
				( pin "sw"
					( attribute "PN" "10"
						( Origin gPackager )
					)
					( objectStatus "EU7A4.10" )
				)
				( pin "tout_flt"
					( attribute "PN" "36"
						( Origin gPackager )
					)
					( objectStatus "EU7A4.36" )
				)
				( pin "vcc"
					( attribute "PN" "3"
						( Origin gPackager )
					)
					( objectStatus "EU7A4.3" )
				)
				( pin "vdrv"
					( attribute "PN" "4"
						( Origin gPackager )
					)
					( objectStatus "EU7A4.4" )
				)
				( pin "vin(0)"
					( attribute "PN" "25"
						( Origin gPackager )
					)
					( objectStatus "EU7A4.25" )
				)
				( pin "vin(1)"
					( attribute "PN" "30"
						( Origin gPackager )
					)
					( objectStatus "EU7A4.30" )
				)
				( pin "vos"
					( attribute "PN" "1"
						( Origin gPackager )
					)
					( objectStatus "EU7A4.1" )
				)
			)
			( gate "@baseboard_fab2_lib.baseboard_fab2(sch_1):page219_i108"
				( attribute "CDS_LIB" "mstr_discrete"
					( Origin gPackager )
				)
				( attribute "CDS_LOCATION" "R7A20"
					( Origin gPackager )
				)
				( attribute "CDS_SEC" "1"
					( Origin gPackager )
				)
				( attribute "LOCATION" "R7A20"
					( Origin gFrontEnd )
				)
				( attribute "MATERIAL" "EMPTY"
					( Origin gFrontEnd )
				)
				( attribute "PACK_TYPE" "0402"
					( Origin gFrontEnd )
				)
				( attribute "PART_NUMBER" "G21796-187"
					( Origin gFrontEnd )
				)
				( attribute "PHYS_PAGE" "219"
					( Origin gFrontEnd )
				)
				( attribute "ROT" "0"
					( Origin gFrontEnd )
				)
				( attribute "SEC" "1"
					( Origin gPackager )
				)
				( attribute "TOLERANCE" "1%"
					( Origin gFrontEnd )
				)
				( attribute "VALUE" "68.1K"
					( Origin gFrontEnd )
				)
				( attribute "VER" "2"
					( Origin gFrontEnd )
				)
				( attribute "WATTAGE" "1/16W"
					( Origin gFrontEnd )
				)
				( attribute "XY" "(4375,2250)"
					( Origin gFrontEnd )
				)
				( attribute "CHIPS_PART_NAME" "RES"
					( Origin gPackager )
				)
				( attribute "CDS_PART_NAME" "RES_0402-68.1K,1%,1/16W,EMPTY,A"
					( Origin gPackager )
				)
				( objectStatus "R7A20" )
				( pin "a"
					( attribute "PN" "1"
						( Origin gPackager )
					)
					( objectStatus "R7A20.1" )
				)
				( pin "b"
					( attribute "PN" "2"
						( Origin gPackager )
					)
					( objectStatus "R7A20.2" )
				)
			)
			( gate "@baseboard_fab2_lib.baseboard_fab2(sch_1):page219_i110"
				( attribute "CDS_LIB" "mstr_discrete"
					( Origin gPackager )
				)
				( attribute "CDS_LOCATION" "R7A21"
					( Origin gPackager )
				)
				( attribute "CDS_SEC" "1"
					( Origin gPackager )
				)
				( attribute "LOCATION" "R7A21"
					( Origin gFrontEnd )
				)
				( attribute "MATERIAL" "EMPTY"
					( Origin gFrontEnd )
				)
				( attribute "PACK_TYPE" "0402"
					( Origin gFrontEnd )
				)
				( attribute "PART_NUMBER" "G21796-187"
					( Origin gFrontEnd )
				)
				( attribute "PHYS_PAGE" "219"
					( Origin gFrontEnd )
				)
				( attribute "ROT" "0"
					( Origin gFrontEnd )
				)
				( attribute "SEC" "1"
					( Origin gPackager )
				)
				( attribute "TOLERANCE" "1%"
					( Origin gFrontEnd )
				)
				( attribute "VALUE" "68.1K"
					( Origin gFrontEnd )
				)
				( attribute "VER" "2"
					( Origin gFrontEnd )
				)
				( attribute "WATTAGE" "1/16W"
					( Origin gFrontEnd )
				)
				( attribute "XY" "(4375,100)"
					( Origin gFrontEnd )
				)
				( attribute "CHIPS_PART_NAME" "RES"
					( Origin gPackager )
				)
				( attribute "CDS_PART_NAME" "RES_0402-68.1K,1%,1/16W,EMPTY,A"
					( Origin gPackager )
				)
				( objectStatus "R7A21" )
				( pin "a"
					( attribute "PN" "1"
						( Origin gPackager )
					)
					( objectStatus "R7A21.1" )
				)
				( pin "b"
					( attribute "PN" "2"
						( Origin gPackager )
					)
					( objectStatus "R7A21.2" )
				)
			)
			( gate "@baseboard_fab2_lib.baseboard_fab2(sch_1):page220_i58"
				( attribute "BOM_COST" "MEM_VRD_PVPP_DEF"
					( Origin gFrontEnd )
				)
				( attribute "CDS_LIB" "mstr_discrete"
					( Origin gPackager )
				)
				( attribute "CDS_LOCATION" "R4L4"
					( Origin gPackager )
				)
				( attribute "CDS_SEC" "1"
					( Origin gPackager )
				)
				( attribute "LOCATION" "R4L4"
					( Origin gFrontEnd )
				)
				( attribute "MATERIAL" "CHIP"
					( Origin gFrontEnd )
				)
				( attribute "PACK_TYPE" "0603"
					( Origin gFrontEnd )
				)
				( attribute "PART_NUMBER" "G22026-003"
					( Origin gFrontEnd )
				)
				( attribute "PHYS_PAGE" "220"
					( Origin gFrontEnd )
				)
				( attribute "ROOM" "VDDQ_DEF_PWR_VR"
					( Origin gFrontEnd )
				)
				( attribute "ROT" "0"
					( Origin gFrontEnd )
				)
				( attribute "SEC" "1"
					( Origin gPackager )
				)
				( attribute "TOLERANCE" "1%"
					( Origin gFrontEnd )
				)
				( attribute "VALUE" "120.0"
					( Origin gFrontEnd )
				)
				( attribute "VER" "2"
					( Origin gFrontEnd )
				)
				( attribute "WATTAGE" "1/10W"
					( Origin gFrontEnd )
				)
				( attribute "XY" "(4550,-175)"
					( Origin gFrontEnd )
				)
				( attribute "CHIPS_PART_NAME" "RES"
					( Origin gPackager )
				)
				( attribute "CDS_PART_NAME" "RES_0603-120.0,1%,1/10W,CHIP,GA"
					( Origin gPackager )
				)
				( objectStatus "R4L4" )
				( pin "a"
					( attribute "PN" "1"
						( Origin gPackager )
					)
					( objectStatus "R4L4.1" )
				)
				( pin "b"
					( attribute "PN" "2"
						( Origin gPackager )
					)
					( objectStatus "R4L4.2" )
				)
			)
			( gate "@baseboard_fab2_lib.baseboard_fab2(sch_1):page220_i74"
				( attribute "CDS_LIB" "mstr_discrete"
					( Origin gPackager )
				)
				( attribute "CDS_LOCATION" "R4L2"
					( Origin gPackager )
				)
				( attribute "CDS_SEC" "1"
					( Origin gPackager )
				)
				( attribute "LOCATION" "R4L2"
					( Origin gFrontEnd )
				)
				( attribute "MATERIAL" "EMPTY"
					( Origin gFrontEnd )
				)
				( attribute "PACK_TYPE" "0402"
					( Origin gFrontEnd )
				)
				( attribute "PART_NUMBER" "G21796-017"
					( Origin gFrontEnd )
				)
				( attribute "PHYS_PAGE" "220"
					( Origin gFrontEnd )
				)
				( attribute "ROOM" "VDDQ_DEF_PWR_VR"
					( Origin gFrontEnd )
				)
				( attribute "ROT" "0"
					( Origin gFrontEnd )
				)
				( attribute "SEC" "1"
					( Origin gFrontEnd )
				)
				( attribute "SEC_TYPE" "0402"
					( Origin gFrontEnd )
				)
				( attribute "TOLERANCE" "1%"
					( Origin gFrontEnd )
				)
				( attribute "VALUE" "100.0"
					( Origin gFrontEnd )
				)
				( attribute "VER" "2"
					( Origin gFrontEnd )
				)
				( attribute "WATTAGE" "1/16W"
					( Origin gFrontEnd )
				)
				( attribute "XY" "(-700,1825)"
					( Origin gFrontEnd )
				)
				( attribute "CHIPS_PART_NAME" "RES"
					( Origin gPackager )
				)
				( attribute "CDS_PART_NAME" "RES_0402-100.0,1%,1/16W,EMPTY,A"
					( Origin gPackager )
				)
				( objectStatus "R4L2" )
				( pin "a"
					( attribute "PN" "1"
						( Origin gPackager )
					)
					( objectStatus "R4L2.1" )
				)
				( pin "b"
					( attribute "PN" "2"
						( Origin gPackager )
					)
					( objectStatus "R4L2.2" )
				)
			)
			( gate "@baseboard_fab2_lib.baseboard_fab2(sch_1):page220_i75"
				( attribute "CDS_LIB" "mstr_discrete"
					( Origin gPackager )
				)
				( attribute "CDS_LOCATION" "C3L6"
					( Origin gPackager )
				)
				( attribute "CDS_SEC" "1"
					( Origin gPackager )
				)
				( attribute "LOCATION" "C3L6"
					( Origin gFrontEnd )
				)
				( attribute "MATERIAL" "ALUM"
					( Origin gFrontEnd )
				)
				( attribute "PACK_TYPE" "3018"
					( Origin gFrontEnd )
				)
				( attribute "PART_NUMBER" "699013-049"
					( Origin gFrontEnd )
				)
				( attribute "PHYS_PAGE" "220"
					( Origin gFrontEnd )
				)
				( attribute "ROOM" "VDDQ_DEF_PWR_VR"
					( Origin gFrontEnd )
				)
				( attribute "ROT" "0"
					( Origin gFrontEnd )
				)
				( attribute "SEC" "1"
					( Origin gFrontEnd )
				)
				( attribute "SEC_TYPE" "3018"
					( Origin gFrontEnd )
				)
				( attribute "TOLERANCE" "20%"
					( Origin gFrontEnd )
				)
				( attribute "VALUE" "470UF"
					( Origin gFrontEnd )
				)
				( attribute "VER" "1"
					( Origin gFrontEnd )
				)
				( attribute "VOLTAGE" "2.5V"
					( Units "uVoltage" "V" 1.000000)
					( Origin gFrontEnd )
				)
				( attribute "XY" "(2925,-150)"
					( Origin gFrontEnd )
				)
				( attribute "CHIPS_PART_NAME" "CAPP"
					( Origin gPackager )
				)
				( attribute "CDS_PART_NAME" "CAPP_3018-470UF,2.5V,20%,ALUM,A"
					( Origin gPackager )
				)
				( objectStatus "C3L6" )
				( pin "a"
					( attribute "PN" "1"
						( Origin gPackager )
					)
					( objectStatus "C3L6.1" )
				)
				( pin "b"
					( attribute "PN" "2"
						( Origin gPackager )
					)
					( objectStatus "C3L6.2" )
				)
			)
			( gate "@baseboard_fab2_lib.baseboard_fab2(sch_1):page220_i76"
				( attribute "CDS_LIB" "mstr_discrete"
					( Origin gPackager )
				)
				( attribute "CDS_LOCATION" "C3L14"
					( Origin gPackager )
				)
				( attribute "CDS_SEC" "1"
					( Origin gPackager )
				)
				( attribute "LOCATION" "C3L14"
					( Origin gFrontEnd )
				)
				( attribute "MATERIAL" "ALUM"
					( Origin gFrontEnd )
				)
				( attribute "PACK_TYPE" "3018"
					( Origin gFrontEnd )
				)
				( attribute "PART_NUMBER" "699013-049"
					( Origin gFrontEnd )
				)
				( attribute "PHYS_PAGE" "220"
					( Origin gFrontEnd )
				)
				( attribute "ROOM" "VDDQ_DEF_PWR_VR"
					( Origin gFrontEnd )
				)
				( attribute "ROT" "0"
					( Origin gFrontEnd )
				)
				( attribute "SEC" "1"
					( Origin gFrontEnd )
				)
				( attribute "SEC_TYPE" "3018"
					( Origin gFrontEnd )
				)
				( attribute "TOLERANCE" "20%"
					( Origin gFrontEnd )
				)
				( attribute "VALUE" "470UF"
					( Origin gFrontEnd )
				)
				( attribute "VER" "1"
					( Origin gFrontEnd )
				)
				( attribute "VOLTAGE" "2.5V"
					( Units "uVoltage" "V" 1.000000)
					( Origin gFrontEnd )
				)
				( attribute "XY" "(3350,-150)"
					( Origin gFrontEnd )
				)
				( attribute "CHIPS_PART_NAME" "CAPP"
					( Origin gPackager )
				)
				( attribute "CDS_PART_NAME" "CAPP_3018-470UF,2.5V,20%,ALUM,A"
					( Origin gPackager )
				)
				( objectStatus "C3L14" )
				( pin "a"
					( attribute "PN" "1"
						( Origin gPackager )
					)
					( objectStatus "C3L14.1" )
				)
				( pin "b"
					( attribute "PN" "2"
						( Origin gPackager )
					)
					( objectStatus "C3L14.2" )
				)
			)
			( gate "@baseboard_fab2_lib.baseboard_fab2(sch_1):page220_i77"
				( attribute "CDS_LIB" "mstr_discrete"
					( Origin gPackager )
				)
				( attribute "CDS_LOCATION" "C6A5"
					( Origin gPackager )
				)
				( attribute "CDS_SEC" "1"
					( Origin gPackager )
				)
				( attribute "LOCATION" "C6A5"
					( Origin gFrontEnd )
				)
				( attribute "MATERIAL" "ALUM"
					( Origin gFrontEnd )
				)
				( attribute "PACK_TYPE" "3018"
					( Origin gFrontEnd )
				)
				( attribute "PART_NUMBER" "699013-049"
					( Origin gFrontEnd )
				)
				( attribute "PHYS_PAGE" "220"
					( Origin gFrontEnd )
				)
				( attribute "ROOM" "VDDQ_DEF_PWR_VR"
					( Origin gFrontEnd )
				)
				( attribute "ROT" "0"
					( Origin gFrontEnd )
				)
				( attribute "SEC" "1"
					( Origin gFrontEnd )
				)
				( attribute "SEC_TYPE" "3018"
					( Origin gFrontEnd )
				)
				( attribute "TOLERANCE" "20%"
					( Origin gFrontEnd )
				)
				( attribute "VALUE" "470UF"
					( Origin gFrontEnd )
				)
				( attribute "VER" "1"
					( Origin gFrontEnd )
				)
				( attribute "VOLTAGE" "2.5V"
					( Units "uVoltage" "V" 1.000000)
					( Origin gFrontEnd )
				)
				( attribute "XY" "(3775,-150)"
					( Origin gFrontEnd )
				)
				( attribute "CHIPS_PART_NAME" "CAPP"
					( Origin gPackager )
				)
				( attribute "CDS_PART_NAME" "CAPP_3018-470UF,2.5V,20%,ALUM,A"
					( Origin gPackager )
				)
				( objectStatus "C6A5" )
				( pin "a"
					( attribute "PN" "1"
						( Origin gPackager )
					)
					( objectStatus "C6A5.1" )
				)
				( pin "b"
					( attribute "PN" "2"
						( Origin gPackager )
					)
					( objectStatus "C6A5.2" )
				)
			)
			( gate "@baseboard_fab2_lib.baseboard_fab2(sch_1):page220_i78"
				( attribute "CDS_LIB" "mstr_discrete"
					( Origin gPackager )
				)
				( attribute "CDS_LOCATION" "C4L5"
					( Origin gPackager )
				)
				( attribute "CDS_SEC" "1"
					( Origin gPackager )
				)
				( attribute "LOCATION" "C4L5"
					( Origin gFrontEnd )
				)
				( attribute "MATERIAL" "ALUM"
					( Origin gFrontEnd )
				)
				( attribute "PACK_TYPE" "3018"
					( Origin gFrontEnd )
				)
				( attribute "PART_NUMBER" "699013-049"
					( Origin gFrontEnd )
				)
				( attribute "PHYS_PAGE" "220"
					( Origin gFrontEnd )
				)
				( attribute "ROOM" "VDDQ_DEF_PWR_VR"
					( Origin gFrontEnd )
				)
				( attribute "ROT" "0"
					( Origin gFrontEnd )
				)
				( attribute "SEC" "1"
					( Origin gFrontEnd )
				)
				( attribute "SEC_TYPE" "3018"
					( Origin gFrontEnd )
				)
				( attribute "TOLERANCE" "20%"
					( Origin gFrontEnd )
				)
				( attribute "VALUE" "470UF"
					( Origin gFrontEnd )
				)
				( attribute "VER" "1"
					( Origin gFrontEnd )
				)
				( attribute "VOLTAGE" "2.5V"
					( Units "uVoltage" "V" 1.000000)
					( Origin gFrontEnd )
				)
				( attribute "XY" "(4175,-175)"
					( Origin gFrontEnd )
				)
				( attribute "CHIPS_PART_NAME" "CAPP"
					( Origin gPackager )
				)
				( attribute "CDS_PART_NAME" "CAPP_3018-470UF,2.5V,20%,ALUM,A"
					( Origin gPackager )
				)
				( objectStatus "C4L5" )
				( pin "a"
					( attribute "PN" "1"
						( Origin gPackager )
					)
					( objectStatus "C4L5.1" )
				)
				( pin "b"
					( attribute "PN" "2"
						( Origin gPackager )
					)
					( objectStatus "C4L5.2" )
				)
			)
			( gate "@baseboard_fab2_lib.baseboard_fab2(sch_1):page220_i82"
				( attribute "BOM_COST" "MEM_VRD_PVDDQ_DEF"
					( Origin gFrontEnd )
				)
				( attribute "CDS_LIB" "mstr_discrete"
					( Origin gPackager )
				)
				( attribute "CDS_LOCATION" "C5M8"
					( Origin gPackager )
				)
				( attribute "CDS_SEC" "1"
					( Origin gPackager )
				)
				( attribute "LOCATION" "C5M8"
					( Origin gFrontEnd )
				)
				( attribute "MATERIAL" "X5R"
					( Origin gFrontEnd )
				)
				( attribute "PACK_TYPE" "0805"
					( Origin gFrontEnd )
				)
				( attribute "PART_NUMBER" "602433-112"
					( Origin gFrontEnd )
				)
				( attribute "PHYS_PAGE" "220"
					( Origin gFrontEnd )
				)
				( attribute "ROOM" "VDDQ_DEF_PWR_VR"
					( Origin gFrontEnd )
				)
				( attribute "ROT" "0"
					( Origin gFrontEnd )
				)
				( attribute "SEC" "1"
					( Origin gFrontEnd )
				)
				( attribute "SEC_TYPE" "0805"
					( Origin gFrontEnd )
				)
				( attribute "TOLERANCE" "20%"
					( Origin gFrontEnd )
				)
				( attribute "VALUE" "100UF"
					( Origin gFrontEnd )
				)
				( attribute "VER" "1"
					( Origin gFrontEnd )
				)
				( attribute "VOLTAGE" "4V"
					( Units "uVoltage" "V" 1.000000)
					( Origin gFrontEnd )
				)
				( attribute "XY" "(5000,2825)"
					( Origin gFrontEnd )
				)
				( attribute "CHIPS_PART_NAME" "CAP"
					( Origin gPackager )
				)
				( attribute "CDS_PART_NAME" "CAP_0805-100UF,4V,20%,X5R,6024A"
					( Origin gPackager )
				)
				( objectStatus "C5M8" )
				( pin "a"
					( attribute "PN" "1"
						( Origin gPackager )
					)
					( objectStatus "C5M8.1" )
				)
				( pin "b"
					( attribute "PN" "2"
						( Origin gPackager )
					)
					( objectStatus "C5M8.2" )
				)
			)
			( gate "@baseboard_fab2_lib.baseboard_fab2(sch_1):page220_i83"
				( attribute "BOM_COST" "MEM_VRD_PVDDQ_DEF"
					( Origin gFrontEnd )
				)
				( attribute "CDS_LIB" "mstr_discrete"
					( Origin gPackager )
				)
				( attribute "CDS_LOCATION" "C5L14"
					( Origin gPackager )
				)
				( attribute "CDS_SEC" "1"
					( Origin gPackager )
				)
				( attribute "LOCATION" "C5L14"
					( Origin gFrontEnd )
				)
				( attribute "MATERIAL" "X5R"
					( Origin gFrontEnd )
				)
				( attribute "PACK_TYPE" "0805"
					( Origin gFrontEnd )
				)
				( attribute "PART_NUMBER" "602433-112"
					( Origin gFrontEnd )
				)
				( attribute "PHYS_PAGE" "220"
					( Origin gFrontEnd )
				)
				( attribute "ROOM" "VDDQ_DEF_PWR_VR"
					( Origin gFrontEnd )
				)
				( attribute "ROT" "0"
					( Origin gFrontEnd )
				)
				( attribute "SEC" "1"
					( Origin gFrontEnd )
				)
				( attribute "SEC_TYPE" "0805"
					( Origin gFrontEnd )
				)
				( attribute "TOLERANCE" "20%"
					( Origin gFrontEnd )
				)
				( attribute "VALUE" "100UF"
					( Origin gFrontEnd )
				)
				( attribute "VER" "1"
					( Origin gFrontEnd )
				)
				( attribute "VOLTAGE" "4V"
					( Units "uVoltage" "V" 1.000000)
					( Origin gFrontEnd )
				)
				( attribute "XY" "(4600,2825)"
					( Origin gFrontEnd )
				)
				( attribute "CHIPS_PART_NAME" "CAP"
					( Origin gPackager )
				)
				( attribute "CDS_PART_NAME" "CAP_0805-100UF,4V,20%,X5R,6024A"
					( Origin gPackager )
				)
				( objectStatus "C5L14" )
				( pin "a"
					( attribute "PN" "1"
						( Origin gPackager )
					)
					( objectStatus "C5L14.1" )
				)
				( pin "b"
					( attribute "PN" "2"
						( Origin gPackager )
					)
					( objectStatus "C5L14.2" )
				)
			)
			( gate "@baseboard_fab2_lib.baseboard_fab2(sch_1):page220_i88"
				( attribute "BOM_COST" "MEM_VRD_PVDDQ_DEF"
					( Origin gFrontEnd )
				)
				( attribute "CDS_LIB" "mstr_discrete"
					( Origin gPackager )
				)
				( attribute "CDS_LOCATION" "C5M12"
					( Origin gPackager )
				)
				( attribute "CDS_SEC" "1"
					( Origin gPackager )
				)
				( attribute "LOCATION" "C5M12"
					( Origin gFrontEnd )
				)
				( attribute "MATERIAL" "X5R"
					( Origin gFrontEnd )
				)
				( attribute "PACK_TYPE" "0805"
					( Origin gFrontEnd )
				)
				( attribute "PART_NUMBER" "602433-112"
					( Origin gFrontEnd )
				)
				( attribute "PHYS_PAGE" "220"
					( Origin gFrontEnd )
				)
				( attribute "ROOM" "VDDQ_DEF_PWR_VR"
					( Origin gFrontEnd )
				)
				( attribute "ROT" "0"
					( Origin gFrontEnd )
				)
				( attribute "SEC" "1"
					( Origin gFrontEnd )
				)
				( attribute "SEC_TYPE" "0805"
					( Origin gFrontEnd )
				)
				( attribute "TOLERANCE" "20%"
					( Origin gFrontEnd )
				)
				( attribute "VALUE" "100UF"
					( Origin gFrontEnd )
				)
				( attribute "VER" "1"
					( Origin gFrontEnd )
				)
				( attribute "VOLTAGE" "4V"
					( Units "uVoltage" "V" 1.000000)
					( Origin gFrontEnd )
				)
				( attribute "XY" "(4250,2825)"
					( Origin gFrontEnd )
				)
				( attribute "CHIPS_PART_NAME" "CAP"
					( Origin gPackager )
				)
				( attribute "CDS_PART_NAME" "CAP_0805-100UF,4V,20%,X5R,6024A"
					( Origin gPackager )
				)
				( objectStatus "C5M12" )
				( pin "a"
					( attribute "PN" "1"
						( Origin gPackager )
					)
					( objectStatus "C5M12.1" )
				)
				( pin "b"
					( attribute "PN" "2"
						( Origin gPackager )
					)
					( objectStatus "C5M12.2" )
				)
			)
			( gate "@baseboard_fab2_lib.baseboard_fab2(sch_1):page220_i89"
				( attribute "BOM_COST" "MEM_VRD_PVDDQ_DEF"
					( Origin gFrontEnd )
				)
				( attribute "CDS_LIB" "mstr_discrete"
					( Origin gPackager )
				)
				( attribute "CDS_LOCATION" "C5L3"
					( Origin gPackager )
				)
				( attribute "CDS_SEC" "1"
					( Origin gPackager )
				)
				( attribute "LOCATION" "C5L3"
					( Origin gFrontEnd )
				)
				( attribute "MATERIAL" "X5R"
					( Origin gFrontEnd )
				)
				( attribute "PACK_TYPE" "0805"
					( Origin gFrontEnd )
				)
				( attribute "PART_NUMBER" "602433-112"
					( Origin gFrontEnd )
				)
				( attribute "PHYS_PAGE" "220"
					( Origin gFrontEnd )
				)
				( attribute "ROOM" "VDDQ_DEF_PWR_VR"
					( Origin gFrontEnd )
				)
				( attribute "ROT" "0"
					( Origin gFrontEnd )
				)
				( attribute "SEC" "1"
					( Origin gFrontEnd )
				)
				( attribute "SEC_TYPE" "0805"
					( Origin gFrontEnd )
				)
				( attribute "TOLERANCE" "20%"
					( Origin gFrontEnd )
				)
				( attribute "VALUE" "100UF"
					( Origin gFrontEnd )
				)
				( attribute "VER" "1"
					( Origin gFrontEnd )
				)
				( attribute "VOLTAGE" "4V"
					( Units "uVoltage" "V" 1.000000)
					( Origin gFrontEnd )
				)
				( attribute "XY" "(3850,2825)"
					( Origin gFrontEnd )
				)
				( attribute "CHIPS_PART_NAME" "CAP"
					( Origin gPackager )
				)
				( attribute "CDS_PART_NAME" "CAP_0805-100UF,4V,20%,X5R,6024A"
					( Origin gPackager )
				)
				( objectStatus "C5L3" )
				( pin "a"
					( attribute "PN" "1"
						( Origin gPackager )
					)
					( objectStatus "C5L3.1" )
				)
				( pin "b"
					( attribute "PN" "2"
						( Origin gPackager )
					)
					( objectStatus "C5L3.2" )
				)
			)
			( gate "@baseboard_fab2_lib.baseboard_fab2(sch_1):page220_i90"
				( attribute "BOM_COST" "MEM_VRD_PVDDQ_DEF"
					( Origin gFrontEnd )
				)
				( attribute "CDS_LIB" "mstr_discrete"
					( Origin gPackager )
				)
				( attribute "CDS_LOCATION" "C5L2"
					( Origin gPackager )
				)
				( attribute "CDS_SEC" "1"
					( Origin gPackager )
				)
				( attribute "LOCATION" "C5L2"
					( Origin gFrontEnd )
				)
				( attribute "MATERIAL" "X5R"
					( Origin gFrontEnd )
				)
				( attribute "PACK_TYPE" "0805"
					( Origin gFrontEnd )
				)
				( attribute "PART_NUMBER" "602433-112"
					( Origin gFrontEnd )
				)
				( attribute "PHYS_PAGE" "220"
					( Origin gFrontEnd )
				)
				( attribute "ROOM" "VDDQ_DEF_PWR_VR"
					( Origin gFrontEnd )
				)
				( attribute "ROT" "0"
					( Origin gFrontEnd )
				)
				( attribute "SEC" "1"
					( Origin gFrontEnd )
				)
				( attribute "SEC_TYPE" "0805"
					( Origin gFrontEnd )
				)
				( attribute "TOLERANCE" "20%"
					( Origin gFrontEnd )
				)
				( attribute "VALUE" "100UF"
					( Origin gFrontEnd )
				)
				( attribute "VER" "1"
					( Origin gFrontEnd )
				)
				( attribute "VOLTAGE" "4V"
					( Units "uVoltage" "V" 1.000000)
					( Origin gFrontEnd )
				)
				( attribute "XY" "(3500,2825)"
					( Origin gFrontEnd )
				)
				( attribute "CHIPS_PART_NAME" "CAP"
					( Origin gPackager )
				)
				( attribute "CDS_PART_NAME" "CAP_0805-100UF,4V,20%,X5R,6024A"
					( Origin gPackager )
				)
				( objectStatus "C5L2" )
				( pin "a"
					( attribute "PN" "1"
						( Origin gPackager )
					)
					( objectStatus "C5L2.1" )
				)
				( pin "b"
					( attribute "PN" "2"
						( Origin gPackager )
					)
					( objectStatus "C5L2.2" )
				)
			)
			( gate "@baseboard_fab2_lib.baseboard_fab2(sch_1):page220_i91"
				( attribute "BOM_COST" "MEM_VRD_PVDDQ_DEF"
					( Origin gFrontEnd )
				)
				( attribute "CDS_LIB" "mstr_discrete"
					( Origin gPackager )
				)
				( attribute "CDS_LOCATION" "C5L1"
					( Origin gPackager )
				)
				( attribute "CDS_SEC" "1"
					( Origin gPackager )
				)
				( attribute "LOCATION" "C5L1"
					( Origin gFrontEnd )
				)
				( attribute "MATERIAL" "X5R"
					( Origin gFrontEnd )
				)
				( attribute "PACK_TYPE" "0805"
					( Origin gFrontEnd )
				)
				( attribute "PART_NUMBER" "602433-112"
					( Origin gFrontEnd )
				)
				( attribute "PHYS_PAGE" "220"
					( Origin gFrontEnd )
				)
				( attribute "ROOM" "VDDQ_DEF_PWR_VR"
					( Origin gFrontEnd )
				)
				( attribute "ROT" "0"
					( Origin gFrontEnd )
				)
				( attribute "SEC" "1"
					( Origin gFrontEnd )
				)
				( attribute "SEC_TYPE" "0805"
					( Origin gFrontEnd )
				)
				( attribute "TOLERANCE" "20%"
					( Origin gFrontEnd )
				)
				( attribute "VALUE" "100UF"
					( Origin gFrontEnd )
				)
				( attribute "VER" "1"
					( Origin gFrontEnd )
				)
				( attribute "VOLTAGE" "4V"
					( Units "uVoltage" "V" 1.000000)
					( Origin gFrontEnd )
				)
				( attribute "XY" "(3150,2825)"
					( Origin gFrontEnd )
				)
				( attribute "CHIPS_PART_NAME" "CAP"
					( Origin gPackager )
				)
				( attribute "CDS_PART_NAME" "CAP_0805-100UF,4V,20%,X5R,6024A"
					( Origin gPackager )
				)
				( objectStatus "C5L1" )
				( pin "a"
					( attribute "PN" "1"
						( Origin gPackager )
					)
					( objectStatus "C5L1.1" )
				)
				( pin "b"
					( attribute "PN" "2"
						( Origin gPackager )
					)
					( objectStatus "C5L1.2" )
				)
			)
			( gate "@baseboard_fab2_lib.baseboard_fab2(sch_1):page220_i92"
				( attribute "BOM_COST" "MEM_VRD_PVDDQ_DEF"
					( Origin gFrontEnd )
				)
				( attribute "CDS_LIB" "mstr_discrete"
					( Origin gPackager )
				)
				( attribute "CDS_LOCATION" "C5A20"
					( Origin gPackager )
				)
				( attribute "CDS_SEC" "1"
					( Origin gPackager )
				)
				( attribute "LOCATION" "C5A20"
					( Origin gFrontEnd )
				)
				( attribute "MATERIAL" "X5R"
					( Origin gFrontEnd )
				)
				( attribute "PACK_TYPE" "0805"
					( Origin gFrontEnd )
				)
				( attribute "PART_NUMBER" "602433-112"
					( Origin gFrontEnd )
				)
				( attribute "PHYS_PAGE" "220"
					( Origin gFrontEnd )
				)
				( attribute "ROOM" "VDDQ_DEF_PWR_VR"
					( Origin gFrontEnd )
				)
				( attribute "ROT" "0"
					( Origin gFrontEnd )
				)
				( attribute "SEC" "1"
					( Origin gFrontEnd )
				)
				( attribute "SEC_TYPE" "0805"
					( Origin gFrontEnd )
				)
				( attribute "TOLERANCE" "20%"
					( Origin gFrontEnd )
				)
				( attribute "VALUE" "100UF"
					( Origin gFrontEnd )
				)
				( attribute "VER" "1"
					( Origin gFrontEnd )
				)
				( attribute "VOLTAGE" "4V"
					( Units "uVoltage" "V" 1.000000)
					( Origin gFrontEnd )
				)
				( attribute "XY" "(2750,2825)"
					( Origin gFrontEnd )
				)
				( attribute "CHIPS_PART_NAME" "CAP"
					( Origin gPackager )
				)
				( attribute "CDS_PART_NAME" "CAP_0805-100UF,4V,20%,X5R,6024A"
					( Origin gPackager )
				)
				( objectStatus "C5A20" )
				( pin "a"
					( attribute "PN" "1"
						( Origin gPackager )
					)
					( objectStatus "C5A20.1" )
				)
				( pin "b"
					( attribute "PN" "2"
						( Origin gPackager )
					)
					( objectStatus "C5A20.2" )
				)
			)
			( gate "@baseboard_fab2_lib.baseboard_fab2(sch_1):page220_i110"
				( attribute "BOM_COST" "MEM_VRD_PVDDQ_DEF"
					( Origin gFrontEnd )
				)
				( attribute "CDS_LIB" "mstr_discrete"
					( Origin gPackager )
				)
				( attribute "CDS_LOCATION" "C5A10"
					( Origin gPackager )
				)
				( attribute "CDS_SEC" "1"
					( Origin gPackager )
				)
				( attribute "LOCATION" "C5A10"
					( Origin gFrontEnd )
				)
				( attribute "MATERIAL" "X5R"
					( Origin gFrontEnd )
				)
				( attribute "PACK_TYPE" "0805"
					( Origin gFrontEnd )
				)
				( attribute "PART_NUMBER" "602433-112"
					( Origin gFrontEnd )
				)
				( attribute "PHYS_PAGE" "220"
					( Origin gFrontEnd )
				)
				( attribute "ROOM" "VDDQ_DEF_PWR_VR"
					( Origin gFrontEnd )
				)
				( attribute "ROT" "0"
					( Origin gFrontEnd )
				)
				( attribute "SEC" "1"
					( Origin gFrontEnd )
				)
				( attribute "SEC_TYPE" "0805"
					( Origin gFrontEnd )
				)
				( attribute "TOLERANCE" "20%"
					( Origin gFrontEnd )
				)
				( attribute "VALUE" "100UF"
					( Origin gFrontEnd )
				)
				( attribute "VER" "1"
					( Origin gFrontEnd )
				)
				( attribute "VOLTAGE" "4V"
					( Units "uVoltage" "V" 1.000000)
					( Origin gFrontEnd )
				)
				( attribute "XY" "(2400,2825)"
					( Origin gFrontEnd )
				)
				( attribute "CHIPS_PART_NAME" "CAP"
					( Origin gPackager )
				)
				( attribute "CDS_PART_NAME" "CAP_0805-100UF,4V,20%,X5R,6024A"
					( Origin gPackager )
				)
				( objectStatus "C5A10" )
				( pin "a"
					( attribute "PN" "1"
						( Origin gPackager )
					)
					( objectStatus "C5A10.1" )
				)
				( pin "b"
					( attribute "PN" "2"
						( Origin gPackager )
					)
					( objectStatus "C5A10.2" )
				)
			)
			( gate "@baseboard_fab2_lib.baseboard_fab2(sch_1):page220_i124"
				( attribute "BOM_COST" "MEM_VRD_PVDDQ_DEF"
					( Origin gFrontEnd )
				)
				( attribute "CDS_LIB" "mstr_discrete"
					( Origin gPackager )
				)
				( attribute "CDS_LOCATION" "L7A5"
					( Origin gPackager )
				)
				( attribute "CDS_SEC" "1"
					( Origin gPackager )
				)
				( attribute "LOCATION" "L7A5"
					( Origin gFrontEnd )
				)
				( attribute "MATERIAL" "IND"
					( Origin gFrontEnd )
				)
				( attribute "PACK_TYPE" "SM"
					( Origin gFrontEnd )
				)
				( attribute "PART_NUMBER" "D92183-020"
					( Origin gFrontEnd )
				)
				( attribute "PHYS_PAGE" "220"
					( Origin gFrontEnd )
				)
				( attribute "ROOM" "VDDQ_DEF_PWR_VR"
					( Origin gFrontEnd )
				)
				( attribute "ROT" "0"
					( Origin gFrontEnd )
				)
				( attribute "SEC" "1"
					( Origin gFrontEnd )
				)
				( attribute "SEC_TYPE" "SM"
					( Origin gFrontEnd )
				)
				( attribute "VALUE" "100NH"
					( Origin gFrontEnd )
				)
				( attribute "VER" "1"
					( Origin gFrontEnd )
				)
				( attribute "XY" "(-1475,1125)"
					( Origin gFrontEnd )
				)
				( attribute "CHIPS_PART_NAME" "INDUCTOR"
					( Origin gPackager )
				)
				( attribute "CDS_PART_NAME" "INDUCTOR_SM-100NH,IND,D92183-0B"
					( Origin gPackager )
				)
				( objectStatus "L7A5" )
				( pin "ina"
					( attribute "PN" "1"
						( Origin gPackager )
					)
					( objectStatus "L7A5.1" )
				)
				( pin "inb"
					( attribute "PN" "2"
						( Origin gPackager )
					)
					( objectStatus "L7A5.2" )
				)
			)
			( gate "@baseboard_fab2_lib.baseboard_fab2(sch_1):page220_i175"
				( attribute "CDS_LIB" "mstr_discrete"
					( Origin gPackager )
				)
				( attribute "CDS_LOCATION" "C7A19"
					( Origin gPackager )
				)
				( attribute "CDS_SEC" "1"
					( Origin gPackager )
				)
				( attribute "LOCATION" "C7A19"
					( Origin gFrontEnd )
				)
				( attribute "MATERIAL" "OSCON"
					( Origin gFrontEnd )
				)
				( attribute "PACK_TYPE" "2626"
					( Origin gFrontEnd )
				)
				( attribute "PART_NUMBER" "A31228-047"
					( Origin gFrontEnd )
				)
				( attribute "PHYS_PAGE" "220"
					( Origin gFrontEnd )
				)
				( attribute "ROOM" "VDDQ_DEF_PWR_VR"
					( Origin gFrontEnd )
				)
				( attribute "ROT" "0"
					( Origin gFrontEnd )
				)
				( attribute "SEC" "1"
					( Origin gFrontEnd )
				)
				( attribute "SEC_TYPE" "2626"
					( Origin gFrontEnd )
				)
				( attribute "TOLERANCE" "20%"
					( Origin gFrontEnd )
				)
				( attribute "VALUE" "270UF"
					( Origin gFrontEnd )
				)
				( attribute "VER" "1"
					( Origin gFrontEnd )
				)
				( attribute "VOLTAGE" "16V"
					( Units "uVoltage" "V" 1.000000)
					( Origin gFrontEnd )
				)
				( attribute "XY" "(-1050,925)"
					( Origin gFrontEnd )
				)
				( attribute "CHIPS_PART_NAME" "CAPP"
					( Origin gPackager )
				)
				( attribute "CDS_PART_NAME" "CAPP_2626-270UF,16V,20%,OSCON,A"
					( Origin gPackager )
				)
				( objectStatus "C7A19" )
				( pin "a"
					( attribute "PN" "1"
						( Origin gPackager )
					)
					( objectStatus "C7A19.1" )
				)
				( pin "b"
					( attribute "PN" "2"
						( Origin gPackager )
					)
					( objectStatus "C7A19.2" )
				)
			)
			( gate "@baseboard_fab2_lib.baseboard_fab2(sch_1):page220_i177"
				( attribute "BOM_COST" "MEM_VRD_PVDDQ_DEF"
					( Origin gFrontEnd )
				)
				( attribute "CDS_LIB" "mstr_discrete"
					( Origin gPackager )
				)
				( attribute "CDS_LOCATION" "C5P2"
					( Origin gPackager )
				)
				( attribute "CDS_SEC" "1"
					( Origin gPackager )
				)
				( attribute "LOCATION" "C5P2"
					( Origin gFrontEnd )
				)
				( attribute "MATERIAL" "X6S"
					( Origin gFrontEnd )
				)
				( attribute "PACK_TYPE" "0805LF"
					( Origin gFrontEnd )
				)
				( attribute "PART_NUMBER" "C95333-002"
					( Origin gFrontEnd )
				)
				( attribute "PHYS_PAGE" "220"
					( Origin gFrontEnd )
				)
				( attribute "ROOM" "VDDQ_DEF_CPU0"
					( Origin gFrontEnd )
				)
				( attribute "ROT" "0"
					( Origin gFrontEnd )
				)
				( attribute "SEC" "1"
					( Origin gFrontEnd )
				)
				( attribute "SEC_TYPE" "0805LF"
					( Origin gFrontEnd )
				)
				( attribute "TOLERANCE" "20%"
					( Origin gFrontEnd )
				)
				( attribute "VALUE" "22UF"
					( Origin gFrontEnd )
				)
				( attribute "VER" "1"
					( Origin gFrontEnd )
				)
				( attribute "VOLTAGE" "4V"
					( Units "uVoltage" "V" 1.000000)
					( Origin gFrontEnd )
				)
				( attribute "XY" "(-2225,2900)"
					( Origin gFrontEnd )
				)
				( attribute "CHIPS_PART_NAME" "CAP"
					( Origin gPackager )
				)
				( attribute "CDS_PART_NAME" "CAP_0805LF-22UF,4V,20%,X6S,C95A"
					( Origin gPackager )
				)
				( objectStatus "C5P2" )
				( pin "a"
					( attribute "PN" "1"
						( Origin gPackager )
					)
					( objectStatus "C5P2.1" )
				)
				( pin "b"
					( attribute "PN" "2"
						( Origin gPackager )
					)
					( objectStatus "C5P2.2" )
				)
			)
			( gate "@baseboard_fab2_lib.baseboard_fab2(sch_1):page220_i179"
				( attribute "BOM_COST" "MEM_VRD_PVDDQ_DEF"
					( Origin gFrontEnd )
				)
				( attribute "CDS_LIB" "mstr_discrete"
					( Origin gPackager )
				)
				( attribute "CDS_LOCATION" "C5P1"
					( Origin gPackager )
				)
				( attribute "CDS_SEC" "1"
					( Origin gPackager )
				)
				( attribute "LOCATION" "C5P1"
					( Origin gFrontEnd )
				)
				( attribute "MATERIAL" "X6S"
					( Origin gFrontEnd )
				)
				( attribute "PACK_TYPE" "0805LF"
					( Origin gFrontEnd )
				)
				( attribute "PART_NUMBER" "C95333-002"
					( Origin gFrontEnd )
				)
				( attribute "PHYS_PAGE" "220"
					( Origin gFrontEnd )
				)
				( attribute "ROOM" "VDDQ_DEF_CPU0"
					( Origin gFrontEnd )
				)
				( attribute "ROT" "0"
					( Origin gFrontEnd )
				)
				( attribute "SEC" "1"
					( Origin gFrontEnd )
				)
				( attribute "SEC_TYPE" "0805LF"
					( Origin gFrontEnd )
				)
				( attribute "TOLERANCE" "20%"
					( Origin gFrontEnd )
				)
				( attribute "VALUE" "22UF"
					( Origin gFrontEnd )
				)
				( attribute "VER" "1"
					( Origin gFrontEnd )
				)
				( attribute "VOLTAGE" "4V"
					( Units "uVoltage" "V" 1.000000)
					( Origin gFrontEnd )
				)
				( attribute "XY" "(-1875,2900)"
					( Origin gFrontEnd )
				)
				( attribute "CHIPS_PART_NAME" "CAP"
					( Origin gPackager )
				)
				( attribute "CDS_PART_NAME" "CAP_0805LF-22UF,4V,20%,X6S,C95A"
					( Origin gPackager )
				)
				( objectStatus "C5P1" )
				( pin "a"
					( attribute "PN" "1"
						( Origin gPackager )
					)
					( objectStatus "C5P1.1" )
				)
				( pin "b"
					( attribute "PN" "2"
						( Origin gPackager )
					)
					( objectStatus "C5P1.2" )
				)
			)
			( gate "@baseboard_fab2_lib.baseboard_fab2(sch_1):page220_i180"
				( attribute "BOM_COST" "MEM_VRD_PVDDQ_DEF"
					( Origin gFrontEnd )
				)
				( attribute "CDS_LIB" "mstr_discrete"
					( Origin gPackager )
				)
				( attribute "CDS_LOCATION" "C5D9"
					( Origin gPackager )
				)
				( attribute "CDS_SEC" "1"
					( Origin gPackager )
				)
				( attribute "LOCATION" "C5D9"
					( Origin gFrontEnd )
				)
				( attribute "MATERIAL" "X6S"
					( Origin gFrontEnd )
				)
				( attribute "PACK_TYPE" "0603LF"
					( Origin gFrontEnd )
				)
				( attribute "PART_NUMBER" "E15431-001"
					( Origin gFrontEnd )
				)
				( attribute "PHYS_PAGE" "220"
					( Origin gFrontEnd )
				)
				( attribute "ROOM" "VDDQ_DEF_CPU0"
					( Origin gFrontEnd )
				)
				( attribute "ROT" "0"
					( Origin gFrontEnd )
				)
				( attribute "SEC" "1"
					( Origin gFrontEnd )
				)
				( attribute "SEC_TYPE" "0603LF"
					( Origin gFrontEnd )
				)
				( attribute "TOLERANCE" "20%"
					( Origin gFrontEnd )
				)
				( attribute "VALUE" "10UF"
					( Origin gFrontEnd )
				)
				( attribute "VER" "1"
					( Origin gFrontEnd )
				)
				( attribute "VOLTAGE" "4V"
					( Units "uVoltage" "V" 1.000000)
					( Origin gFrontEnd )
				)
				( attribute "XY" "(-1475,2900)"
					( Origin gFrontEnd )
				)
				( attribute "CHIPS_PART_NAME" "CAP"
					( Origin gPackager )
				)
				( attribute "CDS_PART_NAME" "CAP_0603LF-10UF,4V,20%,X6S,E15A"
					( Origin gPackager )
				)
				( objectStatus "C5D9" )
				( pin "a"
					( attribute "PN" "1"
						( Origin gPackager )
					)
					( objectStatus "C5D9.1" )
				)
				( pin "b"
					( attribute "PN" "2"
						( Origin gPackager )
					)
					( objectStatus "C5D9.2" )
				)
			)
			( gate "@baseboard_fab2_lib.baseboard_fab2(sch_1):page220_i182"
				( attribute "BOM_COST" "MEM_VRD_PVDDQ_DEF"
					( Origin gFrontEnd )
				)
				( attribute "CDS_LIB" "mstr_discrete"
					( Origin gPackager )
				)
				( attribute "CDS_LOCATION" "C5D6"
					( Origin gPackager )
				)
				( attribute "CDS_SEC" "1"
					( Origin gPackager )
				)
				( attribute "LOCATION" "C5D6"
					( Origin gFrontEnd )
				)
				( attribute "MATERIAL" "X6S"
					( Origin gFrontEnd )
				)
				( attribute "PACK_TYPE" "0603LF"
					( Origin gFrontEnd )
				)
				( attribute "PART_NUMBER" "E15431-001"
					( Origin gFrontEnd )
				)
				( attribute "PHYS_PAGE" "220"
					( Origin gFrontEnd )
				)
				( attribute "ROOM" "VDDQ_DEF_CPU0"
					( Origin gFrontEnd )
				)
				( attribute "ROT" "0"
					( Origin gFrontEnd )
				)
				( attribute "SEC" "1"
					( Origin gFrontEnd )
				)
				( attribute "SEC_TYPE" "0603LF"
					( Origin gFrontEnd )
				)
				( attribute "TOLERANCE" "20%"
					( Origin gFrontEnd )
				)
				( attribute "VALUE" "10UF"
					( Origin gFrontEnd )
				)
				( attribute "VER" "1"
					( Origin gFrontEnd )
				)
				( attribute "VOLTAGE" "4V"
					( Units "uVoltage" "V" 1.000000)
					( Origin gFrontEnd )
				)
				( attribute "XY" "(-1125,2900)"
					( Origin gFrontEnd )
				)
				( attribute "CHIPS_PART_NAME" "CAP"
					( Origin gPackager )
				)
				( attribute "CDS_PART_NAME" "CAP_0603LF-10UF,4V,20%,X6S,E15A"
					( Origin gPackager )
				)
				( objectStatus "C5D6" )
				( pin "a"
					( attribute "PN" "1"
						( Origin gPackager )
					)
					( objectStatus "C5D6.1" )
				)
				( pin "b"
					( attribute "PN" "2"
						( Origin gPackager )
					)
					( objectStatus "C5D6.2" )
				)
			)
			( gate "@baseboard_fab2_lib.baseboard_fab2(sch_1):page220_i183"
				( attribute "BOM_COST" "MEM_VRD_PVDDQ_DEF"
					( Origin gFrontEnd )
				)
				( attribute "CDS_LIB" "mstr_discrete"
					( Origin gPackager )
				)
				( attribute "CDS_LOCATION" "C5D7"
					( Origin gPackager )
				)
				( attribute "CDS_SEC" "1"
					( Origin gPackager )
				)
				( attribute "LOCATION" "C5D7"
					( Origin gFrontEnd )
				)
				( attribute "MATERIAL" "X6S"
					( Origin gFrontEnd )
				)
				( attribute "PACK_TYPE" "0603LF"
					( Origin gFrontEnd )
				)
				( attribute "PART_NUMBER" "E15431-001"
					( Origin gFrontEnd )
				)
				( attribute "PHYS_PAGE" "220"
					( Origin gFrontEnd )
				)
				( attribute "ROOM" "VDDQ_DEF_CPU0"
					( Origin gFrontEnd )
				)
				( attribute "ROT" "0"
					( Origin gFrontEnd )
				)
				( attribute "SEC" "1"
					( Origin gFrontEnd )
				)
				( attribute "SEC_TYPE" "0603LF"
					( Origin gFrontEnd )
				)
				( attribute "TOLERANCE" "20%"
					( Origin gFrontEnd )
				)
				( attribute "VALUE" "10UF"
					( Origin gFrontEnd )
				)
				( attribute "VER" "1"
					( Origin gFrontEnd )
				)
				( attribute "VOLTAGE" "4V"
					( Units "uVoltage" "V" 1.000000)
					( Origin gFrontEnd )
				)
				( attribute "XY" "(-775,2900)"
					( Origin gFrontEnd )
				)
				( attribute "CHIPS_PART_NAME" "CAP"
					( Origin gPackager )
				)
				( attribute "CDS_PART_NAME" "CAP_0603LF-10UF,4V,20%,X6S,E15A"
					( Origin gPackager )
				)
				( objectStatus "C5D7" )
				( pin "a"
					( attribute "PN" "1"
						( Origin gPackager )
					)
					( objectStatus "C5D7.1" )
				)
				( pin "b"
					( attribute "PN" "2"
						( Origin gPackager )
					)
					( objectStatus "C5D7.2" )
				)
			)
			( gate "@baseboard_fab2_lib.baseboard_fab2(sch_1):page220_i184"
				( attribute "BOM_COST" "MEM_VRD_PVDDQ_DEF"
					( Origin gFrontEnd )
				)
				( attribute "CDS_LIB" "mstr_discrete"
					( Origin gPackager )
				)
				( attribute "CDS_LOCATION" "C5D8"
					( Origin gPackager )
				)
				( attribute "CDS_SEC" "1"
					( Origin gPackager )
				)
				( attribute "LOCATION" "C5D8"
					( Origin gFrontEnd )
				)
				( attribute "MATERIAL" "X6S"
					( Origin gFrontEnd )
				)
				( attribute "PACK_TYPE" "0603LF"
					( Origin gFrontEnd )
				)
				( attribute "PART_NUMBER" "E15431-001"
					( Origin gFrontEnd )
				)
				( attribute "PHYS_PAGE" "220"
					( Origin gFrontEnd )
				)
				( attribute "ROOM" "VDDQ_DEF_CPU0"
					( Origin gFrontEnd )
				)
				( attribute "ROT" "0"
					( Origin gFrontEnd )
				)
				( attribute "SEC" "1"
					( Origin gFrontEnd )
				)
				( attribute "SEC_TYPE" "0603LF"
					( Origin gFrontEnd )
				)
				( attribute "TOLERANCE" "20%"
					( Origin gFrontEnd )
				)
				( attribute "VALUE" "10UF"
					( Origin gFrontEnd )
				)
				( attribute "VER" "1"
					( Origin gFrontEnd )
				)
				( attribute "VOLTAGE" "4V"
					( Units "uVoltage" "V" 1.000000)
					( Origin gFrontEnd )
				)
				( attribute "XY" "(-425,2900)"
					( Origin gFrontEnd )
				)
				( attribute "CHIPS_PART_NAME" "CAP"
					( Origin gPackager )
				)
				( attribute "CDS_PART_NAME" "CAP_0603LF-10UF,4V,20%,X6S,E15A"
					( Origin gPackager )
				)
				( objectStatus "C5D8" )
				( pin "a"
					( attribute "PN" "1"
						( Origin gPackager )
					)
					( objectStatus "C5D8.1" )
				)
				( pin "b"
					( attribute "PN" "2"
						( Origin gPackager )
					)
					( objectStatus "C5D8.2" )
				)
			)
			( gate "@baseboard_fab2_lib.baseboard_fab2(sch_1):page220_i192"
				( attribute "CDS_LIB" "dev_discrete"
					( Origin gPackager )
				)
				( attribute "CDS_LOCATION" "C5L15"
					( Origin gPackager )
				)
				( attribute "CDS_SEC" "1"
					( Origin gPackager )
				)
				( attribute "LOCATION" "C5L15"
					( Origin gFrontEnd )
				)
				( attribute "MATERIAL" "X5R"
					( Origin gFrontEnd )
				)
				( attribute "PACK_TYPE" "0603V"
					( Origin gFrontEnd )
				)
				( attribute "PART_NUMBER" "602433-106"
					( Origin gFrontEnd )
				)
				( attribute "PHYS_PAGE" "220"
					( Origin gFrontEnd )
				)
				( attribute "ROT" "0"
					( Origin gFrontEnd )
				)
				( attribute "SEC" "1"
					( Origin gFrontEnd )
				)
				( attribute "SEC_TYPE" "0603V"
					( Origin gFrontEnd )
				)
				( attribute "TOLERANCE" "20%"
					( Origin gFrontEnd )
				)
				( attribute "VALUE" "47UF"
					( Origin gFrontEnd )
				)
				( attribute "VER" "1"
					( Origin gFrontEnd )
				)
				( attribute "VOLTAGE" "4V"
					( Units "uVoltage" "V" 1.000000)
					( Origin gFrontEnd )
				)
				( attribute "XY" "(2650,950)"
					( Origin gFrontEnd )
				)
				( attribute "CHIPS_PART_NAME" "CAP_A"
					( Origin gPackager )
				)
				( attribute "CDS_PART_NAME" "CAP_A_0603V-47UF,4V,20%,X5R,60A"
					( Origin gPackager )
				)
				( objectStatus "C5L15" )
				( pin "a"
					( attribute "PN" "1"
						( Origin gPackager )
					)
					( objectStatus "C5L15.1" )
				)
				( pin "b"
					( attribute "PN" "2"
						( Origin gPackager )
					)
					( objectStatus "C5L15.2" )
				)
			)
			( gate "@baseboard_fab2_lib.baseboard_fab2(sch_1):page220_i193"
				( attribute "CDS_LIB" "dev_discrete"
					( Origin gPackager )
				)
				( attribute "CDS_LOCATION" "C5A5"
					( Origin gPackager )
				)
				( attribute "CDS_SEC" "1"
					( Origin gPackager )
				)
				( attribute "LOCATION" "C5A5"
					( Origin gFrontEnd )
				)
				( attribute "MATERIAL" "X5R"
					( Origin gFrontEnd )
				)
				( attribute "PACK_TYPE" "0603V"
					( Origin gFrontEnd )
				)
				( attribute "PART_NUMBER" "602433-106"
					( Origin gFrontEnd )
				)
				( attribute "PHYS_PAGE" "220"
					( Origin gFrontEnd )
				)
				( attribute "ROT" "0"
					( Origin gFrontEnd )
				)
				( attribute "SEC" "1"
					( Origin gFrontEnd )
				)
				( attribute "SEC_TYPE" "0603V"
					( Origin gFrontEnd )
				)
				( attribute "TOLERANCE" "20%"
					( Origin gFrontEnd )
				)
				( attribute "VALUE" "47UF"
					( Origin gFrontEnd )
				)
				( attribute "VER" "1"
					( Origin gFrontEnd )
				)
				( attribute "VOLTAGE" "4V"
					( Units "uVoltage" "V" 1.000000)
					( Origin gFrontEnd )
				)
				( attribute "XY" "(3000,950)"
					( Origin gFrontEnd )
				)
				( attribute "CHIPS_PART_NAME" "CAP_A"
					( Origin gPackager )
				)
				( attribute "CDS_PART_NAME" "CAP_A_0603V-47UF,4V,20%,X5R,60A"
					( Origin gPackager )
				)
				( objectStatus "C5A5" )
				( pin "a"
					( attribute "PN" "1"
						( Origin gPackager )
					)
					( objectStatus "C5A5.1" )
				)
				( pin "b"
					( attribute "PN" "2"
						( Origin gPackager )
					)
					( objectStatus "C5A5.2" )
				)
			)
			( gate "@baseboard_fab2_lib.baseboard_fab2(sch_1):page220_i194"
				( attribute "CDS_LIB" "dev_discrete"
					( Origin gPackager )
				)
				( attribute "CDS_LOCATION" "C5B1"
					( Origin gPackager )
				)
				( attribute "CDS_SEC" "1"
					( Origin gPackager )
				)
				( attribute "LOCATION" "C5B1"
					( Origin gFrontEnd )
				)
				( attribute "MATERIAL" "X5R"
					( Origin gFrontEnd )
				)
				( attribute "PACK_TYPE" "0603V"
					( Origin gFrontEnd )
				)
				( attribute "PART_NUMBER" "602433-106"
					( Origin gFrontEnd )
				)
				( attribute "PHYS_PAGE" "220"
					( Origin gFrontEnd )
				)
				( attribute "ROT" "0"
					( Origin gFrontEnd )
				)
				( attribute "SEC" "1"
					( Origin gFrontEnd )
				)
				( attribute "SEC_TYPE" "0603V"
					( Origin gFrontEnd )
				)
				( attribute "TOLERANCE" "20%"
					( Origin gFrontEnd )
				)
				( attribute "VALUE" "47UF"
					( Origin gFrontEnd )
				)
				( attribute "VER" "1"
					( Origin gFrontEnd )
				)
				( attribute "VOLTAGE" "4V"
					( Units "uVoltage" "V" 1.000000)
					( Origin gFrontEnd )
				)
				( attribute "XY" "(3400,950)"
					( Origin gFrontEnd )
				)
				( attribute "CHIPS_PART_NAME" "CAP_A"
					( Origin gPackager )
				)
				( attribute "CDS_PART_NAME" "CAP_A_0603V-47UF,4V,20%,X5R,60A"
					( Origin gPackager )
				)
				( objectStatus "C5B1" )
				( pin "a"
					( attribute "PN" "1"
						( Origin gPackager )
					)
					( objectStatus "C5B1.1" )
				)
				( pin "b"
					( attribute "PN" "2"
						( Origin gPackager )
					)
					( objectStatus "C5B1.2" )
				)
			)
			( gate "@baseboard_fab2_lib.baseboard_fab2(sch_1):page220_i195"
				( attribute "CDS_LIB" "dev_discrete"
					( Origin gPackager )
				)
				( attribute "CDS_LOCATION" "C5M9"
					( Origin gPackager )
				)
				( attribute "CDS_SEC" "1"
					( Origin gPackager )
				)
				( attribute "LOCATION" "C5M9"
					( Origin gFrontEnd )
				)
				( attribute "MATERIAL" "X5R"
					( Origin gFrontEnd )
				)
				( attribute "PACK_TYPE" "0603V"
					( Origin gFrontEnd )
				)
				( attribute "PART_NUMBER" "602433-106"
					( Origin gFrontEnd )
				)
				( attribute "PHYS_PAGE" "220"
					( Origin gFrontEnd )
				)
				( attribute "ROT" "0"
					( Origin gFrontEnd )
				)
				( attribute "SEC" "1"
					( Origin gFrontEnd )
				)
				( attribute "SEC_TYPE" "0603V"
					( Origin gFrontEnd )
				)
				( attribute "TOLERANCE" "20%"
					( Origin gFrontEnd )
				)
				( attribute "VALUE" "47UF"
					( Origin gFrontEnd )
				)
				( attribute "VER" "1"
					( Origin gFrontEnd )
				)
				( attribute "VOLTAGE" "4V"
					( Units "uVoltage" "V" 1.000000)
					( Origin gFrontEnd )
				)
				( attribute "XY" "(4125,1675)"
					( Origin gFrontEnd )
				)
				( attribute "CHIPS_PART_NAME" "CAP_A"
					( Origin gPackager )
				)
				( attribute "CDS_PART_NAME" "CAP_A_0603V-47UF,4V,20%,X5R,60A"
					( Origin gPackager )
				)
				( objectStatus "C5M9" )
				( pin "a"
					( attribute "PN" "1"
						( Origin gPackager )
					)
					( objectStatus "C5M9.1" )
				)
				( pin "b"
					( attribute "PN" "2"
						( Origin gPackager )
					)
					( objectStatus "C5M9.2" )
				)
			)
			( gate "@baseboard_fab2_lib.baseboard_fab2(sch_1):page220_i196"
				( attribute "CDS_LIB" "dev_discrete"
					( Origin gPackager )
				)
				( attribute "CDS_LOCATION" "C4M5"
					( Origin gPackager )
				)
				( attribute "CDS_SEC" "1"
					( Origin gPackager )
				)
				( attribute "LOCATION" "C4M5"
					( Origin gFrontEnd )
				)
				( attribute "MATERIAL" "X5R"
					( Origin gFrontEnd )
				)
				( attribute "PACK_TYPE" "0603V"
					( Origin gFrontEnd )
				)
				( attribute "PART_NUMBER" "602433-106"
					( Origin gFrontEnd )
				)
				( attribute "PHYS_PAGE" "220"
					( Origin gFrontEnd )
				)
				( attribute "ROT" "0"
					( Origin gFrontEnd )
				)
				( attribute "SEC" "1"
					( Origin gFrontEnd )
				)
				( attribute "SEC_TYPE" "0603V"
					( Origin gFrontEnd )
				)
				( attribute "TOLERANCE" "20%"
					( Origin gFrontEnd )
				)
				( attribute "VALUE" "47UF"
					( Origin gFrontEnd )
				)
				( attribute "VER" "1"
					( Origin gFrontEnd )
				)
				( attribute "VOLTAGE" "4V"
					( Units "uVoltage" "V" 1.000000)
					( Origin gFrontEnd )
				)
				( attribute "XY" "(3775,1675)"
					( Origin gFrontEnd )
				)
				( attribute "CHIPS_PART_NAME" "CAP_A"
					( Origin gPackager )
				)
				( attribute "CDS_PART_NAME" "CAP_A_0603V-47UF,4V,20%,X5R,60A"
					( Origin gPackager )
				)
				( objectStatus "C4M5" )
				( pin "a"
					( attribute "PN" "1"
						( Origin gPackager )
					)
					( objectStatus "C4M5.1" )
				)
				( pin "b"
					( attribute "PN" "2"
						( Origin gPackager )
					)
					( objectStatus "C4M5.2" )
				)
			)
			( gate "@baseboard_fab2_lib.baseboard_fab2(sch_1):page220_i197"
				( attribute "CDS_LIB" "dev_discrete"
					( Origin gPackager )
				)
				( attribute "CDS_LOCATION" "C5B2"
					( Origin gPackager )
				)
				( attribute "CDS_SEC" "1"
					( Origin gPackager )
				)
				( attribute "LOCATION" "C5B2"
					( Origin gFrontEnd )
				)
				( attribute "MATERIAL" "X5R"
					( Origin gFrontEnd )
				)
				( attribute "PACK_TYPE" "0603V"
					( Origin gFrontEnd )
				)
				( attribute "PART_NUMBER" "602433-106"
					( Origin gFrontEnd )
				)
				( attribute "PHYS_PAGE" "220"
					( Origin gFrontEnd )
				)
				( attribute "ROT" "0"
					( Origin gFrontEnd )
				)
				( attribute "SEC" "1"
					( Origin gFrontEnd )
				)
				( attribute "SEC_TYPE" "0603V"
					( Origin gFrontEnd )
				)
				( attribute "TOLERANCE" "20%"
					( Origin gFrontEnd )
				)
				( attribute "VALUE" "47UF"
					( Origin gFrontEnd )
				)
				( attribute "VER" "1"
					( Origin gFrontEnd )
				)
				( attribute "VOLTAGE" "4V"
					( Units "uVoltage" "V" 1.000000)
					( Origin gFrontEnd )
				)
				( attribute "XY" "(2675,1675)"
					( Origin gFrontEnd )
				)
				( attribute "CHIPS_PART_NAME" "CAP_A"
					( Origin gPackager )
				)
				( attribute "CDS_PART_NAME" "CAP_A_0603V-47UF,4V,20%,X5R,60A"
					( Origin gPackager )
				)
				( objectStatus "C5B2" )
				( pin "a"
					( attribute "PN" "1"
						( Origin gPackager )
					)
					( objectStatus "C5B2.1" )
				)
				( pin "b"
					( attribute "PN" "2"
						( Origin gPackager )
					)
					( objectStatus "C5B2.2" )
				)
			)
			( gate "@baseboard_fab2_lib.baseboard_fab2(sch_1):page220_i198"
				( attribute "CDS_LIB" "dev_discrete"
					( Origin gPackager )
				)
				( attribute "CDS_LOCATION" "C5M10"
					( Origin gPackager )
				)
				( attribute "CDS_SEC" "1"
					( Origin gPackager )
				)
				( attribute "LOCATION" "C5M10"
					( Origin gFrontEnd )
				)
				( attribute "MATERIAL" "X5R"
					( Origin gFrontEnd )
				)
				( attribute "PACK_TYPE" "0603V"
					( Origin gFrontEnd )
				)
				( attribute "PART_NUMBER" "602433-106"
					( Origin gFrontEnd )
				)
				( attribute "PHYS_PAGE" "220"
					( Origin gFrontEnd )
				)
				( attribute "ROT" "0"
					( Origin gFrontEnd )
				)
				( attribute "SEC" "1"
					( Origin gFrontEnd )
				)
				( attribute "SEC_TYPE" "0603V"
					( Origin gFrontEnd )
				)
				( attribute "TOLERANCE" "20%"
					( Origin gFrontEnd )
				)
				( attribute "VALUE" "47UF"
					( Origin gFrontEnd )
				)
				( attribute "VER" "1"
					( Origin gFrontEnd )
				)
				( attribute "VOLTAGE" "4V"
					( Units "uVoltage" "V" 1.000000)
					( Origin gFrontEnd )
				)
				( attribute "XY" "(3025,1675)"
					( Origin gFrontEnd )
				)
				( attribute "CHIPS_PART_NAME" "CAP_A"
					( Origin gPackager )
				)
				( attribute "CDS_PART_NAME" "CAP_A_0603V-47UF,4V,20%,X5R,60A"
					( Origin gPackager )
				)
				( objectStatus "C5M10" )
				( pin "a"
					( attribute "PN" "1"
						( Origin gPackager )
					)
					( objectStatus "C5M10.1" )
				)
				( pin "b"
					( attribute "PN" "2"
						( Origin gPackager )
					)
					( objectStatus "C5M10.2" )
				)
			)
			( gate "@baseboard_fab2_lib.baseboard_fab2(sch_1):page220_i199"
				( attribute "CDS_LIB" "dev_discrete"
					( Origin gPackager )
				)
				( attribute "CDS_LOCATION" "C5M3"
					( Origin gPackager )
				)
				( attribute "CDS_SEC" "1"
					( Origin gPackager )
				)
				( attribute "LOCATION" "C5M3"
					( Origin gFrontEnd )
				)
				( attribute "MATERIAL" "X5R"
					( Origin gFrontEnd )
				)
				( attribute "PACK_TYPE" "0603V"
					( Origin gFrontEnd )
				)
				( attribute "PART_NUMBER" "602433-106"
					( Origin gFrontEnd )
				)
				( attribute "PHYS_PAGE" "220"
					( Origin gFrontEnd )
				)
				( attribute "ROT" "0"
					( Origin gFrontEnd )
				)
				( attribute "SEC" "1"
					( Origin gFrontEnd )
				)
				( attribute "SEC_TYPE" "0603V"
					( Origin gFrontEnd )
				)
				( attribute "TOLERANCE" "20%"
					( Origin gFrontEnd )
				)
				( attribute "VALUE" "47UF"
					( Origin gFrontEnd )
				)
				( attribute "VER" "1"
					( Origin gFrontEnd )
				)
				( attribute "VOLTAGE" "4V"
					( Units "uVoltage" "V" 1.000000)
					( Origin gFrontEnd )
				)
				( attribute "XY" "(3425,1675)"
					( Origin gFrontEnd )
				)
				( attribute "CHIPS_PART_NAME" "CAP_A"
					( Origin gPackager )
				)
				( attribute "CDS_PART_NAME" "CAP_A_0603V-47UF,4V,20%,X5R,60A"
					( Origin gPackager )
				)
				( objectStatus "C5M3" )
				( pin "a"
					( attribute "PN" "1"
						( Origin gPackager )
					)
					( objectStatus "C5M3.1" )
				)
				( pin "b"
					( attribute "PN" "2"
						( Origin gPackager )
					)
					( objectStatus "C5M3.2" )
				)
			)
			( gate "@baseboard_fab2_lib.baseboard_fab2(sch_1):page220_i200"
				( attribute "CDS_LIB" "dev_discrete"
					( Origin gPackager )
				)
				( attribute "CDS_LOCATION" "C5M11"
					( Origin gPackager )
				)
				( attribute "CDS_SEC" "1"
					( Origin gPackager )
				)
				( attribute "LOCATION" "C5M11"
					( Origin gFrontEnd )
				)
				( attribute "MATERIAL" "X5R"
					( Origin gFrontEnd )
				)
				( attribute "PACK_TYPE" "0603V"
					( Origin gFrontEnd )
				)
				( attribute "PART_NUMBER" "602433-106"
					( Origin gFrontEnd )
				)
				( attribute "PHYS_PAGE" "220"
					( Origin gFrontEnd )
				)
				( attribute "ROT" "0"
					( Origin gFrontEnd )
				)
				( attribute "SEC" "1"
					( Origin gFrontEnd )
				)
				( attribute "SEC_TYPE" "0603V"
					( Origin gFrontEnd )
				)
				( attribute "TOLERANCE" "20%"
					( Origin gFrontEnd )
				)
				( attribute "VALUE" "47UF"
					( Origin gFrontEnd )
				)
				( attribute "VER" "1"
					( Origin gFrontEnd )
				)
				( attribute "VOLTAGE" "4V"
					( Units "uVoltage" "V" 1.000000)
					( Origin gFrontEnd )
				)
				( attribute "XY" "(4525,1675)"
					( Origin gFrontEnd )
				)
				( attribute "CHIPS_PART_NAME" "CAP_A"
					( Origin gPackager )
				)
				( attribute "CDS_PART_NAME" "CAP_A_0603V-47UF,4V,20%,X5R,60A"
					( Origin gPackager )
				)
				( objectStatus "C5M11" )
				( pin "a"
					( attribute "PN" "1"
						( Origin gPackager )
					)
					( objectStatus "C5M11.1" )
				)
				( pin "b"
					( attribute "PN" "2"
						( Origin gPackager )
					)
					( objectStatus "C5M11.2" )
				)
			)
			( gate "@baseboard_fab2_lib.baseboard_fab2(sch_1):page220_i203"
				( attribute "CDS_LIB" "dev_discrete"
					( Origin gPackager )
				)
				( attribute "CDS_LOCATION" "C5A19"
					( Origin gPackager )
				)
				( attribute "CDS_SEC" "1"
					( Origin gPackager )
				)
				( attribute "LOCATION" "C5A19"
					( Origin gFrontEnd )
				)
				( attribute "MATERIAL" "X6S"
					( Origin gFrontEnd )
				)
				( attribute "PACK_TYPE" "0603V"
					( Origin gFrontEnd )
				)
				( attribute "PART_NUMBER" "E15431-004"
					( Origin gFrontEnd )
				)
				( attribute "PHYS_PAGE" "220"
					( Origin gFrontEnd )
				)
				( attribute "ROOM" "PVDDQ_DEF"
					( Origin gFrontEnd )
				)
				( attribute "ROT" "0"
					( Origin gFrontEnd )
				)
				( attribute "SEC" "1"
					( Origin gPackager )
				)
				( attribute "TOLERANCE" "20%"
					( Origin gFrontEnd )
				)
				( attribute "VALUE" "22.0UF"
					( Origin gFrontEnd )
				)
				( attribute "VER" "1"
					( Origin gFrontEnd )
				)
				( attribute "VOLTAGE" "4V"
					( Units "uVoltage" "V" 1.000000)
					( Origin gFrontEnd )
				)
				( attribute "XY" "(2225,100)"
					( Origin gFrontEnd )
				)
				( attribute "CHIPS_PART_NAME" "CAP_A"
					( Origin gPackager )
				)
				( attribute "CDS_PART_NAME" "CAP_A_0603V-22.0UF,4V,20%,X6S,A"
					( Origin gPackager )
				)
				( objectStatus "C5A19" )
				( pin "a"
					( attribute "PN" "1"
						( Origin gPackager )
					)
					( objectStatus "C5A19.1" )
				)
				( pin "b"
					( attribute "PN" "2"
						( Origin gPackager )
					)
					( objectStatus "C5A19.2" )
				)
			)
			( gate "@baseboard_fab2_lib.baseboard_fab2(sch_1):page220_i204"
				( attribute "CDS_LIB" "dev_discrete"
					( Origin gPackager )
				)
				( attribute "CDS_LOCATION" "C5A18"
					( Origin gPackager )
				)
				( attribute "CDS_SEC" "1"
					( Origin gPackager )
				)
				( attribute "LOCATION" "C5A18"
					( Origin gFrontEnd )
				)
				( attribute "MATERIAL" "X6S"
					( Origin gFrontEnd )
				)
				( attribute "PACK_TYPE" "0603V"
					( Origin gFrontEnd )
				)
				( attribute "PART_NUMBER" "E15431-004"
					( Origin gFrontEnd )
				)
				( attribute "PHYS_PAGE" "220"
					( Origin gFrontEnd )
				)
				( attribute "ROOM" "PVDDQ_DEF"
					( Origin gFrontEnd )
				)
				( attribute "ROT" "0"
					( Origin gFrontEnd )
				)
				( attribute "SEC" "1"
					( Origin gPackager )
				)
				( attribute "TOLERANCE" "20%"
					( Origin gFrontEnd )
				)
				( attribute "VALUE" "22.0UF"
					( Origin gFrontEnd )
				)
				( attribute "VER" "1"
					( Origin gFrontEnd )
				)
				( attribute "VOLTAGE" "4V"
					( Units "uVoltage" "V" 1.000000)
					( Origin gFrontEnd )
				)
				( attribute "XY" "(1950,100)"
					( Origin gFrontEnd )
				)
				( attribute "CHIPS_PART_NAME" "CAP_A"
					( Origin gPackager )
				)
				( attribute "CDS_PART_NAME" "CAP_A_0603V-22.0UF,4V,20%,X6S,A"
					( Origin gPackager )
				)
				( objectStatus "C5A18" )
				( pin "a"
					( attribute "PN" "1"
						( Origin gPackager )
					)
					( objectStatus "C5A18.1" )
				)
				( pin "b"
					( attribute "PN" "2"
						( Origin gPackager )
					)
					( objectStatus "C5A18.2" )
				)
			)
			( gate "@baseboard_fab2_lib.baseboard_fab2(sch_1):page220_i205"
				( attribute "CDS_LIB" "dev_discrete"
					( Origin gPackager )
				)
				( attribute "CDS_LOCATION" "C5A17"
					( Origin gPackager )
				)
				( attribute "CDS_SEC" "1"
					( Origin gPackager )
				)
				( attribute "LOCATION" "C5A17"
					( Origin gFrontEnd )
				)
				( attribute "MATERIAL" "X6S"
					( Origin gFrontEnd )
				)
				( attribute "PACK_TYPE" "0603V"
					( Origin gFrontEnd )
				)
				( attribute "PART_NUMBER" "E15431-004"
					( Origin gFrontEnd )
				)
				( attribute "PHYS_PAGE" "220"
					( Origin gFrontEnd )
				)
				( attribute "ROOM" "PVDDQ_DEF"
					( Origin gFrontEnd )
				)
				( attribute "ROT" "0"
					( Origin gFrontEnd )
				)
				( attribute "SEC" "1"
					( Origin gPackager )
				)
				( attribute "TOLERANCE" "20%"
					( Origin gFrontEnd )
				)
				( attribute "VALUE" "22.0UF"
					( Origin gFrontEnd )
				)
				( attribute "VER" "1"
					( Origin gFrontEnd )
				)
				( attribute "VOLTAGE" "4V"
					( Units "uVoltage" "V" 1.000000)
					( Origin gFrontEnd )
				)
				( attribute "XY" "(1650,100)"
					( Origin gFrontEnd )
				)
				( attribute "CHIPS_PART_NAME" "CAP_A"
					( Origin gPackager )
				)
				( attribute "CDS_PART_NAME" "CAP_A_0603V-22.0UF,4V,20%,X6S,A"
					( Origin gPackager )
				)
				( objectStatus "C5A17" )
				( pin "a"
					( attribute "PN" "1"
						( Origin gPackager )
					)
					( objectStatus "C5A17.1" )
				)
				( pin "b"
					( attribute "PN" "2"
						( Origin gPackager )
					)
					( objectStatus "C5A17.2" )
				)
			)
			( gate "@baseboard_fab2_lib.baseboard_fab2(sch_1):page220_i206"
				( attribute "CDS_LIB" "dev_discrete"
					( Origin gPackager )
				)
				( attribute "CDS_LOCATION" "C5A4"
					( Origin gPackager )
				)
				( attribute "CDS_SEC" "1"
					( Origin gPackager )
				)
				( attribute "LOCATION" "C5A4"
					( Origin gFrontEnd )
				)
				( attribute "MATERIAL" "X6S"
					( Origin gFrontEnd )
				)
				( attribute "PACK_TYPE" "0603V"
					( Origin gFrontEnd )
				)
				( attribute "PART_NUMBER" "E15431-004"
					( Origin gFrontEnd )
				)
				( attribute "PHYS_PAGE" "220"
					( Origin gFrontEnd )
				)
				( attribute "ROOM" "PVDDQ_DEF"
					( Origin gFrontEnd )
				)
				( attribute "ROT" "0"
					( Origin gFrontEnd )
				)
				( attribute "SEC" "1"
					( Origin gFrontEnd )
				)
				( attribute "SEC_TYPE" "0603V"
					( Origin gFrontEnd )
				)
				( attribute "TOLERANCE" "20%"
					( Origin gFrontEnd )
				)
				( attribute "VALUE" "22.0UF"
					( Origin gFrontEnd )
				)
				( attribute "VER" "1"
					( Origin gFrontEnd )
				)
				( attribute "VOLTAGE" "4V"
					( Units "uVoltage" "V" 1.000000)
					( Origin gFrontEnd )
				)
				( attribute "XY" "(1350,100)"
					( Origin gFrontEnd )
				)
				( attribute "CHIPS_PART_NAME" "CAP_A"
					( Origin gPackager )
				)
				( attribute "CDS_PART_NAME" "CAP_A_0603V-22.0UF,4V,20%,X6S,A"
					( Origin gPackager )
				)
				( objectStatus "C5A4" )
				( pin "a"
					( attribute "PN" "1"
						( Origin gPackager )
					)
					( objectStatus "C5A4.1" )
				)
				( pin "b"
					( attribute "PN" "2"
						( Origin gPackager )
					)
					( objectStatus "C5A4.2" )
				)
			)
			( gate "@baseboard_fab2_lib.baseboard_fab2(sch_1):page220_i207"
				( attribute "CDS_LIB" "dev_discrete"
					( Origin gPackager )
				)
				( attribute "CDS_LOCATION" "C5A16"
					( Origin gPackager )
				)
				( attribute "CDS_SEC" "1"
					( Origin gPackager )
				)
				( attribute "LOCATION" "C5A16"
					( Origin gFrontEnd )
				)
				( attribute "MATERIAL" "X6S"
					( Origin gFrontEnd )
				)
				( attribute "PACK_TYPE" "0603V"
					( Origin gFrontEnd )
				)
				( attribute "PART_NUMBER" "E15431-004"
					( Origin gFrontEnd )
				)
				( attribute "PHYS_PAGE" "220"
					( Origin gFrontEnd )
				)
				( attribute "ROOM" "PVDDQ_DEF"
					( Origin gFrontEnd )
				)
				( attribute "ROT" "0"
					( Origin gFrontEnd )
				)
				( attribute "SEC" "1"
					( Origin gPackager )
				)
				( attribute "TOLERANCE" "20%"
					( Origin gFrontEnd )
				)
				( attribute "VALUE" "22.0UF"
					( Origin gFrontEnd )
				)
				( attribute "VER" "1"
					( Origin gFrontEnd )
				)
				( attribute "VOLTAGE" "4V"
					( Units "uVoltage" "V" 1.000000)
					( Origin gFrontEnd )
				)
				( attribute "XY" "(1075,100)"
					( Origin gFrontEnd )
				)
				( attribute "CHIPS_PART_NAME" "CAP_A"
					( Origin gPackager )
				)
				( attribute "CDS_PART_NAME" "CAP_A_0603V-22.0UF,4V,20%,X6S,A"
					( Origin gPackager )
				)
				( objectStatus "C5A16" )
				( pin "a"
					( attribute "PN" "1"
						( Origin gPackager )
					)
					( objectStatus "C5A16.1" )
				)
				( pin "b"
					( attribute "PN" "2"
						( Origin gPackager )
					)
					( objectStatus "C5A16.2" )
				)
			)
			( gate "@baseboard_fab2_lib.baseboard_fab2(sch_1):page220_i208"
				( attribute "CDS_LIB" "dev_discrete"
					( Origin gPackager )
				)
				( attribute "CDS_LOCATION" "C5A9"
					( Origin gPackager )
				)
				( attribute "CDS_SEC" "1"
					( Origin gPackager )
				)
				( attribute "LOCATION" "C5A9"
					( Origin gFrontEnd )
				)
				( attribute "MATERIAL" "X6S"
					( Origin gFrontEnd )
				)
				( attribute "PACK_TYPE" "0603V"
					( Origin gFrontEnd )
				)
				( attribute "PART_NUMBER" "E15431-004"
					( Origin gFrontEnd )
				)
				( attribute "PHYS_PAGE" "220"
					( Origin gFrontEnd )
				)
				( attribute "ROOM" "PVDDQ_DEF"
					( Origin gFrontEnd )
				)
				( attribute "ROT" "0"
					( Origin gFrontEnd )
				)
				( attribute "SEC" "1"
					( Origin gPackager )
				)
				( attribute "TOLERANCE" "20%"
					( Origin gFrontEnd )
				)
				( attribute "VALUE" "22.0UF"
					( Origin gFrontEnd )
				)
				( attribute "VER" "1"
					( Origin gFrontEnd )
				)
				( attribute "VOLTAGE" "4V"
					( Units "uVoltage" "V" 1.000000)
					( Origin gFrontEnd )
				)
				( attribute "XY" "(800,100)"
					( Origin gFrontEnd )
				)
				( attribute "CHIPS_PART_NAME" "CAP_A"
					( Origin gPackager )
				)
				( attribute "CDS_PART_NAME" "CAP_A_0603V-22.0UF,4V,20%,X6S,A"
					( Origin gPackager )
				)
				( objectStatus "C5A9" )
				( pin "a"
					( attribute "PN" "1"
						( Origin gPackager )
					)
					( objectStatus "C5A9.1" )
				)
				( pin "b"
					( attribute "PN" "2"
						( Origin gPackager )
					)
					( objectStatus "C5A9.2" )
				)
			)
			( gate "@baseboard_fab2_lib.baseboard_fab2(sch_1):page220_i209"
				( attribute "CDS_LIB" "dev_discrete"
					( Origin gPackager )
				)
				( attribute "CDS_LOCATION" "C5A8"
					( Origin gPackager )
				)
				( attribute "CDS_SEC" "1"
					( Origin gPackager )
				)
				( attribute "LOCATION" "C5A8"
					( Origin gFrontEnd )
				)
				( attribute "MATERIAL" "X6S"
					( Origin gFrontEnd )
				)
				( attribute "PACK_TYPE" "0603V"
					( Origin gFrontEnd )
				)
				( attribute "PART_NUMBER" "E15431-004"
					( Origin gFrontEnd )
				)
				( attribute "PHYS_PAGE" "220"
					( Origin gFrontEnd )
				)
				( attribute "ROOM" "PVDDQ_DEF"
					( Origin gFrontEnd )
				)
				( attribute "ROT" "0"
					( Origin gFrontEnd )
				)
				( attribute "SEC" "1"
					( Origin gPackager )
				)
				( attribute "TOLERANCE" "20%"
					( Origin gFrontEnd )
				)
				( attribute "VALUE" "22.0UF"
					( Origin gFrontEnd )
				)
				( attribute "VER" "1"
					( Origin gFrontEnd )
				)
				( attribute "VOLTAGE" "4V"
					( Units "uVoltage" "V" 1.000000)
					( Origin gFrontEnd )
				)
				( attribute "XY" "(500,100)"
					( Origin gFrontEnd )
				)
				( attribute "CHIPS_PART_NAME" "CAP_A"
					( Origin gPackager )
				)
				( attribute "CDS_PART_NAME" "CAP_A_0603V-22.0UF,4V,20%,X6S,A"
					( Origin gPackager )
				)
				( objectStatus "C5A8" )
				( pin "a"
					( attribute "PN" "1"
						( Origin gPackager )
					)
					( objectStatus "C5A8.1" )
				)
				( pin "b"
					( attribute "PN" "2"
						( Origin gPackager )
					)
					( objectStatus "C5A8.2" )
				)
			)
			( gate "@baseboard_fab2_lib.baseboard_fab2(sch_1):page220_i210"
				( attribute "CDS_LIB" "dev_discrete"
					( Origin gPackager )
				)
				( attribute "CDS_LOCATION" "C5A3"
					( Origin gPackager )
				)
				( attribute "CDS_SEC" "1"
					( Origin gPackager )
				)
				( attribute "LOCATION" "C5A3"
					( Origin gFrontEnd )
				)
				( attribute "MATERIAL" "X6S"
					( Origin gFrontEnd )
				)
				( attribute "PACK_TYPE" "0603V"
					( Origin gFrontEnd )
				)
				( attribute "PART_NUMBER" "E15431-004"
					( Origin gFrontEnd )
				)
				( attribute "PHYS_PAGE" "220"
					( Origin gFrontEnd )
				)
				( attribute "ROOM" "PVDDQ_DEF"
					( Origin gFrontEnd )
				)
				( attribute "ROT" "0"
					( Origin gFrontEnd )
				)
				( attribute "SEC" "1"
					( Origin gFrontEnd )
				)
				( attribute "SEC_TYPE" "0603V"
					( Origin gFrontEnd )
				)
				( attribute "TOLERANCE" "20%"
					( Origin gFrontEnd )
				)
				( attribute "VALUE" "22.0UF"
					( Origin gFrontEnd )
				)
				( attribute "VER" "1"
					( Origin gFrontEnd )
				)
				( attribute "VOLTAGE" "4V"
					( Units "uVoltage" "V" 1.000000)
					( Origin gFrontEnd )
				)
				( attribute "XY" "(200,100)"
					( Origin gFrontEnd )
				)
				( attribute "CHIPS_PART_NAME" "CAP_A"
					( Origin gPackager )
				)
				( attribute "CDS_PART_NAME" "CAP_A_0603V-22.0UF,4V,20%,X6S,A"
					( Origin gPackager )
				)
				( objectStatus "C5A3" )
				( pin "a"
					( attribute "PN" "1"
						( Origin gPackager )
					)
					( objectStatus "C5A3.1" )
				)
				( pin "b"
					( attribute "PN" "2"
						( Origin gPackager )
					)
					( objectStatus "C5A3.2" )
				)
			)
			( gate "@baseboard_fab2_lib.baseboard_fab2(sch_1):page220_i211"
				( attribute "CDS_LIB" "dev_discrete"
					( Origin gPackager )
				)
				( attribute "CDS_LOCATION" "C5A7"
					( Origin gPackager )
				)
				( attribute "CDS_SEC" "1"
					( Origin gPackager )
				)
				( attribute "LOCATION" "C5A7"
					( Origin gFrontEnd )
				)
				( attribute "MATERIAL" "X6S"
					( Origin gFrontEnd )
				)
				( attribute "PACK_TYPE" "0603V"
					( Origin gFrontEnd )
				)
				( attribute "PART_NUMBER" "E15431-004"
					( Origin gFrontEnd )
				)
				( attribute "PHYS_PAGE" "220"
					( Origin gFrontEnd )
				)
				( attribute "ROOM" "PVDDQ_DEF"
					( Origin gFrontEnd )
				)
				( attribute "ROT" "0"
					( Origin gFrontEnd )
				)
				( attribute "SEC" "1"
					( Origin gPackager )
				)
				( attribute "TOLERANCE" "20%"
					( Origin gFrontEnd )
				)
				( attribute "VALUE" "22.0UF"
					( Origin gFrontEnd )
				)
				( attribute "VER" "1"
					( Origin gFrontEnd )
				)
				( attribute "VOLTAGE" "4V"
					( Units "uVoltage" "V" 1.000000)
					( Origin gFrontEnd )
				)
				( attribute "XY" "(-125,100)"
					( Origin gFrontEnd )
				)
				( attribute "CHIPS_PART_NAME" "CAP_A"
					( Origin gPackager )
				)
				( attribute "CDS_PART_NAME" "CAP_A_0603V-22.0UF,4V,20%,X6S,A"
					( Origin gPackager )
				)
				( objectStatus "C5A7" )
				( pin "a"
					( attribute "PN" "1"
						( Origin gPackager )
					)
					( objectStatus "C5A7.1" )
				)
				( pin "b"
					( attribute "PN" "2"
						( Origin gPackager )
					)
					( objectStatus "C5A7.2" )
				)
			)
			( gate "@baseboard_fab2_lib.baseboard_fab2(sch_1):page220_i212"
				( attribute "CDS_LIB" "dev_discrete"
					( Origin gPackager )
				)
				( attribute "CDS_LOCATION" "C5A6"
					( Origin gPackager )
				)
				( attribute "CDS_SEC" "1"
					( Origin gPackager )
				)
				( attribute "LOCATION" "C5A6"
					( Origin gFrontEnd )
				)
				( attribute "MATERIAL" "X6S"
					( Origin gFrontEnd )
				)
				( attribute "PACK_TYPE" "0603V"
					( Origin gFrontEnd )
				)
				( attribute "PART_NUMBER" "E15431-004"
					( Origin gFrontEnd )
				)
				( attribute "PHYS_PAGE" "220"
					( Origin gFrontEnd )
				)
				( attribute "ROOM" "PVDDQ_DEF"
					( Origin gFrontEnd )
				)
				( attribute "ROT" "0"
					( Origin gFrontEnd )
				)
				( attribute "SEC" "1"
					( Origin gPackager )
				)
				( attribute "TOLERANCE" "20%"
					( Origin gFrontEnd )
				)
				( attribute "VALUE" "22.0UF"
					( Origin gFrontEnd )
				)
				( attribute "VER" "1"
					( Origin gFrontEnd )
				)
				( attribute "VOLTAGE" "4V"
					( Units "uVoltage" "V" 1.000000)
					( Origin gFrontEnd )
				)
				( attribute "XY" "(-400,100)"
					( Origin gFrontEnd )
				)
				( attribute "CHIPS_PART_NAME" "CAP_A"
					( Origin gPackager )
				)
				( attribute "CDS_PART_NAME" "CAP_A_0603V-22.0UF,4V,20%,X6S,A"
					( Origin gPackager )
				)
				( objectStatus "C5A6" )
				( pin "a"
					( attribute "PN" "1"
						( Origin gPackager )
					)
					( objectStatus "C5A6.1" )
				)
				( pin "b"
					( attribute "PN" "2"
						( Origin gPackager )
					)
					( objectStatus "C5A6.2" )
				)
			)
			( gate "@baseboard_fab2_lib.baseboard_fab2(sch_1):page220_i213"
				( attribute "CDS_LIB" "dev_discrete"
					( Origin gPackager )
				)
				( attribute "CDS_LOCATION" "C5A14"
					( Origin gPackager )
				)
				( attribute "CDS_SEC" "1"
					( Origin gPackager )
				)
				( attribute "LOCATION" "C5A14"
					( Origin gFrontEnd )
				)
				( attribute "MATERIAL" "X6S"
					( Origin gFrontEnd )
				)
				( attribute "PACK_TYPE" "0603V"
					( Origin gFrontEnd )
				)
				( attribute "PART_NUMBER" "E15431-004"
					( Origin gFrontEnd )
				)
				( attribute "PHYS_PAGE" "220"
					( Origin gFrontEnd )
				)
				( attribute "ROOM" "PVDDQ_DEF"
					( Origin gFrontEnd )
				)
				( attribute "ROT" "0"
					( Origin gFrontEnd )
				)
				( attribute "SEC" "1"
					( Origin gPackager )
				)
				( attribute "TOLERANCE" "20%"
					( Origin gFrontEnd )
				)
				( attribute "VALUE" "22.0UF"
					( Origin gFrontEnd )
				)
				( attribute "VER" "1"
					( Origin gFrontEnd )
				)
				( attribute "VOLTAGE" "4V"
					( Units "uVoltage" "V" 1.000000)
					( Origin gFrontEnd )
				)
				( attribute "XY" "(-700,100)"
					( Origin gFrontEnd )
				)
				( attribute "CHIPS_PART_NAME" "CAP_A"
					( Origin gPackager )
				)
				( attribute "CDS_PART_NAME" "CAP_A_0603V-22.0UF,4V,20%,X6S,A"
					( Origin gPackager )
				)
				( objectStatus "C5A14" )
				( pin "a"
					( attribute "PN" "1"
						( Origin gPackager )
					)
					( objectStatus "C5A14.1" )
				)
				( pin "b"
					( attribute "PN" "2"
						( Origin gPackager )
					)
					( objectStatus "C5A14.2" )
				)
			)
			( gate "@baseboard_fab2_lib.baseboard_fab2(sch_1):page220_i214"
				( attribute "CDS_LIB" "dev_discrete"
					( Origin gPackager )
				)
				( attribute "CDS_LOCATION" "C5A2"
					( Origin gPackager )
				)
				( attribute "CDS_SEC" "1"
					( Origin gPackager )
				)
				( attribute "LOCATION" "C5A2"
					( Origin gFrontEnd )
				)
				( attribute "MATERIAL" "X6S"
					( Origin gFrontEnd )
				)
				( attribute "PACK_TYPE" "0603V"
					( Origin gFrontEnd )
				)
				( attribute "PART_NUMBER" "E15431-004"
					( Origin gFrontEnd )
				)
				( attribute "PHYS_PAGE" "220"
					( Origin gFrontEnd )
				)
				( attribute "ROOM" "PVDDQ_DEF"
					( Origin gFrontEnd )
				)
				( attribute "ROT" "0"
					( Origin gFrontEnd )
				)
				( attribute "SEC" "1"
					( Origin gFrontEnd )
				)
				( attribute "SEC_TYPE" "0603V"
					( Origin gFrontEnd )
				)
				( attribute "TOLERANCE" "20%"
					( Origin gFrontEnd )
				)
				( attribute "VALUE" "22.0UF"
					( Origin gFrontEnd )
				)
				( attribute "VER" "1"
					( Origin gFrontEnd )
				)
				( attribute "VOLTAGE" "4V"
					( Units "uVoltage" "V" 1.000000)
					( Origin gFrontEnd )
				)
				( attribute "XY" "(-1000,100)"
					( Origin gFrontEnd )
				)
				( attribute "CHIPS_PART_NAME" "CAP_A"
					( Origin gPackager )
				)
				( attribute "CDS_PART_NAME" "CAP_A_0603V-22.0UF,4V,20%,X6S,A"
					( Origin gPackager )
				)
				( objectStatus "C5A2" )
				( pin "a"
					( attribute "PN" "1"
						( Origin gPackager )
					)
					( objectStatus "C5A2.1" )
				)
				( pin "b"
					( attribute "PN" "2"
						( Origin gPackager )
					)
					( objectStatus "C5A2.2" )
				)
			)
			( gate "@baseboard_fab2_lib.baseboard_fab2(sch_1):page220_i215"
				( attribute "CDS_LIB" "dev_discrete"
					( Origin gPackager )
				)
				( attribute "CDS_LOCATION" "C5A13"
					( Origin gPackager )
				)
				( attribute "CDS_SEC" "1"
					( Origin gPackager )
				)
				( attribute "LOCATION" "C5A13"
					( Origin gFrontEnd )
				)
				( attribute "MATERIAL" "X6S"
					( Origin gFrontEnd )
				)
				( attribute "PACK_TYPE" "0603V"
					( Origin gFrontEnd )
				)
				( attribute "PART_NUMBER" "E15431-004"
					( Origin gFrontEnd )
				)
				( attribute "PHYS_PAGE" "220"
					( Origin gFrontEnd )
				)
				( attribute "ROOM" "PVDDQ_DEF"
					( Origin gFrontEnd )
				)
				( attribute "ROT" "0"
					( Origin gFrontEnd )
				)
				( attribute "SEC" "1"
					( Origin gPackager )
				)
				( attribute "TOLERANCE" "20%"
					( Origin gFrontEnd )
				)
				( attribute "VALUE" "22.0UF"
					( Origin gFrontEnd )
				)
				( attribute "VER" "1"
					( Origin gFrontEnd )
				)
				( attribute "VOLTAGE" "4V"
					( Units "uVoltage" "V" 1.000000)
					( Origin gFrontEnd )
				)
				( attribute "XY" "(-1275,100)"
					( Origin gFrontEnd )
				)
				( attribute "CHIPS_PART_NAME" "CAP_A"
					( Origin gPackager )
				)
				( attribute "CDS_PART_NAME" "CAP_A_0603V-22.0UF,4V,20%,X6S,A"
					( Origin gPackager )
				)
				( objectStatus "C5A13" )
				( pin "a"
					( attribute "PN" "1"
						( Origin gPackager )
					)
					( objectStatus "C5A13.1" )
				)
				( pin "b"
					( attribute "PN" "2"
						( Origin gPackager )
					)
					( objectStatus "C5A13.2" )
				)
			)
			( gate "@baseboard_fab2_lib.baseboard_fab2(sch_1):page220_i216"
				( attribute "CDS_LIB" "dev_discrete"
					( Origin gPackager )
				)
				( attribute "CDS_LOCATION" "C5A12"
					( Origin gPackager )
				)
				( attribute "CDS_SEC" "1"
					( Origin gPackager )
				)
				( attribute "LOCATION" "C5A12"
					( Origin gFrontEnd )
				)
				( attribute "MATERIAL" "X6S"
					( Origin gFrontEnd )
				)
				( attribute "PACK_TYPE" "0603V"
					( Origin gFrontEnd )
				)
				( attribute "PART_NUMBER" "E15431-004"
					( Origin gFrontEnd )
				)
				( attribute "PHYS_PAGE" "220"
					( Origin gFrontEnd )
				)
				( attribute "ROOM" "PVDDQ_DEF"
					( Origin gFrontEnd )
				)
				( attribute "ROT" "0"
					( Origin gFrontEnd )
				)
				( attribute "SEC" "1"
					( Origin gPackager )
				)
				( attribute "TOLERANCE" "20%"
					( Origin gFrontEnd )
				)
				( attribute "VALUE" "22.0UF"
					( Origin gFrontEnd )
				)
				( attribute "VER" "1"
					( Origin gFrontEnd )
				)
				( attribute "VOLTAGE" "4V"
					( Units "uVoltage" "V" 1.000000)
					( Origin gFrontEnd )
				)
				( attribute "XY" "(-1550,100)"
					( Origin gFrontEnd )
				)
				( attribute "CHIPS_PART_NAME" "CAP_A"
					( Origin gPackager )
				)
				( attribute "CDS_PART_NAME" "CAP_A_0603V-22.0UF,4V,20%,X6S,A"
					( Origin gPackager )
				)
				( objectStatus "C5A12" )
				( pin "a"
					( attribute "PN" "1"
						( Origin gPackager )
					)
					( objectStatus "C5A12.1" )
				)
				( pin "b"
					( attribute "PN" "2"
						( Origin gPackager )
					)
					( objectStatus "C5A12.2" )
				)
			)
			( gate "@baseboard_fab2_lib.baseboard_fab2(sch_1):page220_i217"
				( attribute "CDS_LIB" "dev_discrete"
					( Origin gPackager )
				)
				( attribute "CDS_LOCATION" "C5A15"
					( Origin gPackager )
				)
				( attribute "CDS_SEC" "1"
					( Origin gPackager )
				)
				( attribute "LOCATION" "C5A15"
					( Origin gFrontEnd )
				)
				( attribute "MATERIAL" "X6S"
					( Origin gFrontEnd )
				)
				( attribute "PACK_TYPE" "0603V"
					( Origin gFrontEnd )
				)
				( attribute "PART_NUMBER" "E15431-004"
					( Origin gFrontEnd )
				)
				( attribute "PHYS_PAGE" "220"
					( Origin gFrontEnd )
				)
				( attribute "ROOM" "PVDDQ_DEF"
					( Origin gFrontEnd )
				)
				( attribute "ROT" "0"
					( Origin gFrontEnd )
				)
				( attribute "SEC" "1"
					( Origin gPackager )
				)
				( attribute "TOLERANCE" "20%"
					( Origin gFrontEnd )
				)
				( attribute "VALUE" "22.0UF"
					( Origin gFrontEnd )
				)
				( attribute "VER" "1"
					( Origin gFrontEnd )
				)
				( attribute "VOLTAGE" "4V"
					( Units "uVoltage" "V" 1.000000)
					( Origin gFrontEnd )
				)
				( attribute "XY" "(-1850,100)"
					( Origin gFrontEnd )
				)
				( attribute "CHIPS_PART_NAME" "CAP_A"
					( Origin gPackager )
				)
				( attribute "CDS_PART_NAME" "CAP_A_0603V-22.0UF,4V,20%,X6S,A"
					( Origin gPackager )
				)
				( objectStatus "C5A15" )
				( pin "a"
					( attribute "PN" "1"
						( Origin gPackager )
					)
					( objectStatus "C5A15.1" )
				)
				( pin "b"
					( attribute "PN" "2"
						( Origin gPackager )
					)
					( objectStatus "C5A15.2" )
				)
			)
			( gate "@baseboard_fab2_lib.baseboard_fab2(sch_1):page220_i219"
				( attribute "CDS_LIB" "dev_discrete"
					( Origin gPackager )
				)
				( attribute "CDS_LOCATION" "C5A1"
					( Origin gPackager )
				)
				( attribute "CDS_SEC" "1"
					( Origin gPackager )
				)
				( attribute "LOCATION" "C5A1"
					( Origin gFrontEnd )
				)
				( attribute "MATERIAL" "X6S"
					( Origin gFrontEnd )
				)
				( attribute "PACK_TYPE" "0603V"
					( Origin gFrontEnd )
				)
				( attribute "PART_NUMBER" "E15431-004"
					( Origin gFrontEnd )
				)
				( attribute "PHYS_PAGE" "220"
					( Origin gFrontEnd )
				)
				( attribute "ROOM" "PVDDQ_DEF"
					( Origin gFrontEnd )
				)
				( attribute "ROT" "0"
					( Origin gFrontEnd )
				)
				( attribute "SEC" "1"
					( Origin gFrontEnd )
				)
				( attribute "SEC_TYPE" "0603V"
					( Origin gFrontEnd )
				)
				( attribute "TOLERANCE" "20%"
					( Origin gFrontEnd )
				)
				( attribute "VALUE" "22.0UF"
					( Origin gFrontEnd )
				)
				( attribute "VER" "1"
					( Origin gFrontEnd )
				)
				( attribute "VOLTAGE" "4V"
					( Units "uVoltage" "V" 1.000000)
					( Origin gFrontEnd )
				)
				( attribute "XY" "(-2150,100)"
					( Origin gFrontEnd )
				)
				( attribute "CHIPS_PART_NAME" "CAP_A"
					( Origin gPackager )
				)
				( attribute "CDS_PART_NAME" "CAP_A_0603V-22.0UF,4V,20%,X6S,A"
					( Origin gPackager )
				)
				( objectStatus "C5A1" )
				( pin "a"
					( attribute "PN" "1"
						( Origin gPackager )
					)
					( objectStatus "C5A1.1" )
				)
				( pin "b"
					( attribute "PN" "2"
						( Origin gPackager )
					)
					( objectStatus "C5A1.2" )
				)
			)
			( gate "@baseboard_fab2_lib.baseboard_fab2(sch_1):page220_i221"
				( attribute "CDS_LIB" "dev_discrete"
					( Origin gPackager )
				)
				( attribute "CDS_LOCATION" "C5A11"
					( Origin gPackager )
				)
				( attribute "CDS_SEC" "1"
					( Origin gPackager )
				)
				( attribute "LOCATION" "C5A11"
					( Origin gFrontEnd )
				)
				( attribute "MATERIAL" "X6S"
					( Origin gFrontEnd )
				)
				( attribute "PACK_TYPE" "0603V"
					( Origin gFrontEnd )
				)
				( attribute "PART_NUMBER" "E15431-004"
					( Origin gFrontEnd )
				)
				( attribute "PHYS_PAGE" "220"
					( Origin gFrontEnd )
				)
				( attribute "ROOM" "PVDDQ_DEF"
					( Origin gFrontEnd )
				)
				( attribute "ROT" "0"
					( Origin gFrontEnd )
				)
				( attribute "SEC" "1"
					( Origin gPackager )
				)
				( attribute "TOLERANCE" "20%"
					( Origin gFrontEnd )
				)
				( attribute "VALUE" "22.0UF"
					( Origin gFrontEnd )
				)
				( attribute "VER" "1"
					( Origin gFrontEnd )
				)
				( attribute "VOLTAGE" "4V"
					( Units "uVoltage" "V" 1.000000)
					( Origin gFrontEnd )
				)
				( attribute "XY" "(2225,-650)"
					( Origin gFrontEnd )
				)
				( attribute "CHIPS_PART_NAME" "CAP_A"
					( Origin gPackager )
				)
				( attribute "CDS_PART_NAME" "CAP_A_0603V-22.0UF,4V,20%,X6S,A"
					( Origin gPackager )
				)
				( objectStatus "C5A11" )
				( pin "a"
					( attribute "PN" "1"
						( Origin gPackager )
					)
					( objectStatus "C5A11.1" )
				)
				( pin "b"
					( attribute "PN" "2"
						( Origin gPackager )
					)
					( objectStatus "C5A11.2" )
				)
			)
			( gate "@baseboard_fab2_lib.baseboard_fab2(sch_1):page220_i222"
				( attribute "CDS_LIB" "dev_discrete"
					( Origin gPackager )
				)
				( attribute "CDS_LOCATION" "C4M2"
					( Origin gPackager )
				)
				( attribute "CDS_SEC" "1"
					( Origin gPackager )
				)
				( attribute "LOCATION" "C4M2"
					( Origin gFrontEnd )
				)
				( attribute "MATERIAL" "X6S"
					( Origin gFrontEnd )
				)
				( attribute "PACK_TYPE" "0603V"
					( Origin gFrontEnd )
				)
				( attribute "PART_NUMBER" "E15431-004"
					( Origin gFrontEnd )
				)
				( attribute "PHYS_PAGE" "220"
					( Origin gFrontEnd )
				)
				( attribute "ROOM" "PVDDQ_DEF"
					( Origin gFrontEnd )
				)
				( attribute "ROT" "0"
					( Origin gFrontEnd )
				)
				( attribute "SEC" "1"
					( Origin gPackager )
				)
				( attribute "TOLERANCE" "20%"
					( Origin gFrontEnd )
				)
				( attribute "VALUE" "22.0UF"
					( Origin gFrontEnd )
				)
				( attribute "VER" "1"
					( Origin gFrontEnd )
				)
				( attribute "VOLTAGE" "4V"
					( Units "uVoltage" "V" 1.000000)
					( Origin gFrontEnd )
				)
				( attribute "XY" "(1950,-650)"
					( Origin gFrontEnd )
				)
				( attribute "CHIPS_PART_NAME" "CAP_A"
					( Origin gPackager )
				)
				( attribute "CDS_PART_NAME" "CAP_A_0603V-22.0UF,4V,20%,X6S,A"
					( Origin gPackager )
				)
				( objectStatus "C4M2" )
				( pin "a"
					( attribute "PN" "1"
						( Origin gPackager )
					)
					( objectStatus "C4M2.1" )
				)
				( pin "b"
					( attribute "PN" "2"
						( Origin gPackager )
					)
					( objectStatus "C4M2.2" )
				)
			)
			( gate "@baseboard_fab2_lib.baseboard_fab2(sch_1):page220_i223"
				( attribute "CDS_LIB" "dev_discrete"
					( Origin gPackager )
				)
				( attribute "CDS_LOCATION" "C5M1"
					( Origin gPackager )
				)
				( attribute "CDS_SEC" "1"
					( Origin gPackager )
				)
				( attribute "LOCATION" "C5M1"
					( Origin gFrontEnd )
				)
				( attribute "MATERIAL" "X6S"
					( Origin gFrontEnd )
				)
				( attribute "PACK_TYPE" "0603V"
					( Origin gFrontEnd )
				)
				( attribute "PART_NUMBER" "E15431-004"
					( Origin gFrontEnd )
				)
				( attribute "PHYS_PAGE" "220"
					( Origin gFrontEnd )
				)
				( attribute "ROOM" "PVDDQ_DEF"
					( Origin gFrontEnd )
				)
				( attribute "ROT" "0"
					( Origin gFrontEnd )
				)
				( attribute "SEC" "1"
					( Origin gPackager )
				)
				( attribute "TOLERANCE" "20%"
					( Origin gFrontEnd )
				)
				( attribute "VALUE" "22.0UF"
					( Origin gFrontEnd )
				)
				( attribute "VER" "1"
					( Origin gFrontEnd )
				)
				( attribute "VOLTAGE" "4V"
					( Units "uVoltage" "V" 1.000000)
					( Origin gFrontEnd )
				)
				( attribute "XY" "(1650,-650)"
					( Origin gFrontEnd )
				)
				( attribute "CHIPS_PART_NAME" "CAP_A"
					( Origin gPackager )
				)
				( attribute "CDS_PART_NAME" "CAP_A_0603V-22.0UF,4V,20%,X6S,A"
					( Origin gPackager )
				)
				( objectStatus "C5M1" )
				( pin "a"
					( attribute "PN" "1"
						( Origin gPackager )
					)
					( objectStatus "C5M1.1" )
				)
				( pin "b"
					( attribute "PN" "2"
						( Origin gPackager )
					)
					( objectStatus "C5M1.2" )
				)
			)
			( gate "@baseboard_fab2_lib.baseboard_fab2(sch_1):page220_i224"
				( attribute "CDS_LIB" "dev_discrete"
					( Origin gPackager )
				)
				( attribute "CDS_LOCATION" "C5M2"
					( Origin gPackager )
				)
				( attribute "CDS_SEC" "1"
					( Origin gPackager )
				)
				( attribute "LOCATION" "C5M2"
					( Origin gFrontEnd )
				)
				( attribute "MATERIAL" "X6S"
					( Origin gFrontEnd )
				)
				( attribute "PACK_TYPE" "0603V"
					( Origin gFrontEnd )
				)
				( attribute "PART_NUMBER" "E15431-004"
					( Origin gFrontEnd )
				)
				( attribute "PHYS_PAGE" "220"
					( Origin gFrontEnd )
				)
				( attribute "ROOM" "PVDDQ_DEF"
					( Origin gFrontEnd )
				)
				( attribute "ROT" "0"
					( Origin gFrontEnd )
				)
				( attribute "SEC" "1"
					( Origin gPackager )
				)
				( attribute "TOLERANCE" "20%"
					( Origin gFrontEnd )
				)
				( attribute "VALUE" "22.0UF"
					( Origin gFrontEnd )
				)
				( attribute "VER" "1"
					( Origin gFrontEnd )
				)
				( attribute "VOLTAGE" "4V"
					( Units "uVoltage" "V" 1.000000)
					( Origin gFrontEnd )
				)
				( attribute "XY" "(1350,-650)"
					( Origin gFrontEnd )
				)
				( attribute "CHIPS_PART_NAME" "CAP_A"
					( Origin gPackager )
				)
				( attribute "CDS_PART_NAME" "CAP_A_0603V-22.0UF,4V,20%,X6S,A"
					( Origin gPackager )
				)
				( objectStatus "C5M2" )
				( pin "a"
					( attribute "PN" "1"
						( Origin gPackager )
					)
					( objectStatus "C5M2.1" )
				)
				( pin "b"
					( attribute "PN" "2"
						( Origin gPackager )
					)
					( objectStatus "C5M2.2" )
				)
			)
			( gate "@baseboard_fab2_lib.baseboard_fab2(sch_1):page220_i225"
				( attribute "CDS_LIB" "dev_discrete"
					( Origin gPackager )
				)
				( attribute "CDS_LOCATION" "C5M4"
					( Origin gPackager )
				)
				( attribute "CDS_SEC" "1"
					( Origin gPackager )
				)
				( attribute "LOCATION" "C5M4"
					( Origin gFrontEnd )
				)
				( attribute "MATERIAL" "X6S"
					( Origin gFrontEnd )
				)
				( attribute "PACK_TYPE" "0603V"
					( Origin gFrontEnd )
				)
				( attribute "PART_NUMBER" "E15431-004"
					( Origin gFrontEnd )
				)
				( attribute "PHYS_PAGE" "220"
					( Origin gFrontEnd )
				)
				( attribute "ROOM" "PVDDQ_DEF"
					( Origin gFrontEnd )
				)
				( attribute "ROT" "0"
					( Origin gFrontEnd )
				)
				( attribute "SEC" "1"
					( Origin gPackager )
				)
				( attribute "TOLERANCE" "20%"
					( Origin gFrontEnd )
				)
				( attribute "VALUE" "22.0UF"
					( Origin gFrontEnd )
				)
				( attribute "VER" "1"
					( Origin gFrontEnd )
				)
				( attribute "VOLTAGE" "4V"
					( Units "uVoltage" "V" 1.000000)
					( Origin gFrontEnd )
				)
				( attribute "XY" "(1075,-650)"
					( Origin gFrontEnd )
				)
				( attribute "CHIPS_PART_NAME" "CAP_A"
					( Origin gPackager )
				)
				( attribute "CDS_PART_NAME" "CAP_A_0603V-22.0UF,4V,20%,X6S,A"
					( Origin gPackager )
				)
				( objectStatus "C5M4" )
				( pin "a"
					( attribute "PN" "1"
						( Origin gPackager )
					)
					( objectStatus "C5M4.1" )
				)
				( pin "b"
					( attribute "PN" "2"
						( Origin gPackager )
					)
					( objectStatus "C5M4.2" )
				)
			)
			( gate "@baseboard_fab2_lib.baseboard_fab2(sch_1):page220_i226"
				( attribute "CDS_LIB" "dev_discrete"
					( Origin gPackager )
				)
				( attribute "CDS_LOCATION" "C5M5"
					( Origin gPackager )
				)
				( attribute "CDS_SEC" "1"
					( Origin gPackager )
				)
				( attribute "LOCATION" "C5M5"
					( Origin gFrontEnd )
				)
				( attribute "MATERIAL" "X6S"
					( Origin gFrontEnd )
				)
				( attribute "PACK_TYPE" "0603V"
					( Origin gFrontEnd )
				)
				( attribute "PART_NUMBER" "E15431-004"
					( Origin gFrontEnd )
				)
				( attribute "PHYS_PAGE" "220"
					( Origin gFrontEnd )
				)
				( attribute "ROOM" "PVDDQ_DEF"
					( Origin gFrontEnd )
				)
				( attribute "ROT" "0"
					( Origin gFrontEnd )
				)
				( attribute "SEC" "1"
					( Origin gPackager )
				)
				( attribute "TOLERANCE" "20%"
					( Origin gFrontEnd )
				)
				( attribute "VALUE" "22.0UF"
					( Origin gFrontEnd )
				)
				( attribute "VER" "1"
					( Origin gFrontEnd )
				)
				( attribute "VOLTAGE" "4V"
					( Units "uVoltage" "V" 1.000000)
					( Origin gFrontEnd )
				)
				( attribute "XY" "(800,-650)"
					( Origin gFrontEnd )
				)
				( attribute "CHIPS_PART_NAME" "CAP_A"
					( Origin gPackager )
				)
				( attribute "CDS_PART_NAME" "CAP_A_0603V-22.0UF,4V,20%,X6S,A"
					( Origin gPackager )
				)
				( objectStatus "C5M5" )
				( pin "a"
					( attribute "PN" "1"
						( Origin gPackager )
					)
					( objectStatus "C5M5.1" )
				)
				( pin "b"
					( attribute "PN" "2"
						( Origin gPackager )
					)
					( objectStatus "C5M5.2" )
				)
			)
			( gate "@baseboard_fab2_lib.baseboard_fab2(sch_1):page220_i227"
				( attribute "CDS_LIB" "dev_discrete"
					( Origin gPackager )
				)
				( attribute "CDS_LOCATION" "C5M6"
					( Origin gPackager )
				)
				( attribute "CDS_SEC" "1"
					( Origin gPackager )
				)
				( attribute "LOCATION" "C5M6"
					( Origin gFrontEnd )
				)
				( attribute "MATERIAL" "X6S"
					( Origin gFrontEnd )
				)
				( attribute "PACK_TYPE" "0603V"
					( Origin gFrontEnd )
				)
				( attribute "PART_NUMBER" "E15431-004"
					( Origin gFrontEnd )
				)
				( attribute "PHYS_PAGE" "220"
					( Origin gFrontEnd )
				)
				( attribute "ROOM" "PVDDQ_DEF"
					( Origin gFrontEnd )
				)
				( attribute "ROT" "0"
					( Origin gFrontEnd )
				)
				( attribute "SEC" "1"
					( Origin gPackager )
				)
				( attribute "TOLERANCE" "20%"
					( Origin gFrontEnd )
				)
				( attribute "VALUE" "22.0UF"
					( Origin gFrontEnd )
				)
				( attribute "VER" "1"
					( Origin gFrontEnd )
				)
				( attribute "VOLTAGE" "4V"
					( Units "uVoltage" "V" 1.000000)
					( Origin gFrontEnd )
				)
				( attribute "XY" "(500,-650)"
					( Origin gFrontEnd )
				)
				( attribute "CHIPS_PART_NAME" "CAP_A"
					( Origin gPackager )
				)
				( attribute "CDS_PART_NAME" "CAP_A_0603V-22.0UF,4V,20%,X6S,A"
					( Origin gPackager )
				)
				( objectStatus "C5M6" )
				( pin "a"
					( attribute "PN" "1"
						( Origin gPackager )
					)
					( objectStatus "C5M6.1" )
				)
				( pin "b"
					( attribute "PN" "2"
						( Origin gPackager )
					)
					( objectStatus "C5M6.2" )
				)
			)
			( gate "@baseboard_fab2_lib.baseboard_fab2(sch_1):page220_i228"
				( attribute "CDS_LIB" "dev_discrete"
					( Origin gPackager )
				)
				( attribute "CDS_LOCATION" "C5M7"
					( Origin gPackager )
				)
				( attribute "CDS_SEC" "1"
					( Origin gPackager )
				)
				( attribute "LOCATION" "C5M7"
					( Origin gFrontEnd )
				)
				( attribute "MATERIAL" "X6S"
					( Origin gFrontEnd )
				)
				( attribute "PACK_TYPE" "0603V"
					( Origin gFrontEnd )
				)
				( attribute "PART_NUMBER" "E15431-004"
					( Origin gFrontEnd )
				)
				( attribute "PHYS_PAGE" "220"
					( Origin gFrontEnd )
				)
				( attribute "ROOM" "PVDDQ_DEF"
					( Origin gFrontEnd )
				)
				( attribute "ROT" "0"
					( Origin gFrontEnd )
				)
				( attribute "SEC" "1"
					( Origin gPackager )
				)
				( attribute "TOLERANCE" "20%"
					( Origin gFrontEnd )
				)
				( attribute "VALUE" "22.0UF"
					( Origin gFrontEnd )
				)
				( attribute "VER" "1"
					( Origin gFrontEnd )
				)
				( attribute "VOLTAGE" "4V"
					( Units "uVoltage" "V" 1.000000)
					( Origin gFrontEnd )
				)
				( attribute "XY" "(200,-650)"
					( Origin gFrontEnd )
				)
				( attribute "CHIPS_PART_NAME" "CAP_A"
					( Origin gPackager )
				)
				( attribute "CDS_PART_NAME" "CAP_A_0603V-22.0UF,4V,20%,X6S,A"
					( Origin gPackager )
				)
				( objectStatus "C5M7" )
				( pin "a"
					( attribute "PN" "1"
						( Origin gPackager )
					)
					( objectStatus "C5M7.1" )
				)
				( pin "b"
					( attribute "PN" "2"
						( Origin gPackager )
					)
					( objectStatus "C5M7.2" )
				)
			)
			( gate "@baseboard_fab2_lib.baseboard_fab2(sch_1):page220_i229"
				( attribute "CDS_LIB" "dev_discrete"
					( Origin gPackager )
				)
				( attribute "CDS_LOCATION" "C5L13"
					( Origin gPackager )
				)
				( attribute "CDS_SEC" "1"
					( Origin gPackager )
				)
				( attribute "LOCATION" "C5L13"
					( Origin gFrontEnd )
				)
				( attribute "MATERIAL" "X6S"
					( Origin gFrontEnd )
				)
				( attribute "PACK_TYPE" "0603V"
					( Origin gFrontEnd )
				)
				( attribute "PART_NUMBER" "E15431-004"
					( Origin gFrontEnd )
				)
				( attribute "PHYS_PAGE" "220"
					( Origin gFrontEnd )
				)
				( attribute "ROOM" "PVDDQ_DEF"
					( Origin gFrontEnd )
				)
				( attribute "ROT" "0"
					( Origin gFrontEnd )
				)
				( attribute "SEC" "1"
					( Origin gPackager )
				)
				( attribute "TOLERANCE" "20%"
					( Origin gFrontEnd )
				)
				( attribute "VALUE" "22.0UF"
					( Origin gFrontEnd )
				)
				( attribute "VER" "1"
					( Origin gFrontEnd )
				)
				( attribute "VOLTAGE" "4V"
					( Units "uVoltage" "V" 1.000000)
					( Origin gFrontEnd )
				)
				( attribute "XY" "(-125,-650)"
					( Origin gFrontEnd )
				)
				( attribute "CHIPS_PART_NAME" "CAP_A"
					( Origin gPackager )
				)
				( attribute "CDS_PART_NAME" "CAP_A_0603V-22.0UF,4V,20%,X6S,A"
					( Origin gPackager )
				)
				( objectStatus "C5L13" )
				( pin "a"
					( attribute "PN" "1"
						( Origin gPackager )
					)
					( objectStatus "C5L13.1" )
				)
				( pin "b"
					( attribute "PN" "2"
						( Origin gPackager )
					)
					( objectStatus "C5L13.2" )
				)
			)
			( gate "@baseboard_fab2_lib.baseboard_fab2(sch_1):page220_i230"
				( attribute "CDS_LIB" "dev_discrete"
					( Origin gPackager )
				)
				( attribute "CDS_LOCATION" "C5L12"
					( Origin gPackager )
				)
				( attribute "CDS_SEC" "1"
					( Origin gPackager )
				)
				( attribute "LOCATION" "C5L12"
					( Origin gFrontEnd )
				)
				( attribute "MATERIAL" "X6S"
					( Origin gFrontEnd )
				)
				( attribute "PACK_TYPE" "0603V"
					( Origin gFrontEnd )
				)
				( attribute "PART_NUMBER" "E15431-004"
					( Origin gFrontEnd )
				)
				( attribute "PHYS_PAGE" "220"
					( Origin gFrontEnd )
				)
				( attribute "ROOM" "PVDDQ_DEF"
					( Origin gFrontEnd )
				)
				( attribute "ROT" "0"
					( Origin gFrontEnd )
				)
				( attribute "SEC" "1"
					( Origin gPackager )
				)
				( attribute "TOLERANCE" "20%"
					( Origin gFrontEnd )
				)
				( attribute "VALUE" "22.0UF"
					( Origin gFrontEnd )
				)
				( attribute "VER" "1"
					( Origin gFrontEnd )
				)
				( attribute "VOLTAGE" "4V"
					( Units "uVoltage" "V" 1.000000)
					( Origin gFrontEnd )
				)
				( attribute "XY" "(-400,-650)"
					( Origin gFrontEnd )
				)
				( attribute "CHIPS_PART_NAME" "CAP_A"
					( Origin gPackager )
				)
				( attribute "CDS_PART_NAME" "CAP_A_0603V-22.0UF,4V,20%,X6S,A"
					( Origin gPackager )
				)
				( objectStatus "C5L12" )
				( pin "a"
					( attribute "PN" "1"
						( Origin gPackager )
					)
					( objectStatus "C5L12.1" )
				)
				( pin "b"
					( attribute "PN" "2"
						( Origin gPackager )
					)
					( objectStatus "C5L12.2" )
				)
			)
			( gate "@baseboard_fab2_lib.baseboard_fab2(sch_1):page220_i231"
				( attribute "CDS_LIB" "dev_discrete"
					( Origin gPackager )
				)
				( attribute "CDS_LOCATION" "C5L11"
					( Origin gPackager )
				)
				( attribute "CDS_SEC" "1"
					( Origin gPackager )
				)
				( attribute "LOCATION" "C5L11"
					( Origin gFrontEnd )
				)
				( attribute "MATERIAL" "X6S"
					( Origin gFrontEnd )
				)
				( attribute "PACK_TYPE" "0603V"
					( Origin gFrontEnd )
				)
				( attribute "PART_NUMBER" "E15431-004"
					( Origin gFrontEnd )
				)
				( attribute "PHYS_PAGE" "220"
					( Origin gFrontEnd )
				)
				( attribute "ROOM" "PVDDQ_DEF"
					( Origin gFrontEnd )
				)
				( attribute "ROT" "0"
					( Origin gFrontEnd )
				)
				( attribute "SEC" "1"
					( Origin gPackager )
				)
				( attribute "TOLERANCE" "20%"
					( Origin gFrontEnd )
				)
				( attribute "VALUE" "22.0UF"
					( Origin gFrontEnd )
				)
				( attribute "VER" "1"
					( Origin gFrontEnd )
				)
				( attribute "VOLTAGE" "4V"
					( Units "uVoltage" "V" 1.000000)
					( Origin gFrontEnd )
				)
				( attribute "XY" "(-700,-650)"
					( Origin gFrontEnd )
				)
				( attribute "CHIPS_PART_NAME" "CAP_A"
					( Origin gPackager )
				)
				( attribute "CDS_PART_NAME" "CAP_A_0603V-22.0UF,4V,20%,X6S,A"
					( Origin gPackager )
				)
				( objectStatus "C5L11" )
				( pin "a"
					( attribute "PN" "1"
						( Origin gPackager )
					)
					( objectStatus "C5L11.1" )
				)
				( pin "b"
					( attribute "PN" "2"
						( Origin gPackager )
					)
					( objectStatus "C5L11.2" )
				)
			)
			( gate "@baseboard_fab2_lib.baseboard_fab2(sch_1):page220_i232"
				( attribute "CDS_LIB" "dev_discrete"
					( Origin gPackager )
				)
				( attribute "CDS_LOCATION" "C5L10"
					( Origin gPackager )
				)
				( attribute "CDS_SEC" "1"
					( Origin gPackager )
				)
				( attribute "LOCATION" "C5L10"
					( Origin gFrontEnd )
				)
				( attribute "MATERIAL" "X6S"
					( Origin gFrontEnd )
				)
				( attribute "PACK_TYPE" "0603V"
					( Origin gFrontEnd )
				)
				( attribute "PART_NUMBER" "E15431-004"
					( Origin gFrontEnd )
				)
				( attribute "PHYS_PAGE" "220"
					( Origin gFrontEnd )
				)
				( attribute "ROOM" "PVDDQ_DEF"
					( Origin gFrontEnd )
				)
				( attribute "ROT" "0"
					( Origin gFrontEnd )
				)
				( attribute "SEC" "1"
					( Origin gPackager )
				)
				( attribute "TOLERANCE" "20%"
					( Origin gFrontEnd )
				)
				( attribute "VALUE" "22.0UF"
					( Origin gFrontEnd )
				)
				( attribute "VER" "1"
					( Origin gFrontEnd )
				)
				( attribute "VOLTAGE" "4V"
					( Units "uVoltage" "V" 1.000000)
					( Origin gFrontEnd )
				)
				( attribute "XY" "(-1000,-650)"
					( Origin gFrontEnd )
				)
				( attribute "CHIPS_PART_NAME" "CAP_A"
					( Origin gPackager )
				)
				( attribute "CDS_PART_NAME" "CAP_A_0603V-22.0UF,4V,20%,X6S,A"
					( Origin gPackager )
				)
				( objectStatus "C5L10" )
				( pin "a"
					( attribute "PN" "1"
						( Origin gPackager )
					)
					( objectStatus "C5L10.1" )
				)
				( pin "b"
					( attribute "PN" "2"
						( Origin gPackager )
					)
					( objectStatus "C5L10.2" )
				)
			)
			( gate "@baseboard_fab2_lib.baseboard_fab2(sch_1):page220_i233"
				( attribute "CDS_LIB" "dev_discrete"
					( Origin gPackager )
				)
				( attribute "CDS_LOCATION" "C5L9"
					( Origin gPackager )
				)
				( attribute "CDS_SEC" "1"
					( Origin gPackager )
				)
				( attribute "LOCATION" "C5L9"
					( Origin gFrontEnd )
				)
				( attribute "MATERIAL" "X6S"
					( Origin gFrontEnd )
				)
				( attribute "PACK_TYPE" "0603V"
					( Origin gFrontEnd )
				)
				( attribute "PART_NUMBER" "E15431-004"
					( Origin gFrontEnd )
				)
				( attribute "PHYS_PAGE" "220"
					( Origin gFrontEnd )
				)
				( attribute "ROOM" "PVDDQ_DEF"
					( Origin gFrontEnd )
				)
				( attribute "ROT" "0"
					( Origin gFrontEnd )
				)
				( attribute "SEC" "1"
					( Origin gPackager )
				)
				( attribute "TOLERANCE" "20%"
					( Origin gFrontEnd )
				)
				( attribute "VALUE" "22.0UF"
					( Origin gFrontEnd )
				)
				( attribute "VER" "1"
					( Origin gFrontEnd )
				)
				( attribute "VOLTAGE" "4V"
					( Units "uVoltage" "V" 1.000000)
					( Origin gFrontEnd )
				)
				( attribute "XY" "(-1275,-650)"
					( Origin gFrontEnd )
				)
				( attribute "CHIPS_PART_NAME" "CAP_A"
					( Origin gPackager )
				)
				( attribute "CDS_PART_NAME" "CAP_A_0603V-22.0UF,4V,20%,X6S,A"
					( Origin gPackager )
				)
				( objectStatus "C5L9" )
				( pin "a"
					( attribute "PN" "1"
						( Origin gPackager )
					)
					( objectStatus "C5L9.1" )
				)
				( pin "b"
					( attribute "PN" "2"
						( Origin gPackager )
					)
					( objectStatus "C5L9.2" )
				)
			)
			( gate "@baseboard_fab2_lib.baseboard_fab2(sch_1):page220_i234"
				( attribute "CDS_LIB" "dev_discrete"
					( Origin gPackager )
				)
				( attribute "CDS_LOCATION" "C5L8"
					( Origin gPackager )
				)
				( attribute "CDS_SEC" "1"
					( Origin gPackager )
				)
				( attribute "LOCATION" "C5L8"
					( Origin gFrontEnd )
				)
				( attribute "MATERIAL" "X6S"
					( Origin gFrontEnd )
				)
				( attribute "PACK_TYPE" "0603V"
					( Origin gFrontEnd )
				)
				( attribute "PART_NUMBER" "E15431-004"
					( Origin gFrontEnd )
				)
				( attribute "PHYS_PAGE" "220"
					( Origin gFrontEnd )
				)
				( attribute "ROOM" "PVDDQ_DEF"
					( Origin gFrontEnd )
				)
				( attribute "ROT" "0"
					( Origin gFrontEnd )
				)
				( attribute "SEC" "1"
					( Origin gPackager )
				)
				( attribute "TOLERANCE" "20%"
					( Origin gFrontEnd )
				)
				( attribute "VALUE" "22.0UF"
					( Origin gFrontEnd )
				)
				( attribute "VER" "1"
					( Origin gFrontEnd )
				)
				( attribute "VOLTAGE" "4V"
					( Units "uVoltage" "V" 1.000000)
					( Origin gFrontEnd )
				)
				( attribute "XY" "(-1550,-650)"
					( Origin gFrontEnd )
				)
				( attribute "CHIPS_PART_NAME" "CAP_A"
					( Origin gPackager )
				)
				( attribute "CDS_PART_NAME" "CAP_A_0603V-22.0UF,4V,20%,X6S,A"
					( Origin gPackager )
				)
				( objectStatus "C5L8" )
				( pin "a"
					( attribute "PN" "1"
						( Origin gPackager )
					)
					( objectStatus "C5L8.1" )
				)
				( pin "b"
					( attribute "PN" "2"
						( Origin gPackager )
					)
					( objectStatus "C5L8.2" )
				)
			)
			( gate "@baseboard_fab2_lib.baseboard_fab2(sch_1):page220_i236"
				( attribute "CDS_LIB" "dev_discrete"
					( Origin gPackager )
				)
				( attribute "CDS_LOCATION" "C5L7"
					( Origin gPackager )
				)
				( attribute "CDS_SEC" "1"
					( Origin gPackager )
				)
				( attribute "LOCATION" "C5L7"
					( Origin gFrontEnd )
				)
				( attribute "MATERIAL" "X6S"
					( Origin gFrontEnd )
				)
				( attribute "PACK_TYPE" "0603V"
					( Origin gFrontEnd )
				)
				( attribute "PART_NUMBER" "E15431-004"
					( Origin gFrontEnd )
				)
				( attribute "PHYS_PAGE" "220"
					( Origin gFrontEnd )
				)
				( attribute "ROOM" "PVDDQ_DEF"
					( Origin gFrontEnd )
				)
				( attribute "ROT" "0"
					( Origin gFrontEnd )
				)
				( attribute "SEC" "1"
					( Origin gPackager )
				)
				( attribute "TOLERANCE" "20%"
					( Origin gFrontEnd )
				)
				( attribute "VALUE" "22.0UF"
					( Origin gFrontEnd )
				)
				( attribute "VER" "1"
					( Origin gFrontEnd )
				)
				( attribute "VOLTAGE" "4V"
					( Units "uVoltage" "V" 1.000000)
					( Origin gFrontEnd )
				)
				( attribute "XY" "(-1850,-650)"
					( Origin gFrontEnd )
				)
				( attribute "CHIPS_PART_NAME" "CAP_A"
					( Origin gPackager )
				)
				( attribute "CDS_PART_NAME" "CAP_A_0603V-22.0UF,4V,20%,X6S,A"
					( Origin gPackager )
				)
				( objectStatus "C5L7" )
				( pin "a"
					( attribute "PN" "1"
						( Origin gPackager )
					)
					( objectStatus "C5L7.1" )
				)
				( pin "b"
					( attribute "PN" "2"
						( Origin gPackager )
					)
					( objectStatus "C5L7.2" )
				)
			)
			( gate "@baseboard_fab2_lib.baseboard_fab2(sch_1):page220_i237"
				( attribute "CDS_LIB" "dev_discrete"
					( Origin gPackager )
				)
				( attribute "CDS_LOCATION" "C5L6"
					( Origin gPackager )
				)
				( attribute "CDS_SEC" "1"
					( Origin gPackager )
				)
				( attribute "LOCATION" "C5L6"
					( Origin gFrontEnd )
				)
				( attribute "MATERIAL" "X6S"
					( Origin gFrontEnd )
				)
				( attribute "PACK_TYPE" "0603V"
					( Origin gFrontEnd )
				)
				( attribute "PART_NUMBER" "E15431-004"
					( Origin gFrontEnd )
				)
				( attribute "PHYS_PAGE" "220"
					( Origin gFrontEnd )
				)
				( attribute "ROOM" "PVDDQ_DEF"
					( Origin gFrontEnd )
				)
				( attribute "ROT" "0"
					( Origin gFrontEnd )
				)
				( attribute "SEC" "1"
					( Origin gPackager )
				)
				( attribute "TOLERANCE" "20%"
					( Origin gFrontEnd )
				)
				( attribute "VALUE" "22.0UF"
					( Origin gFrontEnd )
				)
				( attribute "VER" "1"
					( Origin gFrontEnd )
				)
				( attribute "VOLTAGE" "4V"
					( Units "uVoltage" "V" 1.000000)
					( Origin gFrontEnd )
				)
				( attribute "XY" "(-2150,-650)"
					( Origin gFrontEnd )
				)
				( attribute "CHIPS_PART_NAME" "CAP_A"
					( Origin gPackager )
				)
				( attribute "CDS_PART_NAME" "CAP_A_0603V-22.0UF,4V,20%,X6S,A"
					( Origin gPackager )
				)
				( objectStatus "C5L6" )
				( pin "a"
					( attribute "PN" "1"
						( Origin gPackager )
					)
					( objectStatus "C5L6.1" )
				)
				( pin "b"
					( attribute "PN" "2"
						( Origin gPackager )
					)
					( objectStatus "C5L6.2" )
				)
			)
			( gate "@baseboard_fab2_lib.baseboard_fab2(sch_1):page220_i239"
				( attribute "CDS_LIB" "mstr_misc"
					( Origin gPackager )
				)
				( attribute "CDS_LOCATION" "SH4L2"
					( Origin gPackager )
				)
				( attribute "CDS_SEC" "1"
					( Origin gPackager )
				)
				( attribute "LOCATION" "SH4L2"
					( Origin gFrontEnd )
				)
				( attribute "MATERIAL" "EMPTY"
					( Origin gFrontEnd )
				)
				( attribute "PACK_TYPE" "SH0201"
					( Origin gFrontEnd )
				)
				( attribute "PART_NUMBER" "N_A"
					( Origin gFrontEnd )
				)
				( attribute "PHYS_PAGE" "220"
					( Origin gFrontEnd )
				)
				( attribute "PIN_SHORT" "A:B"
					( Origin gFrontEnd )
				)
				( attribute "ROT" "0"
					( Origin gFrontEnd )
				)
				( attribute "SEC" "1"
					( Origin gFrontEnd )
				)
				( attribute "SEC_TYPE" "SH0201"
					( Origin gFrontEnd )
				)
				( attribute "VER" "1"
					( Origin gFrontEnd )
				)
				( attribute "XY" "(-300,2075)"
					( Origin gFrontEnd )
				)
				( attribute "CHIPS_PART_NAME" "SHUNT"
					( Origin gPackager )
				)
				( attribute "CDS_PART_NAME" "SHUNT_SH0201-EMPTY,N_A"
					( Origin gPackager )
				)
				( objectStatus "SH4L2" )
				( pin "a"
					( attribute "PN" "1"
						( Origin gPackager )
					)
					( objectStatus "SH4L2.1" )
				)
				( pin "b"
					( attribute "PN" "2"
						( Origin gPackager )
					)
					( objectStatus "SH4L2.2" )
				)
			)
			( gate "@baseboard_fab2_lib.baseboard_fab2(sch_1):page220_i240"
				( attribute "CDS_LIB" "mstr_misc"
					( Origin gPackager )
				)
				( attribute "CDS_LOCATION" "SH4L1"
					( Origin gPackager )
				)
				( attribute "CDS_SEC" "1"
					( Origin gPackager )
				)
				( attribute "LOCATION" "SH4L1"
					( Origin gFrontEnd )
				)
				( attribute "MATERIAL" "EMPTY"
					( Origin gFrontEnd )
				)
				( attribute "PACK_TYPE" "SH0201"
					( Origin gFrontEnd )
				)
				( attribute "PART_NUMBER" "N_A"
					( Origin gFrontEnd )
				)
				( attribute "PHYS_PAGE" "220"
					( Origin gFrontEnd )
				)
				( attribute "PIN_SHORT" "A:B"
					( Origin gFrontEnd )
				)
				( attribute "ROT" "0"
					( Origin gFrontEnd )
				)
				( attribute "SEC" "1"
					( Origin gFrontEnd )
				)
				( attribute "SEC_TYPE" "SH0201"
					( Origin gFrontEnd )
				)
				( attribute "VER" "1"
					( Origin gFrontEnd )
				)
				( attribute "XY" "(-325,1625)"
					( Origin gFrontEnd )
				)
				( attribute "CHIPS_PART_NAME" "SHUNT"
					( Origin gPackager )
				)
				( attribute "CDS_PART_NAME" "SHUNT_SH0201-EMPTY,N_A"
					( Origin gPackager )
				)
				( objectStatus "SH4L1" )
				( pin "a"
					( attribute "PN" "1"
						( Origin gPackager )
					)
					( objectStatus "SH4L1.1" )
				)
				( pin "b"
					( attribute "PN" "2"
						( Origin gPackager )
					)
					( objectStatus "SH4L1.2" )
				)
			)
			( gate "@baseboard_fab2_lib.baseboard_fab2(sch_1):page221_i1"
				( attribute "BOM_COST" "MEM_VRD_VTT_ABC"
					( Origin gFrontEnd )
				)
				( attribute "CDS_LIB" "mstr_vreg"
					( Origin gPackager )
				)
				( attribute "CDS_LMAN_SYM_OUTLINE" "-250,350,250,-350"
					( Origin gPackager )
				)
				( attribute "CDS_LOCATION" "EU4G3"
					( Origin gPackager )
				)
				( attribute "CDS_SEC" "1"
					( Origin gPackager )
				)
				( attribute "LOCATION" "EU4G3"
					( Origin gFrontEnd )
				)
				( attribute "MATERIAL" "IC"
					( Origin gFrontEnd )
				)
				( attribute "PACK_TYPE" "DFN"
					( Origin gFrontEnd )
				)
				( attribute "PART_NUMBER" "H55101-001"
					( Origin gFrontEnd )
				)
				( attribute "PHYS_PAGE" "221"
					( Origin gFrontEnd )
				)
				( attribute "ROOM" "VTT_ABC_PWR_VR"
					( Origin gFrontEnd )
				)
				( attribute "ROT" "0"
					( Origin gFrontEnd )
				)
				( attribute "SEC" "1"
					( Origin gFrontEnd )
				)
				( attribute "SEC_TYPE" "DFN"
					( Origin gFrontEnd )
				)
				( attribute "VER" "1"
					( Origin gFrontEnd )
				)
				( attribute "XY" "(1550,1050)"
					( Origin gFrontEnd )
				)
				( attribute "CHIPS_PART_NAME" "MIC5166"
					( Origin gPackager )
				)
				( attribute "CDS_PART_NAME" "MIC5166_DFN-IC,H55101-001"
					( Origin gPackager )
				)
				( objectStatus "EU4G3" )
				( pin "agnd"
					( attribute "PN" "3"
						( Origin gPackager )
					)
					( objectStatus "EU4G3.3" )
				)
				( pin "bias"
					( attribute "PN" "2"
						( Origin gPackager )
					)
					( objectStatus "EU4G3.2" )
				)
				( pin "en"
					( attribute "PN" "7"
						( Origin gPackager )
					)
					( objectStatus "EU4G3.7" )
				)
				( pin "pg"
					( attribute "PN" "5"
						( Origin gPackager )
					)
					( objectStatus "EU4G3.5" )
				)
				( pin "pgnd"
					( attribute "PN" "8"
						( Origin gPackager )
					)
					( objectStatus "EU4G3.8" )
				)
				( pin "sns"
					( attribute "PN" "6"
						( Origin gPackager )
					)
					( objectStatus "EU4G3.6" )
				)
				( pin "thpad"
					( attribute "PN" "11"
						( Origin gPackager )
					)
					( objectStatus "EU4G3.11" )
				)
				( pin "vddq"
					( attribute "PN" "4"
						( Origin gPackager )
					)
					( objectStatus "EU4G3.4" )
				)
				( pin "vin"
					( attribute "PN" "10"
						( Origin gPackager )
					)
					( objectStatus "EU4G3.10" )
				)
				( pin "vref"
					( attribute "PN" "1"
						( Origin gPackager )
					)
					( objectStatus "EU4G3.1" )
				)
				( pin "vtt"
					( attribute "PN" "9"
						( Origin gPackager )
					)
					( objectStatus "EU4G3.9" )
				)
			)
			( gate "@baseboard_fab2_lib.baseboard_fab2(sch_1):page221_i15"
				( attribute "BOM_COST" "MEM_VRD_VTT_ABC"
					( Origin gFrontEnd )
				)
				( attribute "CDS_LIB" "mstr_discrete"
					( Origin gPackager )
				)
				( attribute "CDS_LOCATION" "C4G14"
					( Origin gPackager )
				)
				( attribute "CDS_SEC" "1"
					( Origin gPackager )
				)
				( attribute "LOCATION" "C4G14"
					( Origin gFrontEnd )
				)
				( attribute "MATERIAL" "X7R"
					( Origin gFrontEnd )
				)
				( attribute "PACK_TYPE" "0402LF"
					( Origin gFrontEnd )
				)
				( attribute "PART_NUMBER" "A36096-046"
					( Origin gFrontEnd )
				)
				( attribute "PHYS_PAGE" "221"
					( Origin gFrontEnd )
				)
				( attribute "ROOM" "VTT_ABC_PWR_VR"
					( Origin gFrontEnd )
				)
				( attribute "ROT" "0"
					( Origin gFrontEnd )
				)
				( attribute "SEC" "1"
					( Origin gFrontEnd )
				)
				( attribute "SEC_TYPE" "0402LF"
					( Origin gFrontEnd )
				)
				( attribute "TOLERANCE" "10%"
					( Origin gFrontEnd )
				)
				( attribute "VALUE" "1000PF"
					( Origin gFrontEnd )
				)
				( attribute "VER" "1"
					( Origin gFrontEnd )
				)
				( attribute "VOLTAGE" "50V"
					( Units "uVoltage" "V" 1.000000)
					( Origin gFrontEnd )
				)
				( attribute "XY" "(3875,1600)"
					( Origin gFrontEnd )
				)
				( attribute "CHIPS_PART_NAME" "CAP"
					( Origin gPackager )
				)
				( attribute "CDS_PART_NAME" "CAP_0402LF-1000PF,50V,10%,X7R,A"
					( Origin gPackager )
				)
				( objectStatus "C4G14" )
				( pin "a"
					( attribute "PN" "1"
						( Origin gPackager )
					)
					( objectStatus "C4G14.1" )
				)
				( pin "b"
					( attribute "PN" "2"
						( Origin gPackager )
					)
					( objectStatus "C4G14.2" )
				)
			)
			( gate "@baseboard_fab2_lib.baseboard_fab2(sch_1):page221_i20"
				( attribute "BOM_COST" "MEM_VRD_VTT_ABC"
					( Origin gFrontEnd )
				)
				( attribute "CDS_LIB" "mstr_discrete"
					( Origin gPackager )
				)
				( attribute "CDS_LOCATION" "C4G24"
					( Origin gPackager )
				)
				( attribute "CDS_SEC" "1"
					( Origin gPackager )
				)
				( attribute "LOCATION" "C4G24"
					( Origin gFrontEnd )
				)
				( attribute "MATERIAL" "X6S"
					( Origin gFrontEnd )
				)
				( attribute "PACK_TYPE" "0805LF"
					( Origin gFrontEnd )
				)
				( attribute "PART_NUMBER" "C95333-002"
					( Origin gFrontEnd )
				)
				( attribute "PHYS_PAGE" "221"
					( Origin gFrontEnd )
				)
				( attribute "ROOM" "VTT_ABC_PWR_VR"
					( Origin gFrontEnd )
				)
				( attribute "ROT" "0"
					( Origin gFrontEnd )
				)
				( attribute "SEC" "1"
					( Origin gFrontEnd )
				)
				( attribute "SEC_TYPE" "0805LF"
					( Origin gFrontEnd )
				)
				( attribute "TOLERANCE" "20%"
					( Origin gFrontEnd )
				)
				( attribute "VALUE" "22UF"
					( Origin gFrontEnd )
				)
				( attribute "VER" "1"
					( Origin gFrontEnd )
				)
				( attribute "VOLTAGE" "4V"
					( Units "uVoltage" "V" 1.000000)
					( Origin gFrontEnd )
				)
				( attribute "XY" "(3975,1025)"
					( Origin gFrontEnd )
				)
				( attribute "CHIPS_PART_NAME" "CAP"
					( Origin gPackager )
				)
				( attribute "CDS_PART_NAME" "CAP_0805LF-22UF,4V,20%,X6S,C95A"
					( Origin gPackager )
				)
				( objectStatus "C4G24" )
				( pin "a"
					( attribute "PN" "1"
						( Origin gPackager )
					)
					( objectStatus "C4G24.1" )
				)
				( pin "b"
					( attribute "PN" "2"
						( Origin gPackager )
					)
					( objectStatus "C4G24.2" )
				)
			)
			( gate "@baseboard_fab2_lib.baseboard_fab2(sch_1):page221_i22"
				( attribute "BOM_COST" "MEM_VRD_VTT_ABC"
					( Origin gFrontEnd )
				)
				( attribute "CDS_LIB" "mstr_discrete"
					( Origin gPackager )
				)
				( attribute "CDS_LOCATION" "C6U16"
					( Origin gPackager )
				)
				( attribute "CDS_SEC" "1"
					( Origin gPackager )
				)
				( attribute "LOCATION" "C6U16"
					( Origin gFrontEnd )
				)
				( attribute "MATERIAL" "X6S"
					( Origin gFrontEnd )
				)
				( attribute "PACK_TYPE" "0603LF"
					( Origin gFrontEnd )
				)
				( attribute "PART_NUMBER" "E15431-001"
					( Origin gFrontEnd )
				)
				( attribute "PHYS_PAGE" "221"
					( Origin gFrontEnd )
				)
				( attribute "ROOM" "VTT_ABC_PWR_VR"
					( Origin gFrontEnd )
				)
				( attribute "ROT" "0"
					( Origin gFrontEnd )
				)
				( attribute "SEC" "1"
					( Origin gFrontEnd )
				)
				( attribute "SEC_TYPE" "0603LF"
					( Origin gFrontEnd )
				)
				( attribute "TOLERANCE" "20%"
					( Origin gFrontEnd )
				)
				( attribute "VALUE" "10UF"
					( Origin gFrontEnd )
				)
				( attribute "VER" "1"
					( Origin gFrontEnd )
				)
				( attribute "VOLTAGE" "4V"
					( Units "uVoltage" "V" 1.000000)
					( Origin gFrontEnd )
				)
				( attribute "XY" "(475,2350)"
					( Origin gFrontEnd )
				)
				( attribute "CHIPS_PART_NAME" "CAP"
					( Origin gPackager )
				)
				( attribute "CDS_PART_NAME" "CAP_0603LF-10UF,4V,20%,X6S,E15A"
					( Origin gPackager )
				)
				( objectStatus "C6U16" )
				( pin "a"
					( attribute "PN" "1"
						( Origin gPackager )
					)
					( objectStatus "C6U16.1" )
				)
				( pin "b"
					( attribute "PN" "2"
						( Origin gPackager )
					)
					( objectStatus "C6U16.2" )
				)
			)
			( gate "@baseboard_fab2_lib.baseboard_fab2(sch_1):page221_i24"
				( attribute "BOM_COST" "MEM_VRD_VTT_ABC"
					( Origin gFrontEnd )
				)
				( attribute "CDS_LIB" "mstr_discrete"
					( Origin gPackager )
				)
				( attribute "CDS_LOCATION" "C4G15"
					( Origin gPackager )
				)
				( attribute "CDS_SEC" "1"
					( Origin gPackager )
				)
				( attribute "LOCATION" "C4G15"
					( Origin gFrontEnd )
				)
				( attribute "MATERIAL" "X6S"
					( Origin gFrontEnd )
				)
				( attribute "PACK_TYPE" "0402"
					( Origin gFrontEnd )
				)
				( attribute "PART_NUMBER" "D97712-011"
					( Origin gFrontEnd )
				)
				( attribute "PHYS_PAGE" "221"
					( Origin gFrontEnd )
				)
				( attribute "ROOM" "VTT_ABC_PWR_VR"
					( Origin gFrontEnd )
				)
				( attribute "ROT" "0"
					( Origin gFrontEnd )
				)
				( attribute "SEC" "1"
					( Origin gPackager )
				)
				( attribute "TOLERANCE" "10%"
					( Origin gFrontEnd )
				)
				( attribute "VALUE" "1.0UF"
					( Origin gFrontEnd )
				)
				( attribute "VER" "1"
					( Origin gFrontEnd )
				)
				( attribute "VOLTAGE" "16V"
					( Units "uVoltage" "V" 1.000000)
					( Origin gFrontEnd )
				)
				( attribute "XY" "(475,1475)"
					( Origin gFrontEnd )
				)
				( attribute "CHIPS_PART_NAME" "CAP"
					( Origin gPackager )
				)
				( attribute "CDS_PART_NAME" "CAP_0402-1.0UF,16V,10%,X6S,D97A"
					( Origin gPackager )
				)
				( objectStatus "C4G15" )
				( pin "a"
					( attribute "PN" "1"
						( Origin gPackager )
					)
					( objectStatus "C4G15.1" )
				)
				( pin "b"
					( attribute "PN" "2"
						( Origin gPackager )
					)
					( objectStatus "C4G15.2" )
				)
			)
			( gate "@baseboard_fab2_lib.baseboard_fab2(sch_1):page221_i26"
				( attribute "BOM_COST" "MEM_VRD_VTT_ABC"
					( Origin gFrontEnd )
				)
				( attribute "CDS_LIB" "mstr_discrete"
					( Origin gPackager )
				)
				( attribute "CDS_LOCATION" "C6U15"
					( Origin gPackager )
				)
				( attribute "CDS_SEC" "1"
					( Origin gPackager )
				)
				( attribute "LOCATION" "C6U15"
					( Origin gFrontEnd )
				)
				( attribute "MATERIAL" "X6S"
					( Origin gFrontEnd )
				)
				( attribute "PACK_TYPE" "0603LF"
					( Origin gFrontEnd )
				)
				( attribute "PART_NUMBER" "E15431-001"
					( Origin gFrontEnd )
				)
				( attribute "PHYS_PAGE" "221"
					( Origin gFrontEnd )
				)
				( attribute "ROOM" "VTT_ABC_PWR_VR"
					( Origin gFrontEnd )
				)
				( attribute "ROT" "0"
					( Origin gFrontEnd )
				)
				( attribute "SEC" "1"
					( Origin gFrontEnd )
				)
				( attribute "SEC_TYPE" "0603LF"
					( Origin gFrontEnd )
				)
				( attribute "TOLERANCE" "20%"
					( Origin gFrontEnd )
				)
				( attribute "VALUE" "10UF"
					( Origin gFrontEnd )
				)
				( attribute "VER" "1"
					( Origin gFrontEnd )
				)
				( attribute "VOLTAGE" "4V"
					( Units "uVoltage" "V" 1.000000)
					( Origin gFrontEnd )
				)
				( attribute "XY" "(50,2325)"
					( Origin gFrontEnd )
				)
				( attribute "CHIPS_PART_NAME" "CAP"
					( Origin gPackager )
				)
				( attribute "CDS_PART_NAME" "CAP_0603LF-10UF,4V,20%,X6S,E15A"
					( Origin gPackager )
				)
				( objectStatus "C6U15" )
				( pin "a"
					( attribute "PN" "1"
						( Origin gPackager )
					)
					( objectStatus "C6U15.1" )
				)
				( pin "b"
					( attribute "PN" "2"
						( Origin gPackager )
					)
					( objectStatus "C6U15.2" )
				)
			)
			( gate "@baseboard_fab2_lib.baseboard_fab2(sch_1):page221_i28"
				( attribute "BOM_COST" "MEM_VRD_VTT_ABC"
					( Origin gFrontEnd )
				)
				( attribute "CDS_LIB" "mstr_discrete"
					( Origin gPackager )
				)
				( attribute "CDS_LOCATION" "R6U4"
					( Origin gPackager )
				)
				( attribute "CDS_SEC" "1"
					( Origin gPackager )
				)
				( attribute "LOCATION" "R6U4"
					( Origin gFrontEnd )
				)
				( attribute "MATERIAL" "CHIP"
					( Origin gFrontEnd )
				)
				( attribute "PACK_TYPE" "0402"
					( Origin gFrontEnd )
				)
				( attribute "PART_NUMBER" "G21497-005"
					( Origin gFrontEnd )
				)
				( attribute "PHYS_PAGE" "221"
					( Origin gFrontEnd )
				)
				( attribute "ROOM" "VTT_ABC_PWR_VR"
					( Origin gFrontEnd )
				)
				( attribute "ROT" "0"
					( Origin gFrontEnd )
				)
				( attribute "SEC" "1"
					( Origin gFrontEnd )
				)
				( attribute "SEC_TYPE" "0402"
					( Origin gFrontEnd )
				)
				( attribute "TOLERANCE" "5%"
					( Origin gFrontEnd )
				)
				( attribute "VALUE" "0.0"
					( Origin gFrontEnd )
				)
				( attribute "VER" "1"
					( Origin gFrontEnd )
				)
				( attribute "WATTAGE" "1/16W"
					( Origin gFrontEnd )
				)
				( attribute "XY" "(125,1750)"
					( Origin gFrontEnd )
				)
				( attribute "CHIPS_PART_NAME" "RES"
					( Origin gPackager )
				)
				( attribute "CDS_PART_NAME" "RES_0402-0.0,5%,1/16W,CHIP,G21A"
					( Origin gPackager )
				)
				( objectStatus "R6U4" )
				( pin "a"
					( attribute "PN" "1"
						( Origin gPackager )
					)
					( objectStatus "R6U4.1" )
				)
				( pin "b"
					( attribute "PN" "2"
						( Origin gPackager )
					)
					( objectStatus "R6U4.2" )
				)
			)
			( gate "@baseboard_fab2_lib.baseboard_fab2(sch_1):page221_i32"
				( attribute "BOM_COST" "MEM_VRD_VTT_ABC"
					( Origin gFrontEnd )
				)
				( attribute "CDS_LIB" "mstr_discrete"
					( Origin gPackager )
				)
				( attribute "CDS_LOCATION" "R6U5"
					( Origin gPackager )
				)
				( attribute "CDS_SEC" "1"
					( Origin gPackager )
				)
				( attribute "LOCATION" "R6U5"
					( Origin gFrontEnd )
				)
				( attribute "MATERIAL" "CHIP"
					( Origin gFrontEnd )
				)
				( attribute "NO_XNET_CONNECTION" "1"
					( Origin gFrontEnd )
				)
				( attribute "PACK_TYPE" "0402"
					( Origin gFrontEnd )
				)
				( attribute "PART_NUMBER" "G21497-005"
					( Origin gFrontEnd )
				)
				( attribute "PHYS_PAGE" "221"
					( Origin gFrontEnd )
				)
				( attribute "ROOM" "VTT_ABC_PWR_VR"
					( Origin gFrontEnd )
				)
				( attribute "ROT" "1"
					( Origin gFrontEnd )
				)
				( attribute "SEC" "1"
					( Origin gFrontEnd )
				)
				( attribute "SEC_TYPE" "0402"
					( Origin gFrontEnd )
				)
				( attribute "TOLERANCE" "5%"
					( Origin gFrontEnd )
				)
				( attribute "VALUE" "0.0"
					( Origin gFrontEnd )
				)
				( attribute "VER" "2"
					( Origin gFrontEnd )
				)
				( attribute "WATTAGE" "1/16W"
					( Origin gFrontEnd )
				)
				( attribute "XY" "(-775,1525)"
					( Origin gFrontEnd )
				)
				( attribute "CHIPS_PART_NAME" "RES"
					( Origin gPackager )
				)
				( attribute "CDS_PART_NAME" "RES_0402-0.0,5%,1/16W,CHIP,G21A"
					( Origin gPackager )
				)
				( objectStatus "R6U5" )
				( pin "a"
					( attribute "PN" "1"
						( Origin gPackager )
					)
					( objectStatus "R6U5.1" )
				)
				( pin "b"
					( attribute "PN" "2"
						( Origin gPackager )
					)
					( objectStatus "R6U5.2" )
				)
			)
			( gate "@baseboard_fab2_lib.baseboard_fab2(sch_1):page221_i34"
				( attribute "BOM_COST" "MEM_VRD_VTT_ABC"
					( Origin gFrontEnd )
				)
				( attribute "CDS_LIB" "mstr_discrete"
					( Origin gPackager )
				)
				( attribute "CDS_LOCATION" "C4G16"
					( Origin gPackager )
				)
				( attribute "CDS_SEC" "1"
					( Origin gPackager )
				)
				( attribute "LOCATION" "C4G16"
					( Origin gFrontEnd )
				)
				( attribute "MATERIAL" "X6S"
					( Origin gFrontEnd )
				)
				( attribute "PACK_TYPE" "0402"
					( Origin gFrontEnd )
				)
				( attribute "PART_NUMBER" "D97712-011"
					( Origin gFrontEnd )
				)
				( attribute "PHYS_PAGE" "221"
					( Origin gFrontEnd )
				)
				( attribute "ROOM" "VTT_ABC_PWR_VR"
					( Origin gFrontEnd )
				)
				( attribute "ROT" "0"
					( Origin gFrontEnd )
				)
				( attribute "SEC" "1"
					( Origin gFrontEnd )
				)
				( attribute "SEC_TYPE" "0402"
					( Origin gFrontEnd )
				)
				( attribute "TOLERANCE" "10%"
					( Origin gFrontEnd )
				)
				( attribute "VALUE" "1.0UF"
					( Origin gFrontEnd )
				)
				( attribute "VER" "1"
					( Origin gFrontEnd )
				)
				( attribute "VOLTAGE" "16V"
					( Units "uVoltage" "V" 1.000000)
					( Origin gFrontEnd )
				)
				( attribute "XY" "(2375,825)"
					( Origin gFrontEnd )
				)
				( attribute "CHIPS_PART_NAME" "CAP"
					( Origin gPackager )
				)
				( attribute "CDS_PART_NAME" "CAP_0402-1.0UF,16V,10%,X6S,D97A"
					( Origin gPackager )
				)
				( objectStatus "C4G16" )
				( pin "a"
					( attribute "PN" "1"
						( Origin gPackager )
					)
					( objectStatus "C4G16.1" )
				)
				( pin "b"
					( attribute "PN" "2"
						( Origin gPackager )
					)
					( objectStatus "C4G16.2" )
				)
			)
			( gate "@baseboard_fab2_lib.baseboard_fab2(sch_1):page221_i37"
				( attribute "BOM_COST" "MEM_VRD_VTT_ABC"
					( Origin gFrontEnd )
				)
				( attribute "CDS_LIB" "mstr_discrete"
					( Origin gPackager )
				)
				( attribute "CDS_LOCATION" "R6U15"
					( Origin gPackager )
				)
				( attribute "CDS_SEC" "1"
					( Origin gPackager )
				)
				( attribute "LOCATION" "R6U15"
					( Origin gFrontEnd )
				)
				( attribute "MATERIAL" "EMPTY"
					( Origin gFrontEnd )
				)
				( attribute "PACK_TYPE" "0402"
					( Origin gFrontEnd )
				)
				( attribute "PART_NUMBER" "G21796-021"
					( Origin gFrontEnd )
				)
				( attribute "PHYS_PAGE" "221"
					( Origin gFrontEnd )
				)
				( attribute "ROOM" "VTT_ABC_PWR_VR"
					( Origin gFrontEnd )
				)
				( attribute "ROT" "2"
					( Origin gFrontEnd )
				)
				( attribute "SEC" "1"
					( Origin gFrontEnd )
				)
				( attribute "SEC_TYPE" "0402"
					( Origin gFrontEnd )
				)
				( attribute "TOLERANCE" "1%"
					( Origin gFrontEnd )
				)
				( attribute "VALUE" "1.0M"
					( Origin gFrontEnd )
				)
				( attribute "VER" "2"
					( Origin gFrontEnd )
				)
				( attribute "WATTAGE" "1/16W"
					( Origin gFrontEnd )
				)
				( attribute "XY" "(-325,650)"
					( Origin gFrontEnd )
				)
				( attribute "CHIPS_PART_NAME" "RES"
					( Origin gPackager )
				)
				( attribute "CDS_PART_NAME" "RES_0402-1.0M,1%,1/16W,EMPTY,GA"
					( Origin gPackager )
				)
				( objectStatus "R6U15" )
				( pin "a"
					( attribute "PN" "1"
						( Origin gPackager )
					)
					( objectStatus "R6U15.1" )
				)
				( pin "b"
					( attribute "PN" "2"
						( Origin gPackager )
					)
					( objectStatus "R6U15.2" )
				)
			)
			( gate "@baseboard_fab2_lib.baseboard_fab2(sch_1):page221_i38"
				( attribute "BOM_COST" "MEM_VRD_VTT_ABC"
					( Origin gFrontEnd )
				)
				( attribute "CDS_LIB" "mstr_discrete"
					( Origin gPackager )
				)
				( attribute "CDS_LOCATION" "R4G23"
					( Origin gPackager )
				)
				( attribute "CDS_SEC" "1"
					( Origin gPackager )
				)
				( attribute "LOCATION" "R4G23"
					( Origin gFrontEnd )
				)
				( attribute "MATERIAL" "CHIP"
					( Origin gFrontEnd )
				)
				( attribute "PACK_TYPE" "0402"
					( Origin gFrontEnd )
				)
				( attribute "PART_NUMBER" "G21497-005"
					( Origin gFrontEnd )
				)
				( attribute "PHYS_PAGE" "221"
					( Origin gFrontEnd )
				)
				( attribute "ROOM" "VTT_ABC_PWR_VR"
					( Origin gFrontEnd )
				)
				( attribute "ROT" "0"
					( Origin gFrontEnd )
				)
				( attribute "SEC" "1"
					( Origin gFrontEnd )
				)
				( attribute "SEC_TYPE" "0402"
					( Origin gFrontEnd )
				)
				( attribute "TOLERANCE" "5%"
					( Origin gFrontEnd )
				)
				( attribute "VALUE" "0.0"
					( Origin gFrontEnd )
				)
				( attribute "VER" "1"
					( Origin gFrontEnd )
				)
				( attribute "WATTAGE" "1/16W"
					( Origin gFrontEnd )
				)
				( attribute "XY" "(-525,125)"
					( Origin gFrontEnd )
				)
				( attribute "CHIPS_PART_NAME" "RES"
					( Origin gPackager )
				)
				( attribute "CDS_PART_NAME" "RES_0402-0.0,5%,1/16W,CHIP,G21A"
					( Origin gPackager )
				)
				( objectStatus "R4G23" )
				( pin "a"
					( attribute "PN" "1"
						( Origin gPackager )
					)
					( objectStatus "R4G23.1" )
				)
				( pin "b"
					( attribute "PN" "2"
						( Origin gPackager )
					)
					( objectStatus "R4G23.2" )
				)
			)
			( gate "@baseboard_fab2_lib.baseboard_fab2(sch_1):page221_i39"
				( attribute "BOM_COST" "MEM_VRD_VTT_ABC"
					( Origin gFrontEnd )
				)
				( attribute "CDS_LIB" "mstr_discrete"
					( Origin gPackager )
				)
				( attribute "CDS_LOCATION" "C4G23"
					( Origin gPackager )
				)
				( attribute "CDS_SEC" "1"
					( Origin gPackager )
				)
				( attribute "LOCATION" "C4G23"
					( Origin gFrontEnd )
				)
				( attribute "MATERIAL" "EMPTY"
					( Origin gFrontEnd )
				)
				( attribute "PACK_TYPE" "0402LF"
					( Origin gFrontEnd )
				)
				( attribute "PART_NUMBER" "A36096-046"
					( Origin gFrontEnd )
				)
				( attribute "PHYS_PAGE" "221"
					( Origin gFrontEnd )
				)
				( attribute "ROOM" "VTT_ABC_PWR_VR"
					( Origin gFrontEnd )
				)
				( attribute "ROT" "2"
					( Origin gFrontEnd )
				)
				( attribute "SEC" "1"
					( Origin gFrontEnd )
				)
				( attribute "SEC_TYPE" "0402LF"
					( Origin gFrontEnd )
				)
				( attribute "TOLERANCE" "10%"
					( Origin gFrontEnd )
				)
				( attribute "VALUE" "1000PF"
					( Origin gFrontEnd )
				)
				( attribute "VER" "1"
					( Origin gFrontEnd )
				)
				( attribute "VOLTAGE" "50V"
					( Units "uVoltage" "V" 1.000000)
					( Origin gFrontEnd )
				)
				( attribute "XY" "(-375,-400)"
					( Origin gFrontEnd )
				)
				( attribute "CHIPS_PART_NAME" "CAP"
					( Origin gPackager )
				)
				( attribute "CDS_PART_NAME" "CAP_0402LF-1000PF,50V,10%,EMPTA"
					( Origin gPackager )
				)
				( objectStatus "C4G23" )
				( pin "a"
					( attribute "PN" "1"
						( Origin gPackager )
					)
					( objectStatus "C4G23.1" )
				)
				( pin "b"
					( attribute "PN" "2"
						( Origin gPackager )
					)
					( objectStatus "C4G23.2" )
				)
			)
			( gate "@baseboard_fab2_lib.baseboard_fab2(sch_1):page221_i45"
				( attribute "BOM_COST" "MEM_VRD_VTT_ABC"
					( Origin gFrontEnd )
				)
				( attribute "CDS_LIB" "mstr_discrete"
					( Origin gPackager )
				)
				( attribute "CDS_LOCATION" "R4G18"
					( Origin gPackager )
				)
				( attribute "CDS_SEC" "1"
					( Origin gPackager )
				)
				( attribute "LOCATION" "R4G18"
					( Origin gFrontEnd )
				)
				( attribute "MATERIAL" "CHIP"
					( Origin gFrontEnd )
				)
				( attribute "PACK_TYPE" "0402"
					( Origin gFrontEnd )
				)
				( attribute "PART_NUMBER" "G21796-016"
					( Origin gFrontEnd )
				)
				( attribute "PHYS_PAGE" "221"
					( Origin gFrontEnd )
				)
				( attribute "ROOM" "VTT_ABC_PWR_VR"
					( Origin gFrontEnd )
				)
				( attribute "ROT" "0"
					( Origin gFrontEnd )
				)
				( attribute "SEC" "1"
					( Origin gFrontEnd )
				)
				( attribute "SEC_TYPE" "0402"
					( Origin gFrontEnd )
				)
				( attribute "TOLERANCE" "1%"
					( Origin gFrontEnd )
				)
				( attribute "VALUE" "10.0K"
					( Origin gFrontEnd )
				)
				( attribute "VER" "2"
					( Origin gFrontEnd )
				)
				( attribute "WATTAGE" "1/16W"
					( Origin gFrontEnd )
				)
				( attribute "XY" "(3500,2025)"
					( Origin gFrontEnd )
				)
				( attribute "CHIPS_PART_NAME" "RES"
					( Origin gPackager )
				)
				( attribute "CDS_PART_NAME" "RES_0402-10.0K,1%,1/16W,CHIP,GA"
					( Origin gPackager )
				)
				( objectStatus "R4G18" )
				( pin "a"
					( attribute "PN" "1"
						( Origin gPackager )
					)
					( objectStatus "R4G18.1" )
				)
				( pin "b"
					( attribute "PN" "2"
						( Origin gPackager )
					)
					( objectStatus "R4G18.2" )
				)
			)
			( gate "@baseboard_fab2_lib.baseboard_fab2(sch_1):page221_i49"
				( attribute "CDS_LIB" "mstr_discrete"
					( Origin gPackager )
				)
				( attribute "CDS_LOCATION" "C6U12"
					( Origin gPackager )
				)
				( attribute "CDS_SEC" "1"
					( Origin gPackager )
				)
				( attribute "LOCATION" "C6U12"
					( Origin gFrontEnd )
				)
				( attribute "MATERIAL" "X6S"
					( Origin gFrontEnd )
				)
				( attribute "PACK_TYPE" "0603"
					( Origin gFrontEnd )
				)
				( attribute "PART_NUMBER" "E15431-003"
					( Origin gFrontEnd )
				)
				( attribute "PHYS_PAGE" "221"
					( Origin gFrontEnd )
				)
				( attribute "ROOM" "VTT_ABC_PWR_VR"
					( Origin gFrontEnd )
				)
				( attribute "ROT" "0"
					( Origin gFrontEnd )
				)
				( attribute "SEC" "1"
					( Origin gFrontEnd )
				)
				( attribute "SEC_TYPE" "0603"
					( Origin gFrontEnd )
				)
				( attribute "TOLERANCE" "10%"
					( Origin gFrontEnd )
				)
				( attribute "VALUE" "4.7UF"
					( Origin gFrontEnd )
				)
				( attribute "VER" "1"
					( Origin gFrontEnd )
				)
				( attribute "VOLTAGE" "6.3V"
					( Units "uVoltage" "V" 1.000000)
					( Origin gFrontEnd )
				)
				( attribute "XY" "(325,1000)"
					( Origin gFrontEnd )
				)
				( attribute "CHIPS_PART_NAME" "CAP"
					( Origin gPackager )
				)
				( attribute "CDS_PART_NAME" "CAP_0603-4.7UF,6.3V,10%,X6S,E1A"
					( Origin gPackager )
				)
				( objectStatus "C6U12" )
				( pin "a"
					( attribute "PN" "1"
						( Origin gPackager )
					)
					( objectStatus "C6U12.1" )
				)
				( pin "b"
					( attribute "PN" "2"
						( Origin gPackager )
					)
					( objectStatus "C6U12.2" )
				)
			)
			( gate "@baseboard_fab2_lib.baseboard_fab2(sch_1):page221_i50"
				( attribute "CDS_LIB" "dev_discrete"
					( Origin gPackager )
				)
				( attribute "CDS_LOCATION" "C5U12"
					( Origin gPackager )
				)
				( attribute "CDS_SEC" "1"
					( Origin gPackager )
				)
				( attribute "LOCATION" "C5U12"
					( Origin gFrontEnd )
				)
				( attribute "MATERIAL" "X5R"
					( Origin gFrontEnd )
				)
				( attribute "PACK_TYPE" "0603V"
					( Origin gFrontEnd )
				)
				( attribute "PART_NUMBER" "602433-106"
					( Origin gFrontEnd )
				)
				( attribute "PHYS_PAGE" "221"
					( Origin gFrontEnd )
				)
				( attribute "ROT" "0"
					( Origin gFrontEnd )
				)
				( attribute "SEC" "1"
					( Origin gFrontEnd )
				)
				( attribute "SEC_TYPE" "0603V"
					( Origin gFrontEnd )
				)
				( attribute "TOLERANCE" "20%"
					( Origin gFrontEnd )
				)
				( attribute "VALUE" "47UF"
					( Origin gFrontEnd )
				)
				( attribute "VER" "1"
					( Origin gFrontEnd )
				)
				( attribute "VOLTAGE" "4V"
					( Units "uVoltage" "V" 1.000000)
					( Origin gFrontEnd )
				)
				( attribute "XY" "(3600,3450)"
					( Origin gFrontEnd )
				)
				( attribute "CHIPS_PART_NAME" "CAP_A"
					( Origin gPackager )
				)
				( attribute "CDS_PART_NAME" "CAP_A_0603V-47UF,4V,20%,X5R,60A"
					( Origin gPackager )
				)
				( objectStatus "C5U12" )
				( pin "a"
					( attribute "PN" "1"
						( Origin gPackager )
					)
					( objectStatus "C5U12.1" )
				)
				( pin "b"
					( attribute "PN" "2"
						( Origin gPackager )
					)
					( objectStatus "C5U12.2" )
				)
			)
			( gate "@baseboard_fab2_lib.baseboard_fab2(sch_1):page221_i51"
				( attribute "CDS_LIB" "dev_discrete"
					( Origin gPackager )
				)
				( attribute "CDS_LOCATION" "C5T3"
					( Origin gPackager )
				)
				( attribute "CDS_SEC" "1"
					( Origin gPackager )
				)
				( attribute "LOCATION" "C5T3"
					( Origin gFrontEnd )
				)
				( attribute "MATERIAL" "X5R"
					( Origin gFrontEnd )
				)
				( attribute "PACK_TYPE" "0603V"
					( Origin gFrontEnd )
				)
				( attribute "PART_NUMBER" "602433-106"
					( Origin gFrontEnd )
				)
				( attribute "PHYS_PAGE" "221"
					( Origin gFrontEnd )
				)
				( attribute "ROT" "0"
					( Origin gFrontEnd )
				)
				( attribute "SEC" "1"
					( Origin gFrontEnd )
				)
				( attribute "SEC_TYPE" "0603V"
					( Origin gFrontEnd )
				)
				( attribute "TOLERANCE" "20%"
					( Origin gFrontEnd )
				)
				( attribute "VALUE" "47UF"
					( Origin gFrontEnd )
				)
				( attribute "VER" "1"
					( Origin gFrontEnd )
				)
				( attribute "VOLTAGE" "4V"
					( Units "uVoltage" "V" 1.000000)
					( Origin gFrontEnd )
				)
				( attribute "XY" "(3950,3450)"
					( Origin gFrontEnd )
				)
				( attribute "CHIPS_PART_NAME" "CAP_A"
					( Origin gPackager )
				)
				( attribute "CDS_PART_NAME" "CAP_A_0603V-47UF,4V,20%,X5R,60A"
					( Origin gPackager )
				)
				( objectStatus "C5T3" )
				( pin "a"
					( attribute "PN" "1"
						( Origin gPackager )
					)
					( objectStatus "C5T3.1" )
				)
				( pin "b"
					( attribute "PN" "2"
						( Origin gPackager )
					)
					( objectStatus "C5T3.2" )
				)
			)
			( gate "@baseboard_fab2_lib.baseboard_fab2(sch_1):page221_i52"
				( attribute "CDS_LIB" "dev_discrete"
					( Origin gPackager )
				)
				( attribute "CDS_LOCATION" "C5U16"
					( Origin gPackager )
				)
				( attribute "CDS_SEC" "1"
					( Origin gPackager )
				)
				( attribute "LOCATION" "C5U16"
					( Origin gFrontEnd )
				)
				( attribute "MATERIAL" "X5R"
					( Origin gFrontEnd )
				)
				( attribute "PACK_TYPE" "0603V"
					( Origin gFrontEnd )
				)
				( attribute "PART_NUMBER" "602433-106"
					( Origin gFrontEnd )
				)
				( attribute "PHYS_PAGE" "221"
					( Origin gFrontEnd )
				)
				( attribute "ROT" "0"
					( Origin gFrontEnd )
				)
				( attribute "SEC" "1"
					( Origin gFrontEnd )
				)
				( attribute "SEC_TYPE" "0603V"
					( Origin gFrontEnd )
				)
				( attribute "TOLERANCE" "20%"
					( Origin gFrontEnd )
				)
				( attribute "VALUE" "47UF"
					( Origin gFrontEnd )
				)
				( attribute "VER" "1"
					( Origin gFrontEnd )
				)
				( attribute "VOLTAGE" "4V"
					( Units "uVoltage" "V" 1.000000)
					( Origin gFrontEnd )
				)
				( attribute "XY" "(4350,3450)"
					( Origin gFrontEnd )
				)
				( attribute "CHIPS_PART_NAME" "CAP_A"
					( Origin gPackager )
				)
				( attribute "CDS_PART_NAME" "CAP_A_0603V-47UF,4V,20%,X5R,60A"
					( Origin gPackager )
				)
				( objectStatus "C5U16" )
				( pin "a"
					( attribute "PN" "1"
						( Origin gPackager )
					)
					( objectStatus "C5U16.1" )
				)
				( pin "b"
					( attribute "PN" "2"
						( Origin gPackager )
					)
					( objectStatus "C5U16.2" )
				)
			)
			( gate "@baseboard_fab2_lib.baseboard_fab2(sch_1):page221_i54"
				( attribute "CDS_LIB" "mstr_discrete"
					( Origin gPackager )
				)
				( attribute "CDS_LOCATION" "R4G19"
					( Origin gPackager )
				)
				( attribute "CDS_SEC" "1"
					( Origin gPackager )
				)
				( attribute "LOCATION" "R4G19"
					( Origin gFrontEnd )
				)
				( attribute "MATERIAL" "CHIP"
					( Origin gFrontEnd )
				)
				( attribute "PACK_TYPE" "0402"
					( Origin gFrontEnd )
				)
				( attribute "PART_NUMBER" "G21796-074"
					( Origin gFrontEnd )
				)
				( attribute "PHYS_PAGE" "221"
					( Origin gFrontEnd )
				)
				( attribute "ROT" "0"
					( Origin gFrontEnd )
				)
				( attribute "SEC" "1"
					( Origin gFrontEnd )
				)
				( attribute "SEC_TYPE" "0402"
					( Origin gFrontEnd )
				)
				( attribute "TOLERANCE" "1%"
					( Origin gFrontEnd )
				)
				( attribute "VALUE" "33.2"
					( Origin gFrontEnd )
				)
				( attribute "VER" "1"
					( Origin gFrontEnd )
				)
				( attribute "WATTAGE" "1/16W"
					( Origin gFrontEnd )
				)
				( attribute "XY" "(4175,1800)"
					( Origin gFrontEnd )
				)
				( attribute "CHIPS_PART_NAME" "RES"
					( Origin gPackager )
				)
				( attribute "CDS_PART_NAME" "RES_0402-33.2,1%,1/16W,CHIP,G2A"
					( Origin gPackager )
				)
				( objectStatus "R4G19" )
				( pin "a"
					( attribute "PN" "1"
						( Origin gPackager )
					)
					( objectStatus "R4G19.1" )
				)
				( pin "b"
					( attribute "PN" "2"
						( Origin gPackager )
					)
					( objectStatus "R4G19.2" )
				)
			)
			( gate "@baseboard_fab2_lib.baseboard_fab2(sch_1):page221_i55"
				( attribute "CDS_LIB" "mstr_discrete"
					( Origin gPackager )
				)
				( attribute "CDS_LOCATION" "R6U16"
					( Origin gPackager )
				)
				( attribute "CDS_SEC" "1"
					( Origin gPackager )
				)
				( attribute "LOCATION" "R6U16"
					( Origin gFrontEnd )
				)
				( attribute "MATERIAL" "CHIP"
					( Origin gFrontEnd )
				)
				( attribute "PACK_TYPE" "0402"
					( Origin gFrontEnd )
				)
				( attribute "PART_NUMBER" "G21796-208"
					( Origin gFrontEnd )
				)
				( attribute "PHYS_PAGE" "221"
					( Origin gFrontEnd )
				)
				( attribute "ROT" "1"
					( Origin gFrontEnd )
				)
				( attribute "SEC" "1"
					( Origin gPackager )
				)
				( attribute "TOLERANCE" "1.0%"
					( Origin gFrontEnd )
				)
				( attribute "VALUE" "51.1"
					( Origin gFrontEnd )
				)
				( attribute "VER" "1"
					( Origin gFrontEnd )
				)
				( attribute "WATTAGE" "1/16W"
					( Origin gFrontEnd )
				)
				( attribute "XY" "(4700,1000)"
					( Origin gFrontEnd )
				)
				( attribute "CHIPS_PART_NAME" "RES"
					( Origin gPackager )
				)
				( attribute "CDS_PART_NAME" "RES_0402-51.1,1.0%,1/16W,CHIP,A"
					( Origin gPackager )
				)
				( objectStatus "R6U16" )
				( pin "a"
					( attribute "PN" "1"
						( Origin gPackager )
					)
					( objectStatus "R6U16.1" )
				)
				( pin "b"
					( attribute "PN" "2"
						( Origin gPackager )
					)
					( objectStatus "R6U16.2" )
				)
			)
			( gate "@baseboard_fab2_lib.baseboard_fab2(sch_1):page221_i56"
				( attribute "CDS_LIB" "mstr_misc"
					( Origin gPackager )
				)
				( attribute "CDS_LOCATION" "SH5U1"
					( Origin gPackager )
				)
				( attribute "CDS_SEC" "1"
					( Origin gPackager )
				)
				( attribute "LOCATION" "SH5U1"
					( Origin gFrontEnd )
				)
				( attribute "MATERIAL" "EMPTY"
					( Origin gFrontEnd )
				)
				( attribute "PACK_TYPE" "SH0201"
					( Origin gFrontEnd )
				)
				( attribute "PART_NUMBER" "N_A"
					( Origin gFrontEnd )
				)
				( attribute "PHYS_PAGE" "221"
					( Origin gFrontEnd )
				)
				( attribute "PIN_SHORT" "A:B"
					( Origin gFrontEnd )
				)
				( attribute "ROT" "0"
					( Origin gFrontEnd )
				)
				( attribute "SEC" "1"
					( Origin gFrontEnd )
				)
				( attribute "SEC_TYPE" "SH0201"
					( Origin gFrontEnd )
				)
				( attribute "VER" "1"
					( Origin gFrontEnd )
				)
				( attribute "XY" "(4975,0)"
					( Origin gFrontEnd )
				)
				( attribute "CHIPS_PART_NAME" "SHUNT"
					( Origin gPackager )
				)
				( attribute "CDS_PART_NAME" "SHUNT_SH0201-EMPTY,N_A"
					( Origin gPackager )
				)
				( objectStatus "SH5U1" )
				( pin "a"
					( attribute "PN" "1"
						( Origin gPackager )
					)
					( objectStatus "SH5U1.1" )
				)
				( pin "b"
					( attribute "PN" "2"
						( Origin gPackager )
					)
					( objectStatus "SH5U1.2" )
				)
			)
			( gate "@baseboard_fab2_lib.baseboard_fab2(sch_1):page222_i12"
				( attribute "BOM_COST" "MEM_VRD_VTT_DEF"
					( Origin gFrontEnd )
				)
				( attribute "CDS_LIB" "mstr_discrete"
					( Origin gPackager )
				)
				( attribute "CDS_LOCATION" "C4A12"
					( Origin gPackager )
				)
				( attribute "CDS_SEC" "1"
					( Origin gPackager )
				)
				( attribute "LOCATION" "C4A12"
					( Origin gFrontEnd )
				)
				( attribute "MATERIAL" "X7R"
					( Origin gFrontEnd )
				)
				( attribute "PACK_TYPE" "0402LF"
					( Origin gFrontEnd )
				)
				( attribute "PART_NUMBER" "A36096-046"
					( Origin gFrontEnd )
				)
				( attribute "PHYS_PAGE" "222"
					( Origin gFrontEnd )
				)
				( attribute "ROOM" "VTT_DEF_PWR_VR"
					( Origin gFrontEnd )
				)
				( attribute "ROT" "0"
					( Origin gFrontEnd )
				)
				( attribute "SEC" "1"
					( Origin gFrontEnd )
				)
				( attribute "SEC_TYPE" "0402LF"
					( Origin gFrontEnd )
				)
				( attribute "TOLERANCE" "10%"
					( Origin gFrontEnd )
				)
				( attribute "VALUE" "1000PF"
					( Origin gFrontEnd )
				)
				( attribute "VER" "1"
					( Origin gFrontEnd )
				)
				( attribute "VOLTAGE" "50V"
					( Units "uVoltage" "V" 1.000000)
					( Origin gFrontEnd )
				)
				( attribute "XY" "(4000,1725)"
					( Origin gFrontEnd )
				)
				( attribute "CHIPS_PART_NAME" "CAP"
					( Origin gPackager )
				)
				( attribute "CDS_PART_NAME" "CAP_0402LF-1000PF,50V,10%,X7R,A"
					( Origin gPackager )
				)
				( objectStatus "C4A12" )
				( pin "a"
					( attribute "PN" "1"
						( Origin gPackager )
					)
					( objectStatus "C4A12.1" )
				)
				( pin "b"
					( attribute "PN" "2"
						( Origin gPackager )
					)
					( objectStatus "C4A12.2" )
				)
			)
			( gate "@baseboard_fab2_lib.baseboard_fab2(sch_1):page222_i16"
				( attribute "BOM_COST" "MEM_VRD_VTT_DEF"
					( Origin gFrontEnd )
				)
				( attribute "CDS_LIB" "mstr_discrete"
					( Origin gPackager )
				)
				( attribute "CDS_LOCATION" "C4A1"
					( Origin gPackager )
				)
				( attribute "CDS_SEC" "1"
					( Origin gPackager )
				)
				( attribute "LOCATION" "C4A1"
					( Origin gFrontEnd )
				)
				( attribute "MATERIAL" "X6S"
					( Origin gFrontEnd )
				)
				( attribute "PACK_TYPE" "0805LF"
					( Origin gFrontEnd )
				)
				( attribute "PART_NUMBER" "C95333-002"
					( Origin gFrontEnd )
				)
				( attribute "PHYS_PAGE" "222"
					( Origin gFrontEnd )
				)
				( attribute "ROOM" "VTT_DEF_PWR_VR"
					( Origin gFrontEnd )
				)
				( attribute "ROT" "0"
					( Origin gFrontEnd )
				)
				( attribute "SEC" "1"
					( Origin gFrontEnd )
				)
				( attribute "SEC_TYPE" "0805LF"
					( Origin gFrontEnd )
				)
				( attribute "TOLERANCE" "20%"
					( Origin gFrontEnd )
				)
				( attribute "VALUE" "22UF"
					( Origin gFrontEnd )
				)
				( attribute "VER" "1"
					( Origin gFrontEnd )
				)
				( attribute "VOLTAGE" "4V"
					( Units "uVoltage" "V" 1.000000)
					( Origin gFrontEnd )
				)
				( attribute "XY" "(4125,1125)"
					( Origin gFrontEnd )
				)
				( attribute "CHIPS_PART_NAME" "CAP"
					( Origin gPackager )
				)
				( attribute "CDS_PART_NAME" "CAP_0805LF-22UF,4V,20%,X6S,C95A"
					( Origin gPackager )
				)
				( objectStatus "C4A1" )
				( pin "a"
					( attribute "PN" "1"
						( Origin gPackager )
					)
					( objectStatus "C4A1.1" )
				)
				( pin "b"
					( attribute "PN" "2"
						( Origin gPackager )
					)
					( objectStatus "C4A1.2" )
				)
			)
			( gate "@baseboard_fab2_lib.baseboard_fab2(sch_1):page222_i19"
				( attribute "BOM_COST" "MEM_VRD_VTT_DEF"
					( Origin gFrontEnd )
				)
				( attribute "CDS_LIB" "mstr_discrete"
					( Origin gPackager )
				)
				( attribute "CDS_LOCATION" "R6L9"
					( Origin gPackager )
				)
				( attribute "CDS_SEC" "1"
					( Origin gPackager )
				)
				( attribute "LOCATION" "R6L9"
					( Origin gFrontEnd )
				)
				( attribute "MATERIAL" "CHIP"
					( Origin gFrontEnd )
				)
				( attribute "PACK_TYPE" "0402"
					( Origin gFrontEnd )
				)
				( attribute "PART_NUMBER" "G21796-016"
					( Origin gFrontEnd )
				)
				( attribute "PHYS_PAGE" "222"
					( Origin gFrontEnd )
				)
				( attribute "ROOM" "VTT_DEF_PWR_VR"
					( Origin gFrontEnd )
				)
				( attribute "ROT" "0"
					( Origin gFrontEnd )
				)
				( attribute "SEC" "1"
					( Origin gFrontEnd )
				)
				( attribute "SEC_TYPE" "0402"
					( Origin gFrontEnd )
				)
				( attribute "TOLERANCE" "1%"
					( Origin gFrontEnd )
				)
				( attribute "VALUE" "10.0K"
					( Origin gFrontEnd )
				)
				( attribute "VER" "2"
					( Origin gFrontEnd )
				)
				( attribute "WATTAGE" "1/16W"
					( Origin gFrontEnd )
				)
				( attribute "XY" "(3575,2100)"
					( Origin gFrontEnd )
				)
				( attribute "CHIPS_PART_NAME" "RES"
					( Origin gPackager )
				)
				( attribute "CDS_PART_NAME" "RES_0402-10.0K,1%,1/16W,CHIP,GA"
					( Origin gPackager )
				)
				( objectStatus "R6L9" )
				( pin "a"
					( attribute "PN" "1"
						( Origin gPackager )
					)
					( objectStatus "R6L9.1" )
				)
				( pin "b"
					( attribute "PN" "2"
						( Origin gPackager )
					)
					( objectStatus "R6L9.2" )
				)
			)
			( gate "@baseboard_fab2_lib.baseboard_fab2(sch_1):page222_i21"
				( attribute "BOM_COST" "MEM_VRD_VTT_DEF"
					( Origin gFrontEnd )
				)
				( attribute "CDS_LIB" "mstr_discrete"
					( Origin gPackager )
				)
				( attribute "CDS_LOCATION" "C4A9"
					( Origin gPackager )
				)
				( attribute "CDS_SEC" "1"
					( Origin gPackager )
				)
				( attribute "LOCATION" "C4A9"
					( Origin gFrontEnd )
				)
				( attribute "MATERIAL" "X6S"
					( Origin gFrontEnd )
				)
				( attribute "PACK_TYPE" "0402"
					( Origin gFrontEnd )
				)
				( attribute "PART_NUMBER" "D97712-011"
					( Origin gFrontEnd )
				)
				( attribute "PHYS_PAGE" "222"
					( Origin gFrontEnd )
				)
				( attribute "ROOM" "VTT_DEF_PWR_VR"
					( Origin gFrontEnd )
				)
				( attribute "ROT" "0"
					( Origin gFrontEnd )
				)
				( attribute "SEC" "1"
					( Origin gFrontEnd )
				)
				( attribute "SEC_TYPE" "0402"
					( Origin gFrontEnd )
				)
				( attribute "TOLERANCE" "10%"
					( Origin gFrontEnd )
				)
				( attribute "VALUE" "1.0UF"
					( Origin gFrontEnd )
				)
				( attribute "VER" "1"
					( Origin gFrontEnd )
				)
				( attribute "VOLTAGE" "16V"
					( Units "uVoltage" "V" 1.000000)
					( Origin gFrontEnd )
				)
				( attribute "XY" "(2550,950)"
					( Origin gFrontEnd )
				)
				( attribute "CHIPS_PART_NAME" "CAP"
					( Origin gPackager )
				)
				( attribute "CDS_PART_NAME" "CAP_0402-1.0UF,16V,10%,X6S,D97A"
					( Origin gPackager )
				)
				( objectStatus "C4A9" )
				( pin "a"
					( attribute "PN" "1"
						( Origin gPackager )
					)
					( objectStatus "C4A9.1" )
				)
				( pin "b"
					( attribute "PN" "2"
						( Origin gPackager )
					)
					( objectStatus "C4A9.2" )
				)
			)
			( gate "@baseboard_fab2_lib.baseboard_fab2(sch_1):page222_i24"
				( attribute "BOM_COST" "MEM_VRD_VTT_DEF"
					( Origin gFrontEnd )
				)
				( attribute "CDS_LIB" "mstr_discrete"
					( Origin gPackager )
				)
				( attribute "CDS_LOCATION" "C6L3"
					( Origin gPackager )
				)
				( attribute "CDS_SEC" "1"
					( Origin gPackager )
				)
				( attribute "LOCATION" "C6L3"
					( Origin gFrontEnd )
				)
				( attribute "MATERIAL" "X6S"
					( Origin gFrontEnd )
				)
				( attribute "PACK_TYPE" "0603LF"
					( Origin gFrontEnd )
				)
				( attribute "PART_NUMBER" "E15431-001"
					( Origin gFrontEnd )
				)
				( attribute "PHYS_PAGE" "222"
					( Origin gFrontEnd )
				)
				( attribute "ROOM" "VTT_DEF_PWR_VR"
					( Origin gFrontEnd )
				)
				( attribute "ROT" "0"
					( Origin gFrontEnd )
				)
				( attribute "SEC" "1"
					( Origin gFrontEnd )
				)
				( attribute "SEC_TYPE" "0603LF"
					( Origin gFrontEnd )
				)
				( attribute "TOLERANCE" "20%"
					( Origin gFrontEnd )
				)
				( attribute "VALUE" "10UF"
					( Origin gFrontEnd )
				)
				( attribute "VER" "1"
					( Origin gFrontEnd )
				)
				( attribute "VOLTAGE" "4V"
					( Units "uVoltage" "V" 1.000000)
					( Origin gFrontEnd )
				)
				( attribute "XY" "(600,2475)"
					( Origin gFrontEnd )
				)
				( attribute "CHIPS_PART_NAME" "CAP"
					( Origin gPackager )
				)
				( attribute "CDS_PART_NAME" "CAP_0603LF-10UF,4V,20%,X6S,E15A"
					( Origin gPackager )
				)
				( objectStatus "C6L3" )
				( pin "a"
					( attribute "PN" "1"
						( Origin gPackager )
					)
					( objectStatus "C6L3.1" )
				)
				( pin "b"
					( attribute "PN" "2"
						( Origin gPackager )
					)
					( objectStatus "C6L3.2" )
				)
			)
			( gate "@baseboard_fab2_lib.baseboard_fab2(sch_1):page222_i26"
				( attribute "BOM_COST" "MEM_VRD_VTT_DEF"
					( Origin gFrontEnd )
				)
				( attribute "CDS_LIB" "mstr_discrete"
					( Origin gPackager )
				)
				( attribute "CDS_LOCATION" "C6L4"
					( Origin gPackager )
				)
				( attribute "CDS_SEC" "1"
					( Origin gPackager )
				)
				( attribute "LOCATION" "C6L4"
					( Origin gFrontEnd )
				)
				( attribute "MATERIAL" "X6S"
					( Origin gFrontEnd )
				)
				( attribute "PACK_TYPE" "0603LF"
					( Origin gFrontEnd )
				)
				( attribute "PART_NUMBER" "E15431-001"
					( Origin gFrontEnd )
				)
				( attribute "PHYS_PAGE" "222"
					( Origin gFrontEnd )
				)
				( attribute "ROOM" "VTT_DEF_PWR_VR"
					( Origin gFrontEnd )
				)
				( attribute "ROT" "0"
					( Origin gFrontEnd )
				)
				( attribute "SEC" "1"
					( Origin gFrontEnd )
				)
				( attribute "SEC_TYPE" "0603LF"
					( Origin gFrontEnd )
				)
				( attribute "TOLERANCE" "20%"
					( Origin gFrontEnd )
				)
				( attribute "VALUE" "10UF"
					( Origin gFrontEnd )
				)
				( attribute "VER" "1"
					( Origin gFrontEnd )
				)
				( attribute "VOLTAGE" "4V"
					( Units "uVoltage" "V" 1.000000)
					( Origin gFrontEnd )
				)
				( attribute "XY" "(175,2450)"
					( Origin gFrontEnd )
				)
				( attribute "CHIPS_PART_NAME" "CAP"
					( Origin gPackager )
				)
				( attribute "CDS_PART_NAME" "CAP_0603LF-10UF,4V,20%,X6S,E15A"
					( Origin gPackager )
				)
				( objectStatus "C6L4" )
				( pin "a"
					( attribute "PN" "1"
						( Origin gPackager )
					)
					( objectStatus "C6L4.1" )
				)
				( pin "b"
					( attribute "PN" "2"
						( Origin gPackager )
					)
					( objectStatus "C6L4.2" )
				)
			)
			( gate "@baseboard_fab2_lib.baseboard_fab2(sch_1):page222_i28"
				( attribute "BOM_COST" "MEM_VRD_VTT_DEF"
					( Origin gFrontEnd )
				)
				( attribute "CDS_LIB" "mstr_discrete"
					( Origin gPackager )
				)
				( attribute "CDS_LOCATION" "C4A10"
					( Origin gPackager )
				)
				( attribute "CDS_SEC" "1"
					( Origin gPackager )
				)
				( attribute "LOCATION" "C4A10"
					( Origin gFrontEnd )
				)
				( attribute "MATERIAL" "X6S"
					( Origin gFrontEnd )
				)
				( attribute "PACK_TYPE" "0402"
					( Origin gFrontEnd )
				)
				( attribute "PART_NUMBER" "D97712-011"
					( Origin gFrontEnd )
				)
				( attribute "PHYS_PAGE" "222"
					( Origin gFrontEnd )
				)
				( attribute "ROOM" "VTT_DEF_PWR_VR"
					( Origin gFrontEnd )
				)
				( attribute "ROT" "0"
					( Origin gFrontEnd )
				)
				( attribute "SEC" "1"
					( Origin gFrontEnd )
				)
				( attribute "SEC_TYPE" "0402"
					( Origin gFrontEnd )
				)
				( attribute "TOLERANCE" "10%"
					( Origin gFrontEnd )
				)
				( attribute "VALUE" "1.0UF"
					( Origin gFrontEnd )
				)
				( attribute "VER" "1"
					( Origin gFrontEnd )
				)
				( attribute "VOLTAGE" "16V"
					( Units "uVoltage" "V" 1.000000)
					( Origin gFrontEnd )
				)
				( attribute "XY" "(600,1600)"
					( Origin gFrontEnd )
				)
				( attribute "CHIPS_PART_NAME" "CAP"
					( Origin gPackager )
				)
				( attribute "CDS_PART_NAME" "CAP_0402-1.0UF,16V,10%,X6S,D97A"
					( Origin gPackager )
				)
				( objectStatus "C4A10" )
				( pin "a"
					( attribute "PN" "1"
						( Origin gPackager )
					)
					( objectStatus "C4A10.1" )
				)
				( pin "b"
					( attribute "PN" "2"
						( Origin gPackager )
					)
					( objectStatus "C4A10.2" )
				)
			)
			( gate "@baseboard_fab2_lib.baseboard_fab2(sch_1):page222_i30"
				( attribute "BOM_COST" "MEM_VRD_VTT_DEF"
					( Origin gFrontEnd )
				)
				( attribute "CDS_LIB" "mstr_discrete"
					( Origin gPackager )
				)
				( attribute "CDS_LOCATION" "R6L11"
					( Origin gPackager )
				)
				( attribute "CDS_SEC" "1"
					( Origin gPackager )
				)
				( attribute "LOCATION" "R6L11"
					( Origin gFrontEnd )
				)
				( attribute "MATERIAL" "CHIP"
					( Origin gFrontEnd )
				)
				( attribute "PACK_TYPE" "0402"
					( Origin gFrontEnd )
				)
				( attribute "PART_NUMBER" "G21497-005"
					( Origin gFrontEnd )
				)
				( attribute "PHYS_PAGE" "222"
					( Origin gFrontEnd )
				)
				( attribute "ROOM" "VTT_DEF_PWR_VR"
					( Origin gFrontEnd )
				)
				( attribute "ROT" "0"
					( Origin gFrontEnd )
				)
				( attribute "SEC" "1"
					( Origin gFrontEnd )
				)
				( attribute "SEC_TYPE" "0402"
					( Origin gFrontEnd )
				)
				( attribute "TOLERANCE" "5%"
					( Origin gFrontEnd )
				)
				( attribute "VALUE" "0.0"
					( Origin gFrontEnd )
				)
				( attribute "VER" "1"
					( Origin gFrontEnd )
				)
				( attribute "WATTAGE" "1/16W"
					( Origin gFrontEnd )
				)
				( attribute "XY" "(275,1850)"
					( Origin gFrontEnd )
				)
				( attribute "CHIPS_PART_NAME" "RES"
					( Origin gPackager )
				)
				( attribute "CDS_PART_NAME" "RES_0402-0.0,5%,1/16W,CHIP,G21A"
					( Origin gPackager )
				)
				( objectStatus "R6L11" )
				( pin "a"
					( attribute "PN" "1"
						( Origin gPackager )
					)
					( objectStatus "R6L11.1" )
				)
				( pin "b"
					( attribute "PN" "2"
						( Origin gPackager )
					)
					( objectStatus "R6L11.2" )
				)
			)
			( gate "@baseboard_fab2_lib.baseboard_fab2(sch_1):page222_i31"
				( attribute "BOM_COST" "MEM_VRD_VTT_DEF"
					( Origin gFrontEnd )
				)
				( attribute "CDS_LIB" "mstr_vreg"
					( Origin gPackager )
				)
				( attribute "CDS_LMAN_SYM_OUTLINE" "-250,350,250,-350"
					( Origin gPackager )
				)
				( attribute "CDS_LOCATION" "EU4A1"
					( Origin gPackager )
				)
				( attribute "CDS_SEC" "1"
					( Origin gPackager )
				)
				( attribute "LOCATION" "EU4A1"
					( Origin gFrontEnd )
				)
				( attribute "MATERIAL" "IC"
					( Origin gFrontEnd )
				)
				( attribute "PACK_TYPE" "DFN"
					( Origin gFrontEnd )
				)
				( attribute "PART_NUMBER" "H55101-001"
					( Origin gFrontEnd )
				)
				( attribute "PHYS_PAGE" "222"
					( Origin gFrontEnd )
				)
				( attribute "ROOM" "VTT_DEF_PWR_VR"
					( Origin gFrontEnd )
				)
				( attribute "ROT" "0"
					( Origin gFrontEnd )
				)
				( attribute "SEC" "1"
					( Origin gFrontEnd )
				)
				( attribute "SEC_TYPE" "DFN"
					( Origin gFrontEnd )
				)
				( attribute "VER" "1"
					( Origin gFrontEnd )
				)
				( attribute "XY" "(1700,1150)"
					( Origin gFrontEnd )
				)
				( attribute "CHIPS_PART_NAME" "MIC5166"
					( Origin gPackager )
				)
				( attribute "CDS_PART_NAME" "MIC5166_DFN-IC,H55101-001"
					( Origin gPackager )
				)
				( objectStatus "EU4A1" )
				( pin "agnd"
					( attribute "PN" "3"
						( Origin gPackager )
					)
					( objectStatus "EU4A1.3" )
				)
				( pin "bias"
					( attribute "PN" "2"
						( Origin gPackager )
					)
					( objectStatus "EU4A1.2" )
				)
				( pin "en"
					( attribute "PN" "7"
						( Origin gPackager )
					)
					( objectStatus "EU4A1.7" )
				)
				( pin "pg"
					( attribute "PN" "5"
						( Origin gPackager )
					)
					( objectStatus "EU4A1.5" )
				)
				( pin "pgnd"
					( attribute "PN" "8"
						( Origin gPackager )
					)
					( objectStatus "EU4A1.8" )
				)
				( pin "sns"
					( attribute "PN" "6"
						( Origin gPackager )
					)
					( objectStatus "EU4A1.6" )
				)
				( pin "thpad"
					( attribute "PN" "11"
						( Origin gPackager )
					)
					( objectStatus "EU4A1.11" )
				)
				( pin "vddq"
					( attribute "PN" "4"
						( Origin gPackager )
					)
					( objectStatus "EU4A1.4" )
				)
				( pin "vin"
					( attribute "PN" "10"
						( Origin gPackager )
					)
					( objectStatus "EU4A1.10" )
				)
				( pin "vref"
					( attribute "PN" "1"
						( Origin gPackager )
					)
					( objectStatus "EU4A1.1" )
				)
				( pin "vtt"
					( attribute "PN" "9"
						( Origin gPackager )
					)
					( objectStatus "EU4A1.9" )
				)
			)
			( gate "@baseboard_fab2_lib.baseboard_fab2(sch_1):page222_i34"
				( attribute "BOM_COST" "MEM_VRD_VTT_DEF"
					( Origin gFrontEnd )
				)
				( attribute "CDS_LIB" "mstr_discrete"
					( Origin gPackager )
				)
				( attribute "CDS_LOCATION" "R6L10"
					( Origin gPackager )
				)
				( attribute "CDS_SEC" "1"
					( Origin gPackager )
				)
				( attribute "LOCATION" "R6L10"
					( Origin gFrontEnd )
				)
				( attribute "MATERIAL" "CHIP"
					( Origin gFrontEnd )
				)
				( attribute "NO_XNET_CONNECTION" "1"
					( Origin gFrontEnd )
				)
				( attribute "PACK_TYPE" "0402"
					( Origin gFrontEnd )
				)
				( attribute "PART_NUMBER" "G21497-005"
					( Origin gFrontEnd )
				)
				( attribute "PHYS_PAGE" "222"
					( Origin gFrontEnd )
				)
				( attribute "ROOM" "VTT_DEF_PWR_VR"
					( Origin gFrontEnd )
				)
				( attribute "ROT" "1"
					( Origin gFrontEnd )
				)
				( attribute "SEC" "1"
					( Origin gFrontEnd )
				)
				( attribute "SEC_TYPE" "0402"
					( Origin gFrontEnd )
				)
				( attribute "TOLERANCE" "5%"
					( Origin gFrontEnd )
				)
				( attribute "VALUE" "0.0"
					( Origin gFrontEnd )
				)
				( attribute "VER" "2"
					( Origin gFrontEnd )
				)
				( attribute "WATTAGE" "1/16W"
					( Origin gFrontEnd )
				)
				( attribute "XY" "(-575,1650)"
					( Origin gFrontEnd )
				)
				( attribute "CHIPS_PART_NAME" "RES"
					( Origin gPackager )
				)
				( attribute "CDS_PART_NAME" "RES_0402-0.0,5%,1/16W,CHIP,G21A"
					( Origin gPackager )
				)
				( objectStatus "R6L10" )
				( pin "a"
					( attribute "PN" "1"
						( Origin gPackager )
					)
					( objectStatus "R6L10.1" )
				)
				( pin "b"
					( attribute "PN" "2"
						( Origin gPackager )
					)
					( objectStatus "R6L10.2" )
				)
			)
			( gate "@baseboard_fab2_lib.baseboard_fab2(sch_1):page222_i37"
				( attribute "BOM_COST" "MEM_VRD_VTT_DEF"
					( Origin gFrontEnd )
				)
				( attribute "CDS_LIB" "mstr_discrete"
					( Origin gPackager )
				)
				( attribute "CDS_LOCATION" "R6L4"
					( Origin gPackager )
				)
				( attribute "CDS_SEC" "1"
					( Origin gPackager )
				)
				( attribute "LOCATION" "R6L4"
					( Origin gFrontEnd )
				)
				( attribute "MATERIAL" "EMPTY"
					( Origin gFrontEnd )
				)
				( attribute "PACK_TYPE" "0402"
					( Origin gFrontEnd )
				)
				( attribute "PART_NUMBER" "G21796-021"
					( Origin gFrontEnd )
				)
				( attribute "PHYS_PAGE" "222"
					( Origin gFrontEnd )
				)
				( attribute "ROOM" "VTT_DEF_PWR_VR"
					( Origin gFrontEnd )
				)
				( attribute "ROT" "2"
					( Origin gFrontEnd )
				)
				( attribute "SEC" "1"
					( Origin gFrontEnd )
				)
				( attribute "SEC_TYPE" "0402"
					( Origin gFrontEnd )
				)
				( attribute "TOLERANCE" "1%"
					( Origin gFrontEnd )
				)
				( attribute "VALUE" "1.0M"
					( Origin gFrontEnd )
				)
				( attribute "VER" "2"
					( Origin gFrontEnd )
				)
				( attribute "WATTAGE" "1/16W"
					( Origin gFrontEnd )
				)
				( attribute "XY" "(-175,750)"
					( Origin gFrontEnd )
				)
				( attribute "CHIPS_PART_NAME" "RES"
					( Origin gPackager )
				)
				( attribute "CDS_PART_NAME" "RES_0402-1.0M,1%,1/16W,EMPTY,GA"
					( Origin gPackager )
				)
				( objectStatus "R6L4" )
				( pin "a"
					( attribute "PN" "1"
						( Origin gPackager )
					)
					( objectStatus "R6L4.1" )
				)
				( pin "b"
					( attribute "PN" "2"
						( Origin gPackager )
					)
					( objectStatus "R6L4.2" )
				)
			)
			( gate "@baseboard_fab2_lib.baseboard_fab2(sch_1):page222_i38"
				( attribute "BOM_COST" "MEM_VRD_VTT_DEF"
					( Origin gFrontEnd )
				)
				( attribute "CDS_LIB" "mstr_discrete"
					( Origin gPackager )
				)
				( attribute "CDS_LOCATION" "R4A2"
					( Origin gPackager )
				)
				( attribute "CDS_SEC" "1"
					( Origin gPackager )
				)
				( attribute "LOCATION" "R4A2"
					( Origin gFrontEnd )
				)
				( attribute "MATERIAL" "CHIP"
					( Origin gFrontEnd )
				)
				( attribute "PACK_TYPE" "0402"
					( Origin gFrontEnd )
				)
				( attribute "PART_NUMBER" "G21497-005"
					( Origin gFrontEnd )
				)
				( attribute "PHYS_PAGE" "222"
					( Origin gFrontEnd )
				)
				( attribute "ROOM" "VTT_DEF_PWR_VR"
					( Origin gFrontEnd )
				)
				( attribute "ROT" "0"
					( Origin gFrontEnd )
				)
				( attribute "SEC" "1"
					( Origin gFrontEnd )
				)
				( attribute "SEC_TYPE" "0402"
					( Origin gFrontEnd )
				)
				( attribute "TOLERANCE" "5%"
					( Origin gFrontEnd )
				)
				( attribute "VALUE" "0.0"
					( Origin gFrontEnd )
				)
				( attribute "VER" "1"
					( Origin gFrontEnd )
				)
				( attribute "WATTAGE" "1/16W"
					( Origin gFrontEnd )
				)
				( attribute "XY" "(-375,225)"
					( Origin gFrontEnd )
				)
				( attribute "CHIPS_PART_NAME" "RES"
					( Origin gPackager )
				)
				( attribute "CDS_PART_NAME" "RES_0402-0.0,5%,1/16W,CHIP,G21A"
					( Origin gPackager )
				)
				( objectStatus "R4A2" )
				( pin "a"
					( attribute "PN" "1"
						( Origin gPackager )
					)
					( objectStatus "R4A2.1" )
				)
				( pin "b"
					( attribute "PN" "2"
						( Origin gPackager )
					)
					( objectStatus "R4A2.2" )
				)
			)
			( gate "@baseboard_fab2_lib.baseboard_fab2(sch_1):page222_i40"
				( attribute "BOM_COST" "MEM_VRD_VTT_DEF"
					( Origin gFrontEnd )
				)
				( attribute "CDS_LIB" "mstr_discrete"
					( Origin gPackager )
				)
				( attribute "CDS_LOCATION" "C4A2"
					( Origin gPackager )
				)
				( attribute "CDS_SEC" "1"
					( Origin gPackager )
				)
				( attribute "LOCATION" "C4A2"
					( Origin gFrontEnd )
				)
				( attribute "MATERIAL" "EMPTY"
					( Origin gFrontEnd )
				)
				( attribute "PACK_TYPE" "0402LF"
					( Origin gFrontEnd )
				)
				( attribute "PART_NUMBER" "A36096-046"
					( Origin gFrontEnd )
				)
				( attribute "PHYS_PAGE" "222"
					( Origin gFrontEnd )
				)
				( attribute "ROOM" "VTT_DEF_PWR_VR"
					( Origin gFrontEnd )
				)
				( attribute "ROT" "2"
					( Origin gFrontEnd )
				)
				( attribute "SEC" "1"
					( Origin gFrontEnd )
				)
				( attribute "SEC_TYPE" "0402LF"
					( Origin gFrontEnd )
				)
				( attribute "TOLERANCE" "10%"
					( Origin gFrontEnd )
				)
				( attribute "VALUE" "1000PF"
					( Origin gFrontEnd )
				)
				( attribute "VER" "1"
					( Origin gFrontEnd )
				)
				( attribute "VOLTAGE" "50V"
					( Units "uVoltage" "V" 1.000000)
					( Origin gFrontEnd )
				)
				( attribute "XY" "(-225,-300)"
					( Origin gFrontEnd )
				)
				( attribute "CHIPS_PART_NAME" "CAP"
					( Origin gPackager )
				)
				( attribute "CDS_PART_NAME" "CAP_0402LF-1000PF,50V,10%,EMPTA"
					( Origin gPackager )
				)
				( objectStatus "C4A2" )
				( pin "a"
					( attribute "PN" "1"
						( Origin gPackager )
					)
					( objectStatus "C4A2.1" )
				)
				( pin "b"
					( attribute "PN" "2"
						( Origin gPackager )
					)
					( objectStatus "C4A2.2" )
				)
			)
			( gate "@baseboard_fab2_lib.baseboard_fab2(sch_1):page222_i46"
				( attribute "CDS_LIB" "mstr_discrete"
					( Origin gPackager )
				)
				( attribute "CDS_LOCATION" "C4A11"
					( Origin gPackager )
				)
				( attribute "CDS_SEC" "1"
					( Origin gPackager )
				)
				( attribute "LOCATION" "C4A11"
					( Origin gFrontEnd )
				)
				( attribute "MATERIAL" "X6S"
					( Origin gFrontEnd )
				)
				( attribute "PACK_TYPE" "0603"
					( Origin gFrontEnd )
				)
				( attribute "PART_NUMBER" "E15431-003"
					( Origin gFrontEnd )
				)
				( attribute "PHYS_PAGE" "222"
					( Origin gFrontEnd )
				)
				( attribute "ROOM" "VTT_DEF_PWR_VR"
					( Origin gFrontEnd )
				)
				( attribute "ROT" "0"
					( Origin gFrontEnd )
				)
				( attribute "SEC" "1"
					( Origin gFrontEnd )
				)
				( attribute "SEC_TYPE" "0603"
					( Origin gFrontEnd )
				)
				( attribute "TOLERANCE" "10%"
					( Origin gFrontEnd )
				)
				( attribute "VALUE" "4.7UF"
					( Origin gFrontEnd )
				)
				( attribute "VER" "1"
					( Origin gFrontEnd )
				)
				( attribute "VOLTAGE" "6.3V"
					( Units "uVoltage" "V" 1.000000)
					( Origin gFrontEnd )
				)
				( attribute "XY" "(425,1075)"
					( Origin gFrontEnd )
				)
				( attribute "CHIPS_PART_NAME" "CAP"
					( Origin gPackager )
				)
				( attribute "CDS_PART_NAME" "CAP_0603-4.7UF,6.3V,10%,X6S,E1A"
					( Origin gPackager )
				)
				( objectStatus "C4A11" )
				( pin "a"
					( attribute "PN" "1"
						( Origin gPackager )
					)
					( objectStatus "C4A11.1" )
				)
				( pin "b"
					( attribute "PN" "2"
						( Origin gPackager )
					)
					( objectStatus "C4A11.2" )
				)
			)
			( gate "@baseboard_fab2_lib.baseboard_fab2(sch_1):page222_i47"
				( attribute "CDS_LIB" "dev_discrete"
					( Origin gPackager )
				)
				( attribute "CDS_LOCATION" "C5L4"
					( Origin gPackager )
				)
				( attribute "CDS_SEC" "1"
					( Origin gPackager )
				)
				( attribute "LOCATION" "C5L4"
					( Origin gFrontEnd )
				)
				( attribute "MATERIAL" "X5R"
					( Origin gFrontEnd )
				)
				( attribute "PACK_TYPE" "0603V"
					( Origin gFrontEnd )
				)
				( attribute "PART_NUMBER" "602433-106"
					( Origin gFrontEnd )
				)
				( attribute "PHYS_PAGE" "222"
					( Origin gFrontEnd )
				)
				( attribute "ROT" "0"
					( Origin gFrontEnd )
				)
				( attribute "SEC" "1"
					( Origin gFrontEnd )
				)
				( attribute "SEC_TYPE" "0603V"
					( Origin gFrontEnd )
				)
				( attribute "TOLERANCE" "20%"
					( Origin gFrontEnd )
				)
				( attribute "VALUE" "47UF"
					( Origin gFrontEnd )
				)
				( attribute "VER" "1"
					( Origin gFrontEnd )
				)
				( attribute "VOLTAGE" "4V"
					( Units "uVoltage" "V" 1.000000)
					( Origin gFrontEnd )
				)
				( attribute "XY" "(3675,3475)"
					( Origin gFrontEnd )
				)
				( attribute "CHIPS_PART_NAME" "CAP_A"
					( Origin gPackager )
				)
				( attribute "CDS_PART_NAME" "CAP_A_0603V-47UF,4V,20%,X5R,60A"
					( Origin gPackager )
				)
				( objectStatus "C5L4" )
				( pin "a"
					( attribute "PN" "1"
						( Origin gPackager )
					)
					( objectStatus "C5L4.1" )
				)
				( pin "b"
					( attribute "PN" "2"
						( Origin gPackager )
					)
					( objectStatus "C5L4.2" )
				)
			)
			( gate "@baseboard_fab2_lib.baseboard_fab2(sch_1):page222_i48"
				( attribute "CDS_LIB" "dev_discrete"
					( Origin gPackager )
				)
				( attribute "CDS_LOCATION" "C5M13"
					( Origin gPackager )
				)
				( attribute "CDS_SEC" "1"
					( Origin gPackager )
				)
				( attribute "LOCATION" "C5M13"
					( Origin gFrontEnd )
				)
				( attribute "MATERIAL" "X5R"
					( Origin gFrontEnd )
				)
				( attribute "PACK_TYPE" "0603V"
					( Origin gFrontEnd )
				)
				( attribute "PART_NUMBER" "602433-106"
					( Origin gFrontEnd )
				)
				( attribute "PHYS_PAGE" "222"
					( Origin gFrontEnd )
				)
				( attribute "ROT" "0"
					( Origin gFrontEnd )
				)
				( attribute "SEC" "1"
					( Origin gFrontEnd )
				)
				( attribute "SEC_TYPE" "0603V"
					( Origin gFrontEnd )
				)
				( attribute "TOLERANCE" "20%"
					( Origin gFrontEnd )
				)
				( attribute "VALUE" "47UF"
					( Origin gFrontEnd )
				)
				( attribute "VER" "1"
					( Origin gFrontEnd )
				)
				( attribute "VOLTAGE" "4V"
					( Units "uVoltage" "V" 1.000000)
					( Origin gFrontEnd )
				)
				( attribute "XY" "(4025,3475)"
					( Origin gFrontEnd )
				)
				( attribute "CHIPS_PART_NAME" "CAP_A"
					( Origin gPackager )
				)
				( attribute "CDS_PART_NAME" "CAP_A_0603V-47UF,4V,20%,X5R,60A"
					( Origin gPackager )
				)
				( objectStatus "C5M13" )
				( pin "a"
					( attribute "PN" "1"
						( Origin gPackager )
					)
					( objectStatus "C5M13.1" )
				)
				( pin "b"
					( attribute "PN" "2"
						( Origin gPackager )
					)
					( objectStatus "C5M13.2" )
				)
			)
			( gate "@baseboard_fab2_lib.baseboard_fab2(sch_1):page222_i49"
				( attribute "CDS_LIB" "dev_discrete"
					( Origin gPackager )
				)
				( attribute "CDS_LOCATION" "C5L5"
					( Origin gPackager )
				)
				( attribute "CDS_SEC" "1"
					( Origin gPackager )
				)
				( attribute "LOCATION" "C5L5"
					( Origin gFrontEnd )
				)
				( attribute "MATERIAL" "X5R"
					( Origin gFrontEnd )
				)
				( attribute "PACK_TYPE" "0603V"
					( Origin gFrontEnd )
				)
				( attribute "PART_NUMBER" "602433-106"
					( Origin gFrontEnd )
				)
				( attribute "PHYS_PAGE" "222"
					( Origin gFrontEnd )
				)
				( attribute "ROT" "0"
					( Origin gFrontEnd )
				)
				( attribute "SEC" "1"
					( Origin gFrontEnd )
				)
				( attribute "SEC_TYPE" "0603V"
					( Origin gFrontEnd )
				)
				( attribute "TOLERANCE" "20%"
					( Origin gFrontEnd )
				)
				( attribute "VALUE" "47UF"
					( Origin gFrontEnd )
				)
				( attribute "VER" "1"
					( Origin gFrontEnd )
				)
				( attribute "VOLTAGE" "4V"
					( Units "uVoltage" "V" 1.000000)
					( Origin gFrontEnd )
				)
				( attribute "XY" "(4425,3475)"
					( Origin gFrontEnd )
				)
				( attribute "CHIPS_PART_NAME" "CAP_A"
					( Origin gPackager )
				)
				( attribute "CDS_PART_NAME" "CAP_A_0603V-47UF,4V,20%,X5R,60A"
					( Origin gPackager )
				)
				( objectStatus "C5L5" )
				( pin "a"
					( attribute "PN" "1"
						( Origin gPackager )
					)
					( objectStatus "C5L5.1" )
				)
				( pin "b"
					( attribute "PN" "2"
						( Origin gPackager )
					)
					( objectStatus "C5L5.2" )
				)
			)
			( gate "@baseboard_fab2_lib.baseboard_fab2(sch_1):page222_i51"
				( attribute "CDS_LIB" "mstr_discrete"
					( Origin gPackager )
				)
				( attribute "CDS_LOCATION" "R4A6"
					( Origin gPackager )
				)
				( attribute "CDS_SEC" "1"
					( Origin gPackager )
				)
				( attribute "LOCATION" "R4A6"
					( Origin gFrontEnd )
				)
				( attribute "MATERIAL" "CHIP"
					( Origin gFrontEnd )
				)
				( attribute "PACK_TYPE" "0402"
					( Origin gFrontEnd )
				)
				( attribute "PART_NUMBER" "G21796-074"
					( Origin gFrontEnd )
				)
				( attribute "PHYS_PAGE" "222"
					( Origin gFrontEnd )
				)
				( attribute "ROT" "0"
					( Origin gFrontEnd )
				)
				( attribute "SEC" "1"
					( Origin gFrontEnd )
				)
				( attribute "SEC_TYPE" "0402"
					( Origin gFrontEnd )
				)
				( attribute "TOLERANCE" "1%"
					( Origin gFrontEnd )
				)
				( attribute "VALUE" "33.2"
					( Origin gFrontEnd )
				)
				( attribute "VER" "1"
					( Origin gFrontEnd )
				)
				( attribute "WATTAGE" "1/16W"
					( Origin gFrontEnd )
				)
				( attribute "XY" "(4400,1925)"
					( Origin gFrontEnd )
				)
				( attribute "CHIPS_PART_NAME" "RES"
					( Origin gPackager )
				)
				( attribute "CDS_PART_NAME" "RES_0402-33.2,1%,1/16W,CHIP,G2A"
					( Origin gPackager )
				)
				( objectStatus "R4A6" )
				( pin "a"
					( attribute "PN" "1"
						( Origin gPackager )
					)
					( objectStatus "R4A6.1" )
				)
				( pin "b"
					( attribute "PN" "2"
						( Origin gPackager )
					)
					( objectStatus "R4A6.2" )
				)
			)
			( gate "@baseboard_fab2_lib.baseboard_fab2(sch_1):page222_i52"
				( attribute "CDS_LIB" "mstr_discrete"
					( Origin gPackager )
				)
				( attribute "CDS_LOCATION" "R4A1"
					( Origin gPackager )
				)
				( attribute "CDS_SEC" "1"
					( Origin gPackager )
				)
				( attribute "LOCATION" "R4A1"
					( Origin gFrontEnd )
				)
				( attribute "MATERIAL" "CHIP"
					( Origin gFrontEnd )
				)
				( attribute "PACK_TYPE" "0402"
					( Origin gFrontEnd )
				)
				( attribute "PART_NUMBER" "G21796-208"
					( Origin gFrontEnd )
				)
				( attribute "PHYS_PAGE" "222"
					( Origin gFrontEnd )
				)
				( attribute "ROT" "1"
					( Origin gFrontEnd )
				)
				( attribute "SEC" "1"
					( Origin gPackager )
				)
				( attribute "TOLERANCE" "1.0%"
					( Origin gFrontEnd )
				)
				( attribute "VALUE" "51.1"
					( Origin gFrontEnd )
				)
				( attribute "VER" "1"
					( Origin gFrontEnd )
				)
				( attribute "WATTAGE" "1/16W"
					( Origin gFrontEnd )
				)
				( attribute "XY" "(5025,1125)"
					( Origin gFrontEnd )
				)
				( attribute "CHIPS_PART_NAME" "RES"
					( Origin gPackager )
				)
				( attribute "CDS_PART_NAME" "RES_0402-51.1,1.0%,1/16W,CHIP,A"
					( Origin gPackager )
				)
				( objectStatus "R4A1" )
				( pin "a"
					( attribute "PN" "1"
						( Origin gPackager )
					)
					( objectStatus "R4A1.1" )
				)
				( pin "b"
					( attribute "PN" "2"
						( Origin gPackager )
					)
					( objectStatus "R4A1.2" )
				)
			)
			( gate "@baseboard_fab2_lib.baseboard_fab2(sch_1):page222_i53"
				( attribute "CDS_LIB" "mstr_misc"
					( Origin gPackager )
				)
				( attribute "CDS_LOCATION" "SH5L1"
					( Origin gPackager )
				)
				( attribute "CDS_SEC" "1"
					( Origin gPackager )
				)
				( attribute "LOCATION" "SH5L1"
					( Origin gFrontEnd )
				)
				( attribute "MATERIAL" "EMPTY"
					( Origin gFrontEnd )
				)
				( attribute "PACK_TYPE" "SH0201"
					( Origin gFrontEnd )
				)
				( attribute "PART_NUMBER" "N_A"
					( Origin gFrontEnd )
				)
				( attribute "PHYS_PAGE" "222"
					( Origin gFrontEnd )
				)
				( attribute "PIN_SHORT" "A:B"
					( Origin gFrontEnd )
				)
				( attribute "ROT" "0"
					( Origin gFrontEnd )
				)
				( attribute "SEC" "1"
					( Origin gFrontEnd )
				)
				( attribute "SEC_TYPE" "SH0201"
					( Origin gFrontEnd )
				)
				( attribute "VER" "1"
					( Origin gFrontEnd )
				)
				( attribute "XY" "(5100,125)"
					( Origin gFrontEnd )
				)
				( attribute "CHIPS_PART_NAME" "SHUNT"
					( Origin gPackager )
				)
				( attribute "CDS_PART_NAME" "SHUNT_SH0201-EMPTY,N_A"
					( Origin gPackager )
				)
				( objectStatus "SH5L1" )
				( pin "a"
					( attribute "PN" "1"
						( Origin gPackager )
					)
					( objectStatus "SH5L1.1" )
				)
				( pin "b"
					( attribute "PN" "2"
						( Origin gPackager )
					)
					( objectStatus "SH5L1.2" )
				)
			)
			( gate "@baseboard_fab2_lib.baseboard_fab2(sch_1):page223_i8"
				( attribute "CDS_LIB" "mstr_discrete"
					( Origin gPackager )
				)
				( attribute "CDS_LOCATION" "R9U3"
					( Origin gPackager )
				)
				( attribute "CDS_SEC" "1"
					( Origin gPackager )
				)
				( attribute "LOCATION" "R9U3"
					( Origin gFrontEnd )
				)
				( attribute "MATERIAL" "CHIP"
					( Origin gFrontEnd )
				)
				( attribute "PACK_TYPE" "0402"
					( Origin gFrontEnd )
				)
				( attribute "PART_NUMBER" "G21796-017"
					( Origin gFrontEnd )
				)
				( attribute "PHYS_PAGE" "223"
					( Origin gFrontEnd )
				)
				( attribute "ROOM" "VDDQ_GHJ_PWR_VR"
					( Origin gFrontEnd )
				)
				( attribute "ROT" "0"
					( Origin gFrontEnd )
				)
				( attribute "SEC" "1"
					( Origin gFrontEnd )
				)
				( attribute "SEC_TYPE" "0402"
					( Origin gFrontEnd )
				)
				( attribute "TOLERANCE" "1%"
					( Origin gFrontEnd )
				)
				( attribute "VALUE" "100.0"
					( Origin gFrontEnd )
				)
				( attribute "VER" "2"
					( Origin gFrontEnd )
				)
				( attribute "WATTAGE" "1/16W"
					( Origin gFrontEnd )
				)
				( attribute "XY" "(3925,2800)"
					( Origin gFrontEnd )
				)
				( attribute "CHIPS_PART_NAME" "RES"
					( Origin gPackager )
				)
				( attribute "CDS_PART_NAME" "RES_0402-100.0,1%,1/16W,CHIP,GA"
					( Origin gPackager )
				)
				( objectStatus "R9U3" )
				( pin "a"
					( attribute "PN" "1"
						( Origin gPackager )
					)
					( objectStatus "R9U3.1" )
				)
				( pin "b"
					( attribute "PN" "2"
						( Origin gPackager )
					)
					( objectStatus "R9U3.2" )
				)
			)
			( gate "@baseboard_fab2_lib.baseboard_fab2(sch_1):page223_i13"
				( attribute "CDS_LIB" "mstr_discrete"
					( Origin gPackager )
				)
				( attribute "CDS_LOCATION" "R1G6"
					( Origin gPackager )
				)
				( attribute "CDS_SEC" "1"
					( Origin gPackager )
				)
				( attribute "LOCATION" "R1G6"
					( Origin gFrontEnd )
				)
				( attribute "MATERIAL" "EMPTY"
					( Origin gFrontEnd )
				)
				( attribute "PACK_TYPE" "0402"
					( Origin gFrontEnd )
				)
				( attribute "PART_NUMBER" "G21796-311"
					( Origin gFrontEnd )
				)
				( attribute "PHYS_PAGE" "223"
					( Origin gFrontEnd )
				)
				( attribute "ROOM" "VDDQ_GHJ_PWR_VR"
					( Origin gFrontEnd )
				)
				( attribute "ROT" "0"
					( Origin gFrontEnd )
				)
				( attribute "SEC" "1"
					( Origin gFrontEnd )
				)
				( attribute "SEC_TYPE" "0402"
					( Origin gFrontEnd )
				)
				( attribute "TOLERANCE" "1.0%"
					( Origin gFrontEnd )
				)
				( attribute "VALUE" "2.26K"
					( Origin gFrontEnd )
				)
				( attribute "VER" "2"
					( Origin gFrontEnd )
				)
				( attribute "WATTAGE" "1/16W"
					( Origin gFrontEnd )
				)
				( attribute "XY" "(2700,3100)"
					( Origin gFrontEnd )
				)
				( attribute "CHIPS_PART_NAME" "RES"
					( Origin gPackager )
				)
				( attribute "CDS_PART_NAME" "RES_0402-2.26K,1.0%,1/16W,EMPTA"
					( Origin gPackager )
				)
				( objectStatus "R1G6" )
				( pin "a"
					( attribute "PN" "1"
						( Origin gPackager )
					)
					( objectStatus "R1G6.1" )
				)
				( pin "b"
					( attribute "PN" "2"
						( Origin gPackager )
					)
					( objectStatus "R1G6.2" )
				)
			)
			( gate "@baseboard_fab2_lib.baseboard_fab2(sch_1):page223_i14"
				( attribute "CDS_LIB" "mstr_discrete"
					( Origin gPackager )
				)
				( attribute "CDS_LOCATION" "R1G12"
					( Origin gPackager )
				)
				( attribute "CDS_SEC" "1"
					( Origin gPackager )
				)
				( attribute "LOCATION" "R1G12"
					( Origin gFrontEnd )
				)
				( attribute "MATERIAL" "CHIP"
					( Origin gFrontEnd )
				)
				( attribute "PACK_TYPE" "0402"
					( Origin gFrontEnd )
				)
				( attribute "PART_NUMBER" "G21796-250"
					( Origin gFrontEnd )
				)
				( attribute "PHYS_PAGE" "223"
					( Origin gFrontEnd )
				)
				( attribute "ROOM" "VDDQ_GHJ_PWR_VR"
					( Origin gFrontEnd )
				)
				( attribute "ROT" "0"
					( Origin gFrontEnd )
				)
				( attribute "SEC" "1"
					( Origin gPackager )
				)
				( attribute "TOLERANCE" "1.0%"
					( Origin gFrontEnd )
				)
				( attribute "VALUE" "22.1"
					( Origin gFrontEnd )
				)
				( attribute "VER" "1"
					( Origin gFrontEnd )
				)
				( attribute "WATTAGE" "1/16W"
					( Origin gFrontEnd )
				)
				( attribute "XY" "(3275,2550)"
					( Origin gFrontEnd )
				)
				( attribute "CHIPS_PART_NAME" "RES"
					( Origin gPackager )
				)
				( attribute "CDS_PART_NAME" "RES_0402-22.1,1.0%,1/16W,CHIP,A"
					( Origin gPackager )
				)
				( objectStatus "R1G12" )
				( pin "a"
					( attribute "PN" "1"
						( Origin gPackager )
					)
					( objectStatus "R1G12.1" )
				)
				( pin "b"
					( attribute "PN" "2"
						( Origin gPackager )
					)
					( objectStatus "R1G12.2" )
				)
			)
			( gate "@baseboard_fab2_lib.baseboard_fab2(sch_1):page223_i16"
				( attribute "CDS_LIB" "mstr_discrete"
					( Origin gPackager )
				)
				( attribute "CDS_LOCATION" "R1G9"
					( Origin gPackager )
				)
				( attribute "CDS_SEC" "1"
					( Origin gPackager )
				)
				( attribute "LOCATION" "R1G9"
					( Origin gFrontEnd )
				)
				( attribute "MATERIAL" "CHIP"
					( Origin gFrontEnd )
				)
				( attribute "PACK_TYPE" "0402"
					( Origin gFrontEnd )
				)
				( attribute "PART_NUMBER" "G21497-005"
					( Origin gFrontEnd )
				)
				( attribute "PHYS_PAGE" "223"
					( Origin gFrontEnd )
				)
				( attribute "ROOM" "VDDQ_GHJ_PWR_VR"
					( Origin gFrontEnd )
				)
				( attribute "ROT" "0"
					( Origin gFrontEnd )
				)
				( attribute "SEC" "1"
					( Origin gFrontEnd )
				)
				( attribute "SEC_TYPE" "0402"
					( Origin gFrontEnd )
				)
				( attribute "TOLERANCE" "5%"
					( Origin gFrontEnd )
				)
				( attribute "VALUE" "0.0"
					( Origin gFrontEnd )
				)
				( attribute "VER" "1"
					( Origin gFrontEnd )
				)
				( attribute "WATTAGE" "1/16W"
					( Origin gFrontEnd )
				)
				( attribute "XY" "(2875,2400)"
					( Origin gFrontEnd )
				)
				( attribute "CHIPS_PART_NAME" "RES"
					( Origin gPackager )
				)
				( attribute "CDS_PART_NAME" "RES_0402-0.0,5%,1/16W,CHIP,G21A"
					( Origin gPackager )
				)
				( objectStatus "R1G9" )
				( pin "a"
					( attribute "PN" "1"
						( Origin gPackager )
					)
					( objectStatus "R1G9.1" )
				)
				( pin "b"
					( attribute "PN" "2"
						( Origin gPackager )
					)
					( objectStatus "R1G9.2" )
				)
			)
			( gate "@baseboard_fab2_lib.baseboard_fab2(sch_1):page223_i17"
				( attribute "CDS_LIB" "mstr_discrete"
					( Origin gPackager )
				)
				( attribute "CDS_LOCATION" "R1G16"
					( Origin gPackager )
				)
				( attribute "CDS_SEC" "1"
					( Origin gPackager )
				)
				( attribute "LOCATION" "R1G16"
					( Origin gFrontEnd )
				)
				( attribute "MATERIAL" "CHIP"
					( Origin gFrontEnd )
				)
				( attribute "PACK_TYPE" "0402"
					( Origin gFrontEnd )
				)
				( attribute "PART_NUMBER" "G21796-026"
					( Origin gFrontEnd )
				)
				( attribute "PHYS_PAGE" "223"
					( Origin gFrontEnd )
				)
				( attribute "ROOM" "VDDQ_GHJ_PWR_VR"
					( Origin gFrontEnd )
				)
				( attribute "ROT" "0"
					( Origin gFrontEnd )
				)
				( attribute "SEC" "1"
					( Origin gFrontEnd )
				)
				( attribute "SEC_TYPE" "0402"
					( Origin gFrontEnd )
				)
				( attribute "TOLERANCE" "1%"
					( Origin gFrontEnd )
				)
				( attribute "VALUE" "1.00K"
					( Origin gFrontEnd )
				)
				( attribute "VER" "2"
					( Origin gFrontEnd )
				)
				( attribute "WATTAGE" "1/16W"
					( Origin gFrontEnd )
				)
				( attribute "XY" "(2400,3100)"
					( Origin gFrontEnd )
				)
				( attribute "CHIPS_PART_NAME" "RES"
					( Origin gPackager )
				)
				( attribute "CDS_PART_NAME" "RES_0402-1.00K,1%,1/16W,CHIP,GA"
					( Origin gPackager )
				)
				( objectStatus "R1G16" )
				( pin "a"
					( attribute "PN" "1"
						( Origin gPackager )
					)
					( objectStatus "R1G16.1" )
				)
				( pin "b"
					( attribute "PN" "2"
						( Origin gPackager )
					)
					( objectStatus "R1G16.2" )
				)
			)
			( gate "@baseboard_fab2_lib.baseboard_fab2(sch_1):page223_i21"
				( attribute "CDS_LIB" "mstr_discrete"
					( Origin gPackager )
				)
				( attribute "CDS_LOCATION" "R1G19"
					( Origin gPackager )
				)
				( attribute "CDS_SEC" "1"
					( Origin gPackager )
				)
				( attribute "LOCATION" "R1G19"
					( Origin gFrontEnd )
				)
				( attribute "MATERIAL" "CHIP"
					( Origin gFrontEnd )
				)
				( attribute "PACK_TYPE" "0402"
					( Origin gFrontEnd )
				)
				( attribute "PART_NUMBER" "G21497-005"
					( Origin gFrontEnd )
				)
				( attribute "PHYS_PAGE" "223"
					( Origin gFrontEnd )
				)
				( attribute "ROOM" "VDDQ_GHJ_PWR_VR"
					( Origin gFrontEnd )
				)
				( attribute "ROT" "0"
					( Origin gFrontEnd )
				)
				( attribute "SEC" "1"
					( Origin gPackager )
				)
				( attribute "TOLERANCE" "5%"
					( Origin gFrontEnd )
				)
				( attribute "VALUE" "0.0"
					( Origin gFrontEnd )
				)
				( attribute "VER" "1"
					( Origin gFrontEnd )
				)
				( attribute "WATTAGE" "1/16W"
					( Origin gFrontEnd )
				)
				( attribute "XY" "(3175,2050)"
					( Origin gFrontEnd )
				)
				( attribute "CHIPS_PART_NAME" "RES"
					( Origin gPackager )
				)
				( attribute "CDS_PART_NAME" "RES_0402-0.0,5%,1/16W,CHIP,G21A"
					( Origin gPackager )
				)
				( objectStatus "R1G19" )
				( pin "a"
					( attribute "PN" "1"
						( Origin gPackager )
					)
					( objectStatus "R1G19.1" )
				)
				( pin "b"
					( attribute "PN" "2"
						( Origin gPackager )
					)
					( objectStatus "R1G19.2" )
				)
			)
			( gate "@baseboard_fab2_lib.baseboard_fab2(sch_1):page223_i22"
				( attribute "CDS_LIB" "mstr_discrete"
					( Origin gPackager )
				)
				( attribute "CDS_LOCATION" "R1G21"
					( Origin gPackager )
				)
				( attribute "CDS_SEC" "1"
					( Origin gPackager )
				)
				( attribute "LOCATION" "R1G21"
					( Origin gFrontEnd )
				)
				( attribute "MATERIAL" "CHIP"
					( Origin gFrontEnd )
				)
				( attribute "PACK_TYPE" "0402"
					( Origin gFrontEnd )
				)
				( attribute "PART_NUMBER" "G21497-005"
					( Origin gFrontEnd )
				)
				( attribute "PHYS_PAGE" "223"
					( Origin gFrontEnd )
				)
				( attribute "ROOM" "VDDQ_GHJ_PWR_VR"
					( Origin gFrontEnd )
				)
				( attribute "ROT" "0"
					( Origin gFrontEnd )
				)
				( attribute "SEC" "1"
					( Origin gPackager )
				)
				( attribute "TOLERANCE" "5%"
					( Origin gFrontEnd )
				)
				( attribute "VALUE" "0.0"
					( Origin gFrontEnd )
				)
				( attribute "VER" "1"
					( Origin gFrontEnd )
				)
				( attribute "WATTAGE" "1/16W"
					( Origin gFrontEnd )
				)
				( attribute "XY" "(2850,2000)"
					( Origin gFrontEnd )
				)
				( attribute "CHIPS_PART_NAME" "RES"
					( Origin gPackager )
				)
				( attribute "CDS_PART_NAME" "RES_0402-0.0,5%,1/16W,CHIP,G21A"
					( Origin gPackager )
				)
				( objectStatus "R1G21" )
				( pin "a"
					( attribute "PN" "1"
						( Origin gPackager )
					)
					( objectStatus "R1G21.1" )
				)
				( pin "b"
					( attribute "PN" "2"
						( Origin gPackager )
					)
					( objectStatus "R1G21.2" )
				)
			)
			( gate "@baseboard_fab2_lib.baseboard_fab2(sch_1):page223_i23"
				( attribute "CDS_LIB" "mstr_discrete"
					( Origin gPackager )
				)
				( attribute "CDS_LOCATION" "R1G10"
					( Origin gPackager )
				)
				( attribute "CDS_SEC" "1"
					( Origin gPackager )
				)
				( attribute "LOCATION" "R1G10"
					( Origin gFrontEnd )
				)
				( attribute "MATERIAL" "CHIP"
					( Origin gFrontEnd )
				)
				( attribute "PACK_TYPE" "0402"
					( Origin gFrontEnd )
				)
				( attribute "PART_NUMBER" "G21497-005"
					( Origin gFrontEnd )
				)
				( attribute "PHYS_PAGE" "223"
					( Origin gFrontEnd )
				)
				( attribute "ROOM" "VDDQ_GHJ_PWR_VR"
					( Origin gFrontEnd )
				)
				( attribute "ROT" "0"
					( Origin gFrontEnd )
				)
				( attribute "SEC" "1"
					( Origin gFrontEnd )
				)
				( attribute "SEC_TYPE" "0402"
					( Origin gFrontEnd )
				)
				( attribute "TOLERANCE" "5%"
					( Origin gFrontEnd )
				)
				( attribute "VALUE" "0.0"
					( Origin gFrontEnd )
				)
				( attribute "VER" "1"
					( Origin gFrontEnd )
				)
				( attribute "WATTAGE" "1/16W"
					( Origin gFrontEnd )
				)
				( attribute "XY" "(2850,1700)"
					( Origin gFrontEnd )
				)
				( attribute "CHIPS_PART_NAME" "RES"
					( Origin gPackager )
				)
				( attribute "CDS_PART_NAME" "RES_0402-0.0,5%,1/16W,CHIP,G21A"
					( Origin gPackager )
				)
				( objectStatus "R1G10" )
				( pin "a"
					( attribute "PN" "1"
						( Origin gPackager )
					)
					( objectStatus "R1G10.1" )
				)
				( pin "b"
					( attribute "PN" "2"
						( Origin gPackager )
					)
					( objectStatus "R1G10.2" )
				)
			)
			( gate "@baseboard_fab2_lib.baseboard_fab2(sch_1):page223_i25"
				( attribute "CDS_LIB" "dev_discrete"
					( Origin gPackager )
				)
				( attribute "CDS_LOCATION" "C1G27"
					( Origin gPackager )
				)
				( attribute "CDS_SEC" "1"
					( Origin gPackager )
				)
				( attribute "LOCATION" "C1G27"
					( Origin gFrontEnd )
				)
				( attribute "MATERIAL" "X6S"
					( Origin gFrontEnd )
				)
				( attribute "PACK_TYPE" "0402V"
					( Origin gFrontEnd )
				)
				( attribute "PART_NUMBER" "D97712-004"
					( Origin gFrontEnd )
				)
				( attribute "PHYS_PAGE" "223"
					( Origin gFrontEnd )
				)
				( attribute "ROOM" "VDDQ_GHJ_PWR_VR"
					( Origin gFrontEnd )
				)
				( attribute "ROT" "0"
					( Origin gFrontEnd )
				)
				( attribute "SEC" "1"
					( Origin gPackager )
				)
				( attribute "TOLERANCE" "10%"
					( Origin gFrontEnd )
				)
				( attribute "VALUE" "1.0UF"
					( Origin gFrontEnd )
				)
				( attribute "VER" "1"
					( Origin gFrontEnd )
				)
				( attribute "VOLTAGE" "6.3V"
					( Units "uVoltage" "V" 1.000000)
					( Origin gFrontEnd )
				)
				( attribute "XY" "(1600,3100)"
					( Origin gFrontEnd )
				)
				( attribute "CHIPS_PART_NAME" "CAP_A"
					( Origin gPackager )
				)
				( attribute "CDS_PART_NAME" "CAP_A_0402V-1.0UF,6.3V,10%,X6SA"
					( Origin gPackager )
				)
				( objectStatus "C1G27" )
				( pin "a"
					( attribute "PN" "1"
						( Origin gPackager )
					)
					( objectStatus "C1G27.1" )
				)
				( pin "b"
					( attribute "PN" "2"
						( Origin gPackager )
					)
					( objectStatus "C1G27.2" )
				)
			)
			( gate "@baseboard_fab2_lib.baseboard_fab2(sch_1):page223_i27"
				( attribute "CDS_LIB" "dev_discrete"
					( Origin gPackager )
				)
				( attribute "CDS_LOCATION" "C1G25"
					( Origin gPackager )
				)
				( attribute "CDS_SEC" "1"
					( Origin gPackager )
				)
				( attribute "LOCATION" "C1G25"
					( Origin gFrontEnd )
				)
				( attribute "MATERIAL" "X7R"
					( Origin gFrontEnd )
				)
				( attribute "PACK_TYPE" "0402V"
					( Origin gFrontEnd )
				)
				( attribute "PART_NUMBER" "A36096-030"
					( Origin gFrontEnd )
				)
				( attribute "PHYS_PAGE" "223"
					( Origin gFrontEnd )
				)
				( attribute "ROOM" "VDDQ_GHJ_PWR_VR"
					( Origin gFrontEnd )
				)
				( attribute "ROT" "0"
					( Origin gFrontEnd )
				)
				( attribute "SEC" "1"
					( Origin gFrontEnd )
				)
				( attribute "SEC_TYPE" "0402V"
					( Origin gFrontEnd )
				)
				( attribute "TOLERANCE" "10%"
					( Origin gFrontEnd )
				)
				( attribute "VALUE" "0.1UF"
					( Origin gFrontEnd )
				)
				( attribute "VER" "1"
					( Origin gFrontEnd )
				)
				( attribute "VOLTAGE" "16V"
					( Units "uVoltage" "V" 1.000000)
					( Origin gFrontEnd )
				)
				( attribute "XY" "(1200,3100)"
					( Origin gFrontEnd )
				)
				( attribute "CHIPS_PART_NAME" "CAP_A"
					( Origin gPackager )
				)
				( attribute "CDS_PART_NAME" "CAP_A_0402V-0.1UF,16V,10%,X7R,A"
					( Origin gPackager )
				)
				( objectStatus "C1G25" )
				( pin "a"
					( attribute "PN" "1"
						( Origin gPackager )
					)
					( objectStatus "C1G25.1" )
				)
				( pin "b"
					( attribute "PN" "2"
						( Origin gPackager )
					)
					( objectStatus "C1G25.2" )
				)
			)
			( gate "@baseboard_fab2_lib.baseboard_fab2(sch_1):page223_i30"
				( attribute "CDS_LIB" "mstr_discrete"
					( Origin gPackager )
				)
				( attribute "CDS_LOCATION" "R9U10"
					( Origin gPackager )
				)
				( attribute "CDS_SEC" "1"
					( Origin gPackager )
				)
				( attribute "LOCATION" "R9U10"
					( Origin gFrontEnd )
				)
				( attribute "MATERIAL" "CHIP"
					( Origin gFrontEnd )
				)
				( attribute "PACK_TYPE" "0402"
					( Origin gFrontEnd )
				)
				( attribute "PART_NUMBER" "G21497-005"
					( Origin gFrontEnd )
				)
				( attribute "PHYS_PAGE" "223"
					( Origin gFrontEnd )
				)
				( attribute "ROOM" "VDDQ_GHJ_PWR_VR"
					( Origin gFrontEnd )
				)
				( attribute "ROT" "0"
					( Origin gFrontEnd )
				)
				( attribute "SEC" "1"
					( Origin gFrontEnd )
				)
				( attribute "SEC_TYPE" "0402"
					( Origin gFrontEnd )
				)
				( attribute "TOLERANCE" "5%"
					( Origin gFrontEnd )
				)
				( attribute "VALUE" "0.0"
					( Origin gFrontEnd )
				)
				( attribute "VER" "2"
					( Origin gFrontEnd )
				)
				( attribute "WATTAGE" "1/16W"
					( Origin gFrontEnd )
				)
				( attribute "XY" "(900,3450)"
					( Origin gFrontEnd )
				)
				( attribute "CHIPS_PART_NAME" "RES"
					( Origin gPackager )
				)
				( attribute "CDS_PART_NAME" "RES_0402-0.0,5%,1/16W,CHIP,G21A"
					( Origin gPackager )
				)
				( objectStatus "R9U10" )
				( pin "a"
					( attribute "PN" "1"
						( Origin gPackager )
					)
					( objectStatus "R9U10.1" )
				)
				( pin "b"
					( attribute "PN" "2"
						( Origin gPackager )
					)
					( objectStatus "R9U10.2" )
				)
			)
			( gate "@baseboard_fab2_lib.baseboard_fab2(sch_1):page223_i32"
				( attribute "CDS_LIB" "mstr_discrete"
					( Origin gPackager )
				)
				( attribute "CDS_LOCATION" "R1G5"
					( Origin gPackager )
				)
				( attribute "CDS_SEC" "1"
					( Origin gPackager )
				)
				( attribute "LOCATION" "R1G5"
					( Origin gFrontEnd )
				)
				( attribute "MATERIAL" "CHIP"
					( Origin gFrontEnd )
				)
				( attribute "NO_XNET_CONNECTION" "1"
					( Origin gFrontEnd )
				)
				( attribute "PACK_TYPE" "0402"
					( Origin gFrontEnd )
				)
				( attribute "PART_NUMBER" "G21796-066"
					( Origin gFrontEnd )
				)
				( attribute "PHYS_PAGE" "223"
					( Origin gFrontEnd )
				)
				( attribute "ROOM" "VDDQ_GHJ_PWR_VR"
					( Origin gFrontEnd )
				)
				( attribute "ROT" "0"
					( Origin gFrontEnd )
				)
				( attribute "SEC" "1"
					( Origin gFrontEnd )
				)
				( attribute "SEC_TYPE" "0402"
					( Origin gFrontEnd )
				)
				( attribute "TOLERANCE" "1%"
					( Origin gFrontEnd )
				)
				( attribute "VALUE" "10.0"
					( Origin gFrontEnd )
				)
				( attribute "VER" "1"
					( Origin gFrontEnd )
				)
				( attribute "WATTAGE" "1/16W"
					( Origin gFrontEnd )
				)
				( attribute "XY" "(-1725,1075)"
					( Origin gFrontEnd )
				)
				( attribute "CHIPS_PART_NAME" "RES"
					( Origin gPackager )
				)
				( attribute "CDS_PART_NAME" "RES_0402-10.0,1%,1/16W,CHIP,G2A"
					( Origin gPackager )
				)
				( objectStatus "R1G5" )
				( pin "a"
					( attribute "PN" "1"
						( Origin gPackager )
					)
					( objectStatus "R1G5.1" )
				)
				( pin "b"
					( attribute "PN" "2"
						( Origin gPackager )
					)
					( objectStatus "R1G5.2" )
				)
			)
			( gate "@baseboard_fab2_lib.baseboard_fab2(sch_1):page223_i36"
				( attribute "CDS_LIB" "mstr_discrete"
					( Origin gPackager )
				)
				( attribute "CDS_LOCATION" "C1G24"
					( Origin gPackager )
				)
				( attribute "CDS_SEC" "1"
					( Origin gPackager )
				)
				( attribute "LOCATION" "C1G24"
					( Origin gFrontEnd )
				)
				( attribute "MATERIAL" "X7R"
					( Origin gFrontEnd )
				)
				( attribute "PACK_TYPE" "0402LF"
					( Origin gFrontEnd )
				)
				( attribute "PART_NUMBER" "A36096-050"
					( Origin gFrontEnd )
				)
				( attribute "PHYS_PAGE" "223"
					( Origin gFrontEnd )
				)
				( attribute "ROOM" "VDDQ_GHJ_PWR_VR"
					( Origin gFrontEnd )
				)
				( attribute "ROT" "2"
					( Origin gFrontEnd )
				)
				( attribute "SEC" "1"
					( Origin gFrontEnd )
				)
				( attribute "SEC_TYPE" "0402LF"
					( Origin gFrontEnd )
				)
				( attribute "TOLERANCE" "10%"
					( Origin gFrontEnd )
				)
				( attribute "VALUE" "220PF"
					( Origin gFrontEnd )
				)
				( attribute "VER" "1"
					( Origin gFrontEnd )
				)
				( attribute "VOLTAGE" "50V"
					( Units "uVoltage" "V" 1.000000)
					( Origin gFrontEnd )
				)
				( attribute "XY" "(100,750)"
					( Origin gFrontEnd )
				)
				( attribute "CHIPS_PART_NAME" "CAP"
					( Origin gPackager )
				)
				( attribute "CDS_PART_NAME" "CAP_0402LF-220PF,50V,10%,X7R,AA"
					( Origin gPackager )
				)
				( objectStatus "C1G24" )
				( pin "a"
					( attribute "PN" "1"
						( Origin gPackager )
					)
					( objectStatus "C1G24.1" )
				)
				( pin "b"
					( attribute "PN" "2"
						( Origin gPackager )
					)
					( objectStatus "C1G24.2" )
				)
			)
			( gate "@baseboard_fab2_lib.baseboard_fab2(sch_1):page223_i39"
				( attribute "CDS_LIB" "mstr_discrete"
					( Origin gPackager )
				)
				( attribute "CDS_LOCATION" "C1G16"
					( Origin gPackager )
				)
				( attribute "CDS_SEC" "1"
					( Origin gPackager )
				)
				( attribute "LOCATION" "C1G16"
					( Origin gFrontEnd )
				)
				( attribute "MATERIAL" "X7R"
					( Origin gFrontEnd )
				)
				( attribute "NO_XNET_CONNECTION" "1"
					( Origin gFrontEnd )
				)
				( attribute "PACK_TYPE" "0402LF"
					( Origin gFrontEnd )
				)
				( attribute "PART_NUMBER" "A36096-050"
					( Origin gFrontEnd )
				)
				( attribute "PHYS_PAGE" "223"
					( Origin gFrontEnd )
				)
				( attribute "ROOM" "VDDQ_GHJ_PWR_VR"
					( Origin gFrontEnd )
				)
				( attribute "ROT" "0"
					( Origin gFrontEnd )
				)
				( attribute "SEC" "1"
					( Origin gFrontEnd )
				)
				( attribute "SEC_TYPE" "0402LF"
					( Origin gFrontEnd )
				)
				( attribute "TOLERANCE" "10%"
					( Origin gFrontEnd )
				)
				( attribute "VALUE" "220PF"
					( Origin gFrontEnd )
				)
				( attribute "VER" "1"
					( Origin gFrontEnd )
				)
				( attribute "VOLTAGE" "50V"
					( Units "uVoltage" "V" 1.000000)
					( Origin gFrontEnd )
				)
				( attribute "XY" "(-1450,925)"
					( Origin gFrontEnd )
				)
				( attribute "CHIPS_PART_NAME" "CAP"
					( Origin gPackager )
				)
				( attribute "CDS_PART_NAME" "CAP_0402LF-220PF,50V,10%,X7R,AA"
					( Origin gPackager )
				)
				( objectStatus "C1G16" )
				( pin "a"
					( attribute "PN" "1"
						( Origin gPackager )
					)
					( objectStatus "C1G16.1" )
				)
				( pin "b"
					( attribute "PN" "2"
						( Origin gPackager )
					)
					( objectStatus "C1G16.2" )
				)
			)
			( gate "@baseboard_fab2_lib.baseboard_fab2(sch_1):page223_i41"
				( attribute "CDS_LIB" "dev_discrete"
					( Origin gPackager )
				)
				( attribute "CDS_LOCATION" "C1G23"
					( Origin gPackager )
				)
				( attribute "CDS_SEC" "1"
					( Origin gPackager )
				)
				( attribute "LOCATION" "C1G23"
					( Origin gFrontEnd )
				)
				( attribute "MATERIAL" "X6S"
					( Origin gFrontEnd )
				)
				( attribute "PACK_TYPE" "0402V"
					( Origin gFrontEnd )
				)
				( attribute "PART_NUMBER" "D97712-004"
					( Origin gFrontEnd )
				)
				( attribute "PHYS_PAGE" "223"
					( Origin gFrontEnd )
				)
				( attribute "ROOM" "VDDQ_GHJ_PWR_VR"
					( Origin gFrontEnd )
				)
				( attribute "ROT" "0"
					( Origin gFrontEnd )
				)
				( attribute "SEC" "1"
					( Origin gPackager )
				)
				( attribute "TOLERANCE" "10%"
					( Origin gFrontEnd )
				)
				( attribute "VALUE" "1.0UF"
					( Origin gFrontEnd )
				)
				( attribute "VER" "1"
					( Origin gFrontEnd )
				)
				( attribute "VOLTAGE" "6.3V"
					( Units "uVoltage" "V" 1.000000)
					( Origin gFrontEnd )
				)
				( attribute "XY" "(3775,125)"
					( Origin gFrontEnd )
				)
				( attribute "CHIPS_PART_NAME" "CAP_A"
					( Origin gPackager )
				)
				( attribute "CDS_PART_NAME" "CAP_A_0402V-1.0UF,6.3V,10%,X6SA"
					( Origin gPackager )
				)
				( objectStatus "C1G23" )
				( pin "a"
					( attribute "PN" "1"
						( Origin gPackager )
					)
					( objectStatus "C1G23.1" )
				)
				( pin "b"
					( attribute "PN" "2"
						( Origin gPackager )
					)
					( objectStatus "C1G23.2" )
				)
			)
			( gate "@baseboard_fab2_lib.baseboard_fab2(sch_1):page223_i44"
				( attribute "CDS_LIB" "dev_discrete"
					( Origin gPackager )
				)
				( attribute "CDS_LOCATION" "C1G22"
					( Origin gPackager )
				)
				( attribute "CDS_SEC" "1"
					( Origin gPackager )
				)
				( attribute "LOCATION" "C1G22"
					( Origin gFrontEnd )
				)
				( attribute "MATERIAL" "X7R"
					( Origin gFrontEnd )
				)
				( attribute "PACK_TYPE" "0402V"
					( Origin gFrontEnd )
				)
				( attribute "PART_NUMBER" "A36096-030"
					( Origin gFrontEnd )
				)
				( attribute "PHYS_PAGE" "223"
					( Origin gFrontEnd )
				)
				( attribute "ROOM" "VDDQ_GHJ_PWR_VR"
					( Origin gFrontEnd )
				)
				( attribute "ROT" "0"
					( Origin gFrontEnd )
				)
				( attribute "SEC" "1"
					( Origin gFrontEnd )
				)
				( attribute "SEC_TYPE" "0402V"
					( Origin gFrontEnd )
				)
				( attribute "TOLERANCE" "10%"
					( Origin gFrontEnd )
				)
				( attribute "VALUE" "0.1UF"
					( Origin gFrontEnd )
				)
				( attribute "VER" "1"
					( Origin gFrontEnd )
				)
				( attribute "VOLTAGE" "16V"
					( Units "uVoltage" "V" 1.000000)
					( Origin gFrontEnd )
				)
				( attribute "XY" "(3375,125)"
					( Origin gFrontEnd )
				)
				( attribute "CHIPS_PART_NAME" "CAP_A"
					( Origin gPackager )
				)
				( attribute "CDS_PART_NAME" "CAP_A_0402V-0.1UF,16V,10%,X7R,A"
					( Origin gPackager )
				)
				( objectStatus "C1G22" )
				( pin "a"
					( attribute "PN" "1"
						( Origin gPackager )
					)
					( objectStatus "C1G22.1" )
				)
				( pin "b"
					( attribute "PN" "2"
						( Origin gPackager )
					)
					( objectStatus "C1G22.2" )
				)
			)
			( gate "@baseboard_fab2_lib.baseboard_fab2(sch_1):page223_i50"
				( attribute "CDS_LIB" "mstr_discrete"
					( Origin gPackager )
				)
				( attribute "CDS_LOCATION" "R9U4"
					( Origin gPackager )
				)
				( attribute "CDS_SEC" "1"
					( Origin gPackager )
				)
				( attribute "LOCATION" "R9U4"
					( Origin gFrontEnd )
				)
				( attribute "MATERIAL" "EMPTY"
					( Origin gFrontEnd )
				)
				( attribute "PACK_TYPE" "0402"
					( Origin gFrontEnd )
				)
				( attribute "PART_NUMBER" "G21796-047"
					( Origin gFrontEnd )
				)
				( attribute "PHYS_PAGE" "223"
					( Origin gFrontEnd )
				)
				( attribute "ROOM" "VDDQ_GHJ_PWR_VR"
					( Origin gFrontEnd )
				)
				( attribute "ROT" "0"
					( Origin gFrontEnd )
				)
				( attribute "SEC" "1"
					( Origin gFrontEnd )
				)
				( attribute "SEC_TYPE" "0402"
					( Origin gFrontEnd )
				)
				( attribute "TOLERANCE" "1%"
					( Origin gFrontEnd )
				)
				( attribute "VALUE" "49.9"
					( Origin gFrontEnd )
				)
				( attribute "VER" "2"
					( Origin gFrontEnd )
				)
				( attribute "WATTAGE" "1/16W"
					( Origin gFrontEnd )
				)
				( attribute "XY" "(-625,3350)"
					( Origin gFrontEnd )
				)
				( attribute "CHIPS_PART_NAME" "RES"
					( Origin gPackager )
				)
				( attribute "CDS_PART_NAME" "RES_0402-49.9,1%,1/16W,EMPTY,GA"
					( Origin gPackager )
				)
				( objectStatus "R9U4" )
				( pin "a"
					( attribute "PN" "1"
						( Origin gPackager )
					)
					( objectStatus "R9U4.1" )
				)
				( pin "b"
					( attribute "PN" "2"
						( Origin gPackager )
					)
					( objectStatus "R9U4.2" )
				)
			)
			( gate "@baseboard_fab2_lib.baseboard_fab2(sch_1):page223_i53"
				( attribute "CDS_LIB" "mstr_discrete"
					( Origin gPackager )
				)
				( attribute "CDS_LOCATION" "R1G7"
					( Origin gPackager )
				)
				( attribute "CDS_SEC" "1"
					( Origin gPackager )
				)
				( attribute "LOCATION" "R1G7"
					( Origin gFrontEnd )
				)
				( attribute "MATERIAL" "CHIP"
					( Origin gFrontEnd )
				)
				( attribute "PACK_TYPE" "0402"
					( Origin gFrontEnd )
				)
				( attribute "PART_NUMBER" "G21796-009"
					( Origin gFrontEnd )
				)
				( attribute "PHYS_PAGE" "223"
					( Origin gFrontEnd )
				)
				( attribute "ROOM" "VDDQ_GHJ_PWR_VR"
					( Origin gFrontEnd )
				)
				( attribute "ROT" "0"
					( Origin gFrontEnd )
				)
				( attribute "SEC" "1"
					( Origin gFrontEnd )
				)
				( attribute "SEC_TYPE" "0402"
					( Origin gFrontEnd )
				)
				( attribute "TOLERANCE" "1%"
					( Origin gFrontEnd )
				)
				( attribute "VALUE" "150.0"
					( Origin gFrontEnd )
				)
				( attribute "VER" "1"
					( Origin gFrontEnd )
				)
				( attribute "WATTAGE" "1/16W"
					( Origin gFrontEnd )
				)
				( attribute "XY" "(-225,2975)"
					( Origin gFrontEnd )
				)
				( attribute "CHIPS_PART_NAME" "RES"
					( Origin gPackager )
				)
				( attribute "CDS_PART_NAME" "RES_0402-150.0,1%,1/16W,CHIP,GA"
					( Origin gPackager )
				)
				( objectStatus "R1G7" )
				( pin "a"
					( attribute "PN" "1"
						( Origin gPackager )
					)
					( objectStatus "R1G7.1" )
				)
				( pin "b"
					( attribute "PN" "2"
						( Origin gPackager )
					)
					( objectStatus "R1G7.2" )
				)
			)
			( gate "@baseboard_fab2_lib.baseboard_fab2(sch_1):page223_i57"
				( attribute "CDS_LIB" "mstr_discrete"
					( Origin gPackager )
				)
				( attribute "CDS_LOCATION" "R9U11"
					( Origin gPackager )
				)
				( attribute "CDS_SEC" "1"
					( Origin gPackager )
				)
				( attribute "LOCATION" "R9U11"
					( Origin gFrontEnd )
				)
				( attribute "MATERIAL" "CHIP"
					( Origin gFrontEnd )
				)
				( attribute "PACK_TYPE" "0402"
					( Origin gFrontEnd )
				)
				( attribute "PART_NUMBER" "G21796-160"
					( Origin gFrontEnd )
				)
				( attribute "PHYS_PAGE" "223"
					( Origin gFrontEnd )
				)
				( attribute "ROOM" "VDDQ_GHJ_PWR_VR"
					( Origin gFrontEnd )
				)
				( attribute "ROT" "0"
					( Origin gFrontEnd )
				)
				( attribute "SEC" "1"
					( Origin gFrontEnd )
				)
				( attribute "SEC_TYPE" "0402"
					( Origin gFrontEnd )
				)
				( attribute "TOLERANCE" "1%"
					( Origin gFrontEnd )
				)
				( attribute "VALUE" "100.0K"
					( Origin gFrontEnd )
				)
				( attribute "VER" "2"
					( Origin gFrontEnd )
				)
				( attribute "WATTAGE" "1/16W"
					( Origin gFrontEnd )
				)
				( attribute "XY" "(-1175,3700)"
					( Origin gFrontEnd )
				)
				( attribute "CHIPS_PART_NAME" "RES"
					( Origin gPackager )
				)
				( attribute "CDS_PART_NAME" "RES_0402-100.0K,1%,1/16W,CHIP,B"
					( Origin gPackager )
				)
				( objectStatus "R9U11" )
				( pin "a"
					( attribute "PN" "1"
						( Origin gPackager )
					)
					( objectStatus "R9U11.1" )
				)
				( pin "b"
					( attribute "PN" "2"
						( Origin gPackager )
					)
					( objectStatus "R9U11.2" )
				)
			)
			( gate "@baseboard_fab2_lib.baseboard_fab2(sch_1):page223_i58"
				( attribute "CDS_LIB" "mstr_discrete"
					( Origin gPackager )
				)
				( attribute "CDS_LOCATION" "R1G24"
					( Origin gPackager )
				)
				( attribute "CDS_SEC" "1"
					( Origin gPackager )
				)
				( attribute "LOCATION" "R1G24"
					( Origin gFrontEnd )
				)
				( attribute "MATERIAL" "CHIP"
					( Origin gFrontEnd )
				)
				( attribute "PACK_TYPE" "0402"
					( Origin gFrontEnd )
				)
				( attribute "PART_NUMBER" "G21796-003"
					( Origin gFrontEnd )
				)
				( attribute "PHYS_PAGE" "223"
					( Origin gFrontEnd )
				)
				( attribute "ROOM" "VDDQ_GHJ_PWR_VR"
					( Origin gFrontEnd )
				)
				( attribute "ROT" "0"
					( Origin gFrontEnd )
				)
				( attribute "SEC" "1"
					( Origin gFrontEnd )
				)
				( attribute "SEC_TYPE" "0402"
					( Origin gFrontEnd )
				)
				( attribute "TOLERANCE" "1%"
					( Origin gFrontEnd )
				)
				( attribute "VALUE" "1.5K"
					( Origin gFrontEnd )
				)
				( attribute "VER" "2"
					( Origin gFrontEnd )
				)
				( attribute "WATTAGE" "1/16W"
					( Origin gFrontEnd )
				)
				( attribute "XY" "(-1175,3350)"
					( Origin gFrontEnd )
				)
				( attribute "CHIPS_PART_NAME" "RES"
					( Origin gPackager )
				)
				( attribute "CDS_PART_NAME" "RES_0402-1.5K,1%,1/16W,CHIP,G2A"
					( Origin gPackager )
				)
				( objectStatus "R1G24" )
				( pin "a"
					( attribute "PN" "1"
						( Origin gPackager )
					)
					( objectStatus "R1G24.1" )
				)
				( pin "b"
					( attribute "PN" "2"
						( Origin gPackager )
					)
					( objectStatus "R1G24.2" )
				)
			)
			( gate "@baseboard_fab2_lib.baseboard_fab2(sch_1):page223_i59"
				( attribute "CDS_LIB" "mstr_discrete"
					( Origin gPackager )
				)
				( attribute "CDS_LOCATION" "C1G26"
					( Origin gPackager )
				)
				( attribute "CDS_SEC" "1"
					( Origin gPackager )
				)
				( attribute "LOCATION" "C1G26"
					( Origin gFrontEnd )
				)
				( attribute "MATERIAL" "X7R"
					( Origin gFrontEnd )
				)
				( attribute "PACK_TYPE" "0402LF"
					( Origin gFrontEnd )
				)
				( attribute "PART_NUMBER" "A36096-046"
					( Origin gFrontEnd )
				)
				( attribute "PHYS_PAGE" "223"
					( Origin gFrontEnd )
				)
				( attribute "ROOM" "VDDQ_GHJ_PWR_VR"
					( Origin gFrontEnd )
				)
				( attribute "ROT" "2"
					( Origin gFrontEnd )
				)
				( attribute "SEC" "1"
					( Origin gFrontEnd )
				)
				( attribute "SEC_TYPE" "0402LF"
					( Origin gFrontEnd )
				)
				( attribute "TOLERANCE" "10%"
					( Origin gFrontEnd )
				)
				( attribute "VALUE" "1000PF"
					( Origin gFrontEnd )
				)
				( attribute "VER" "1"
					( Origin gFrontEnd )
				)
				( attribute "VOLTAGE" "50V"
					( Units "uVoltage" "V" 1.000000)
					( Origin gFrontEnd )
				)
				( attribute "XY" "(-1400,3350)"
					( Origin gFrontEnd )
				)
				( attribute "CHIPS_PART_NAME" "CAP"
					( Origin gPackager )
				)
				( attribute "CDS_PART_NAME" "CAP_0402LF-1000PF,50V,10%,X7R,A"
					( Origin gPackager )
				)
				( objectStatus "C1G26" )
				( pin "a"
					( attribute "PN" "1"
						( Origin gPackager )
					)
					( objectStatus "C1G26.1" )
				)
				( pin "b"
					( attribute "PN" "2"
						( Origin gPackager )
					)
					( objectStatus "C1G26.2" )
				)
			)
			( gate "@baseboard_fab2_lib.baseboard_fab2(sch_1):page223_i77"
				( attribute "CDS_LIB" "mstr_discrete"
					( Origin gPackager )
				)
				( attribute "CDS_LOCATION" "R1G23"
					( Origin gPackager )
				)
				( attribute "CDS_SEC" "1"
					( Origin gPackager )
				)
				( attribute "LOCATION" "R1G23"
					( Origin gFrontEnd )
				)
				( attribute "MATERIAL" "CHIP"
					( Origin gFrontEnd )
				)
				( attribute "PACK_TYPE" "0402"
					( Origin gFrontEnd )
				)
				( attribute "PART_NUMBER" "G21796-082"
					( Origin gFrontEnd )
				)
				( attribute "PHYS_PAGE" "223"
					( Origin gFrontEnd )
				)
				( attribute "ROOM" "VDDQ_GHJ_PWR_VR"
					( Origin gFrontEnd )
				)
				( attribute "ROT" "0"
					( Origin gFrontEnd )
				)
				( attribute "SEC" "1"
					( Origin gFrontEnd )
				)
				( attribute "SEC_TYPE" "0402"
					( Origin gFrontEnd )
				)
				( attribute "TOLERANCE" "1%"
					( Origin gFrontEnd )
				)
				( attribute "VALUE" "4.02K"
					( Origin gFrontEnd )
				)
				( attribute "VER" "2"
					( Origin gFrontEnd )
				)
				( attribute "WATTAGE" "1/16W"
					( Origin gFrontEnd )
				)
				( attribute "XY" "(275,300)"
					( Origin gFrontEnd )
				)
				( attribute "CHIPS_PART_NAME" "RES"
					( Origin gPackager )
				)
				( attribute "CDS_PART_NAME" "RES_0402-4.02K,1%,1/16W,CHIP,GA"
					( Origin gPackager )
				)
				( objectStatus "R1G23" )
				( pin "a"
					( attribute "PN" "1"
						( Origin gPackager )
					)
					( objectStatus "R1G23.1" )
				)
				( pin "b"
					( attribute "PN" "2"
						( Origin gPackager )
					)
					( objectStatus "R1G23.2" )
				)
			)
			( gate "@baseboard_fab2_lib.baseboard_fab2(sch_1):page223_i78"
				( attribute "CDS_LIB" "mstr_discrete"
					( Origin gPackager )
				)
				( attribute "CDS_LOCATION" "R1G22"
					( Origin gPackager )
				)
				( attribute "CDS_SEC" "1"
					( Origin gPackager )
				)
				( attribute "LOCATION" "R1G22"
					( Origin gFrontEnd )
				)
				( attribute "MATERIAL" "CHIP"
					( Origin gFrontEnd )
				)
				( attribute "PACK_TYPE" "0402"
					( Origin gFrontEnd )
				)
				( attribute "PART_NUMBER" "G21796-297"
					( Origin gFrontEnd )
				)
				( attribute "PHYS_PAGE" "223"
					( Origin gFrontEnd )
				)
				( attribute "ROOM" "VDDQ_GHJ_PWR_VR"
					( Origin gFrontEnd )
				)
				( attribute "ROT" "0"
					( Origin gFrontEnd )
				)
				( attribute "SEC" "1"
					( Origin gFrontEnd )
				)
				( attribute "SEC_TYPE" "0402"
					( Origin gFrontEnd )
				)
				( attribute "TOLERANCE" "1.0%"
					( Origin gFrontEnd )
				)
				( attribute "VALUE" "5.36K"
					( Origin gFrontEnd )
				)
				( attribute "VER" "2"
					( Origin gFrontEnd )
				)
				( attribute "WATTAGE" "1/16W"
					( Origin gFrontEnd )
				)
				( attribute "XY" "(625,300)"
					( Origin gFrontEnd )
				)
				( attribute "CHIPS_PART_NAME" "RES"
					( Origin gPackager )
				)
				( attribute "CDS_PART_NAME" "RES_0402-5.36K,1.0%,1/16W,CHIPA"
					( Origin gPackager )
				)
				( objectStatus "R1G22" )
				( pin "a"
					( attribute "PN" "1"
						( Origin gPackager )
					)
					( objectStatus "R1G22.1" )
				)
				( pin "b"
					( attribute "PN" "2"
						( Origin gPackager )
					)
					( objectStatus "R1G22.2" )
				)
			)
			( gate "@baseboard_fab2_lib.baseboard_fab2(sch_1):page223_i79"
				( attribute "CDS_LIB" "mstr_discrete"
					( Origin gPackager )
				)
				( attribute "CDS_LOCATION" "R1G11"
					( Origin gPackager )
				)
				( attribute "CDS_SEC" "1"
					( Origin gPackager )
				)
				( attribute "LOCATION" "R1G11"
					( Origin gFrontEnd )
				)
				( attribute "MATERIAL" "CHIP"
					( Origin gFrontEnd )
				)
				( attribute "PACK_TYPE" "0402"
					( Origin gFrontEnd )
				)
				( attribute "PART_NUMBER" "G21796-026"
					( Origin gFrontEnd )
				)
				( attribute "PHYS_PAGE" "223"
					( Origin gFrontEnd )
				)
				( attribute "ROOM" "RQ_PVDDQ_GHJ_VRHOT_LVT3_N"
					( Origin gFrontEnd )
				)
				( attribute "ROT" "0"
					( Origin gFrontEnd )
				)
				( attribute "SEC" "1"
					( Origin gFrontEnd )
				)
				( attribute "SEC_TYPE" "0402"
					( Origin gFrontEnd )
				)
				( attribute "TOLERANCE" "1%"
					( Origin gFrontEnd )
				)
				( attribute "VALUE" "1.00K"
					( Origin gFrontEnd )
				)
				( attribute "VER" "2"
					( Origin gFrontEnd )
				)
				( attribute "WATTAGE" "1/16W"
					( Origin gFrontEnd )
				)
				( attribute "XY" "(2200,3125)"
					( Origin gFrontEnd )
				)
				( attribute "CHIPS_PART_NAME" "RES"
					( Origin gPackager )
				)
				( attribute "CDS_PART_NAME" "RES_0402-1.00K,1%,1/16W,CHIP,GA"
					( Origin gPackager )
				)
				( objectStatus "R1G11" )
				( pin "a"
					( attribute "PN" "1"
						( Origin gPackager )
					)
					( objectStatus "R1G11.1" )
				)
				( pin "b"
					( attribute "PN" "2"
						( Origin gPackager )
					)
					( objectStatus "R1G11.2" )
				)
			)
			( gate "@baseboard_fab2_lib.baseboard_fab2(sch_1):page223_i80"
				( attribute "CDS_LIB" "mstr_discrete"
					( Origin gPackager )
				)
				( attribute "CDS_LOCATION" "C1G21"
					( Origin gPackager )
				)
				( attribute "CDS_SEC" "1"
					( Origin gPackager )
				)
				( attribute "LOCATION" "C1G21"
					( Origin gFrontEnd )
				)
				( attribute "MATERIAL" "X7R"
					( Origin gFrontEnd )
				)
				( attribute "PACK_TYPE" "0402LF"
					( Origin gFrontEnd )
				)
				( attribute "PART_NUMBER" "A36096-046"
					( Origin gFrontEnd )
				)
				( attribute "PHYS_PAGE" "223"
					( Origin gFrontEnd )
				)
				( attribute "ROOM" "VDDQ_GHJ_PWR_VR"
					( Origin gFrontEnd )
				)
				( attribute "ROT" "0"
					( Origin gFrontEnd )
				)
				( attribute "SEC" "1"
					( Origin gFrontEnd )
				)
				( attribute "SEC_TYPE" "0402LF"
					( Origin gFrontEnd )
				)
				( attribute "TOLERANCE" "10%"
					( Origin gFrontEnd )
				)
				( attribute "VALUE" "1000PF"
					( Origin gFrontEnd )
				)
				( attribute "VER" "1"
					( Origin gFrontEnd )
				)
				( attribute "VOLTAGE" "50V"
					( Units "uVoltage" "V" 1.000000)
					( Origin gFrontEnd )
				)
				( attribute "XY" "(3050,1000)"
					( Origin gFrontEnd )
				)
				( attribute "CHIPS_PART_NAME" "CAP"
					( Origin gPackager )
				)
				( attribute "CDS_PART_NAME" "CAP_0402LF-1000PF,50V,10%,X7R,A"
					( Origin gPackager )
				)
				( objectStatus "C1G21" )
				( pin "a"
					( attribute "PN" "1"
						( Origin gPackager )
					)
					( objectStatus "C1G21.1" )
				)
				( pin "b"
					( attribute "PN" "2"
						( Origin gPackager )
					)
					( objectStatus "C1G21.2" )
				)
			)
			( gate "@baseboard_fab2_lib.baseboard_fab2(sch_1):page223_i82"
				( attribute "CDS_LIB" "mstr_discrete"
					( Origin gPackager )
				)
				( attribute "CDS_LOCATION" "R1G8"
					( Origin gPackager )
				)
				( attribute "CDS_SEC" "1"
					( Origin gPackager )
				)
				( attribute "LOCATION" "R1G8"
					( Origin gFrontEnd )
				)
				( attribute "MATERIAL" "CHIP"
					( Origin gFrontEnd )
				)
				( attribute "PACK_TYPE" "0402"
					( Origin gFrontEnd )
				)
				( attribute "PART_NUMBER" "G21796-074"
					( Origin gFrontEnd )
				)
				( attribute "PHYS_PAGE" "223"
					( Origin gFrontEnd )
				)
				( attribute "ROT" "0"
					( Origin gFrontEnd )
				)
				( attribute "SEC" "1"
					( Origin gFrontEnd )
				)
				( attribute "SEC_TYPE" "0402"
					( Origin gFrontEnd )
				)
				( attribute "TOLERANCE" "1%"
					( Origin gFrontEnd )
				)
				( attribute "VALUE" "33.2"
					( Origin gFrontEnd )
				)
				( attribute "VER" "1"
					( Origin gFrontEnd )
				)
				( attribute "WATTAGE" "1/16W"
					( Origin gFrontEnd )
				)
				( attribute "XY" "(3475,2450)"
					( Origin gFrontEnd )
				)
				( attribute "CHIPS_PART_NAME" "RES"
					( Origin gPackager )
				)
				( attribute "CDS_PART_NAME" "RES_0402-33.2,1%,1/16W,CHIP,G2A"
					( Origin gPackager )
				)
				( objectStatus "R1G8" )
				( pin "a"
					( attribute "PN" "1"
						( Origin gPackager )
					)
					( objectStatus "R1G8.1" )
				)
				( pin "b"
					( attribute "PN" "2"
						( Origin gPackager )
					)
					( objectStatus "R1G8.2" )
				)
			)
			( gate "@baseboard_fab2_lib.baseboard_fab2(sch_1):page223_i84"
				( attribute "CDS_LIB" "mstr_discrete"
					( Origin gPackager )
				)
				( attribute "CDS_LOCATION" "R9U7"
					( Origin gPackager )
				)
				( attribute "CDS_SEC" "1"
					( Origin gPackager )
				)
				( attribute "LOCATION" "R9U7"
					( Origin gFrontEnd )
				)
				( attribute "MATERIAL" "CHIP"
					( Origin gFrontEnd )
				)
				( attribute "PACK_TYPE" "0402"
					( Origin gFrontEnd )
				)
				( attribute "PART_NUMBER" "G21497-005"
					( Origin gFrontEnd )
				)
				( attribute "PHYS_PAGE" "223"
					( Origin gFrontEnd )
				)
				( attribute "ROOM" "PVCCIN_CPU0_VR"
					( Origin gFrontEnd )
				)
				( attribute "ROT" "0"
					( Origin gFrontEnd )
				)
				( attribute "SEC" "1"
					( Origin gPackager )
				)
				( attribute "TOLERANCE" "5%"
					( Origin gFrontEnd )
				)
				( attribute "VALUE" "0.0"
					( Origin gFrontEnd )
				)
				( attribute "VER" "1"
					( Origin gFrontEnd )
				)
				( attribute "WATTAGE" "1/16W"
					( Origin gFrontEnd )
				)
				( attribute "XY" "(-1500,1500)"
					( Origin gFrontEnd )
				)
				( attribute "CHIPS_PART_NAME" "RES"
					( Origin gPackager )
				)
				( attribute "CDS_PART_NAME" "RES_0402-0.0,5%,1/16W,CHIP,G21A"
					( Origin gPackager )
				)
				( objectStatus "R9U7" )
				( pin "a"
					( attribute "PN" "1"
						( Origin gPackager )
					)
					( objectStatus "R9U7.1" )
				)
				( pin "b"
					( attribute "PN" "2"
						( Origin gPackager )
					)
					( objectStatus "R9U7.2" )
				)
			)
			( gate "@baseboard_fab2_lib.baseboard_fab2(sch_1):page223_i85"
				( attribute "BOM_COST" "SM_CONTROLLER"
					( Origin gFrontEnd )
				)
				( attribute "CDS_LIB" "mstr_discrete"
					( Origin gPackager )
				)
				( attribute "CDS_LOCATION" "R9U8"
					( Origin gPackager )
				)
				( attribute "CDS_SEC" "1"
					( Origin gPackager )
				)
				( attribute "LOCATION" "R9U8"
					( Origin gFrontEnd )
				)
				( attribute "MATERIAL" "EMPTY"
					( Origin gFrontEnd )
				)
				( attribute "PACK_TYPE" "0402"
					( Origin gFrontEnd )
				)
				( attribute "PART_NUMBER" "G21796-010"
					( Origin gFrontEnd )
				)
				( attribute "PHYS_PAGE" "223"
					( Origin gFrontEnd )
				)
				( attribute "ROOM" "BMC"
					( Origin gFrontEnd )
				)
				( attribute "ROT" "0"
					( Origin gFrontEnd )
				)
				( attribute "SEC" "1"
					( Origin gPackager )
				)
				( attribute "TOLERANCE" "1%"
					( Origin gFrontEnd )
				)
				( attribute "VALUE" "100.0K"
					( Origin gFrontEnd )
				)
				( attribute "VER" "2"
					( Origin gFrontEnd )
				)
				( attribute "WATTAGE" "1/16W"
					( Origin gFrontEnd )
				)
				( attribute "XY" "(175,3425)"
					( Origin gFrontEnd )
				)
				( attribute "CHIPS_PART_NAME" "RES"
					( Origin gPackager )
				)
				( attribute "CDS_PART_NAME" "RES_0402-100.0K,1%,1/16W,EMPTYA"
					( Origin gPackager )
				)
				( objectStatus "R9U8" )
				( pin "a"
					( attribute "PN" "1"
						( Origin gPackager )
					)
					( objectStatus "R9U8.1" )
				)
				( pin "b"
					( attribute "PN" "2"
						( Origin gPackager )
					)
					( objectStatus "R9U8.2" )
				)
			)
			( gate "@baseboard_fab2_lib.baseboard_fab2(sch_1):page223_i87"
				( attribute "CDS_LIB" "mstr_discrete"
					( Origin gPackager )
				)
				( attribute "CDS_LOCATION" "R1G28"
					( Origin gPackager )
				)
				( attribute "CDS_SEC" "1"
					( Origin gPackager )
				)
				( attribute "LOCATION" "R1G28"
					( Origin gFrontEnd )
				)
				( attribute "MATERIAL" "CHIP"
					( Origin gFrontEnd )
				)
				( attribute "PACK_TYPE" "0402"
					( Origin gFrontEnd )
				)
				( attribute "PART_NUMBER" "G21497-005"
					( Origin gFrontEnd )
				)
				( attribute "PHYS_PAGE" "223"
					( Origin gFrontEnd )
				)
				( attribute "ROOM" "PVCCIN_CPU0_VR"
					( Origin gFrontEnd )
				)
				( attribute "ROT" "0"
					( Origin gFrontEnd )
				)
				( attribute "SEC" "1"
					( Origin gPackager )
				)
				( attribute "TOLERANCE" "5%"
					( Origin gFrontEnd )
				)
				( attribute "VALUE" "0.0"
					( Origin gFrontEnd )
				)
				( attribute "VER" "1"
					( Origin gFrontEnd )
				)
				( attribute "WATTAGE" "1/16W"
					( Origin gFrontEnd )
				)
				( attribute "XY" "(-1375,2625)"
					( Origin gFrontEnd )
				)
				( attribute "CHIPS_PART_NAME" "RES"
					( Origin gPackager )
				)
				( attribute "CDS_PART_NAME" "RES_0402-0.0,5%,1/16W,CHIP,G21A"
					( Origin gPackager )
				)
				( objectStatus "R1G28" )
				( pin "a"
					( attribute "PN" "1"
						( Origin gPackager )
					)
					( objectStatus "R1G28.1" )
				)
				( pin "b"
					( attribute "PN" "2"
						( Origin gPackager )
					)
					( objectStatus "R1G28.2" )
				)
			)
			( gate "@baseboard_fab2_lib.baseboard_fab2(sch_1):page223_i88"
				( attribute "CDS_LIB" "mstr_discrete"
					( Origin gPackager )
				)
				( attribute "CDS_LOCATION" "R1G27"
					( Origin gPackager )
				)
				( attribute "CDS_SEC" "1"
					( Origin gPackager )
				)
				( attribute "LOCATION" "R1G27"
					( Origin gFrontEnd )
				)
				( attribute "MATERIAL" "CHIP"
					( Origin gFrontEnd )
				)
				( attribute "PACK_TYPE" "0402"
					( Origin gFrontEnd )
				)
				( attribute "PART_NUMBER" "G21497-005"
					( Origin gFrontEnd )
				)
				( attribute "PHYS_PAGE" "223"
					( Origin gFrontEnd )
				)
				( attribute "ROOM" "PVCCIN_CPU0_VR"
					( Origin gFrontEnd )
				)
				( attribute "ROT" "0"
					( Origin gFrontEnd )
				)
				( attribute "SEC" "1"
					( Origin gPackager )
				)
				( attribute "TOLERANCE" "5%"
					( Origin gFrontEnd )
				)
				( attribute "VALUE" "0.0"
					( Origin gFrontEnd )
				)
				( attribute "VER" "1"
					( Origin gFrontEnd )
				)
				( attribute "WATTAGE" "1/16W"
					( Origin gFrontEnd )
				)
				( attribute "XY" "(-600,2800)"
					( Origin gFrontEnd )
				)
				( attribute "CHIPS_PART_NAME" "RES"
					( Origin gPackager )
				)
				( attribute "CDS_PART_NAME" "RES_0402-0.0,5%,1/16W,CHIP,G21A"
					( Origin gPackager )
				)
				( objectStatus "R1G27" )
				( pin "a"
					( attribute "PN" "1"
						( Origin gPackager )
					)
					( objectStatus "R1G27.1" )
				)
				( pin "b"
					( attribute "PN" "2"
						( Origin gPackager )
					)
					( objectStatus "R1G27.2" )
				)
			)
			( gate "@baseboard_fab2_lib.baseboard_fab2(sch_1):page223_i90"
				( attribute "CDS_LIB" "mstr_controller"
					( Origin gPackager )
				)
				( attribute "CDS_LMAN_SYM_OUTLINE" "-400,900,400,-900"
					( Origin gPackager )
				)
				( attribute "CDS_LOCATION" "EU1G2"
					( Origin gPackager )
				)
				( attribute "CDS_SEC" "1"
					( Origin gPackager )
				)
				( attribute "LOCATION" "EU1G2"
					( Origin gFrontEnd )
				)
				( attribute "MATERIAL" "IC"
					( Origin gFrontEnd )
				)
				( attribute "PACK_TYPE" "QFN"
					( Origin gFrontEnd )
				)
				( attribute "PART_NUMBER" "H89186-001"
					( Origin gFrontEnd )
				)
				( attribute "PHYS_PAGE" "223"
					( Origin gFrontEnd )
				)
				( attribute "ROT" "0"
					( Origin gFrontEnd )
				)
				( attribute "SEC" "1"
					( Origin gFrontEnd )
				)
				( attribute "SEC_TYPE" "QFN"
					( Origin gFrontEnd )
				)
				( attribute "VER" "2"
					( Origin gFrontEnd )
				)
				( attribute "XY" "(1500,1800)"
					( Origin gFrontEnd )
				)
				( attribute "CHIPS_PART_NAME" "PXM1310B"
					( Origin gPackager )
				)
				( attribute "CDS_PART_NAME" "PXM1310B_QFN-IC,H89186-001"
					( Origin gPackager )
				)
				( objectStatus "EU1G2" )
				( pin "airef1"
					( attribute "PN" "21"
						( Origin gPackager )
					)
					( objectStatus "EU1G2.21" )
				)
				( pin "airef2"
					( attribute "PN" "23"
						( Origin gPackager )
					)
					( objectStatus "EU1G2.23" )
				)
				( pin "airef3"
					( attribute "PN" "25"
						( Origin gPackager )
					)
					( objectStatus "EU1G2.25" )
				)
				( pin "aisen1"
					( attribute "PN" "22"
						( Origin gPackager )
					)
					( objectStatus "EU1G2.22" )
				)
				( pin "aisen2"
					( attribute "PN" "24"
						( Origin gPackager )
					)
					( objectStatus "EU1G2.24" )
				)
				( pin "aisen3"
					( attribute "PN" "26"
						( Origin gPackager )
					)
					( objectStatus "EU1G2.26" )
				)
				( pin "apwm1"
					( attribute "PN" "5"
						( Origin gPackager )
					)
					( objectStatus "EU1G2.5" )
				)
				( pin "apwm2"
					( attribute "PN" "4"
						( Origin gPackager )
					)
					( objectStatus "EU1G2.4" )
				)
				( pin "apwm3"
					( attribute "PN" "3"
						( Origin gPackager )
					)
					( objectStatus "EU1G2.3" )
				)
				( pin "atsen"
					( attribute "PN" "35"
						( Origin gPackager )
					)
					( objectStatus "EU1G2.35" )
				)
				( pin "avref"
					( attribute "PN" "20"
						( Origin gPackager )
					)
					( objectStatus "EU1G2.20" )
				)
				( pin "avren"
					( attribute "PN" "10"
						( Origin gPackager )
					)
					( objectStatus "EU1G2.10" )
				)
				( pin "avrrdy"
					( attribute "PN" "9"
						( Origin gPackager )
					)
					( objectStatus "EU1G2.9" )
				)
				( pin "avsen"
					( attribute "PN" "19"
						( Origin gPackager )
					)
					( objectStatus "EU1G2.19" )
				)
				( pin "biref1"
					( attribute "PN" "31"
						( Origin gPackager )
					)
					( objectStatus "EU1G2.31" )
				)
				( pin "bisen1"
					( attribute "PN" "32"
						( Origin gPackager )
					)
					( objectStatus "EU1G2.32" )
				)
				( pin "bpwm1"
					( attribute "PN" "1"
						( Origin gPackager )
					)
					( objectStatus "EU1G2.1" )
				)
				( pin "btsen"
					( attribute "PN" "34"
						( Origin gPackager )
					)
					( objectStatus "EU1G2.34" )
				)
				( pin "bvref"
					( attribute "PN" "30"
						( Origin gPackager )
					)
					( objectStatus "EU1G2.30" )
				)
				( pin "bvsen"
					( attribute "PN" "29"
						( Origin gPackager )
					)
					( objectStatus "EU1G2.29" )
				)
				( pin "dnc(0)"
					( attribute "PN" "2"
						( Origin gPackager )
					)
					( objectStatus "EU1G2.2" )
				)
				( pin "dnc(1)"
					( attribute "PN" "28"
						( Origin gPackager )
					)
					( objectStatus "EU1G2.28" )
				)
				( pin "gnd"
					( attribute "PN" "27"
						( Origin gPackager )
					)
					( objectStatus "EU1G2.27" )
				)
				( pin "iinsen"
					( attribute "PN" "38"
						( Origin gPackager )
					)
					( objectStatus "EU1G2.38" )
				)
				( pin "mp0"
					( attribute "PN" "13"
						( Origin gPackager )
					)
					( objectStatus "EU1G2.13" )
				)
				( pin "mp1"
					( attribute "PN" "14"
						( Origin gPackager )
					)
					( objectStatus "EU1G2.14" )
				)
				( pin "mp2"
					( attribute "PN" "18"
						( Origin gPackager )
					)
					( objectStatus "EU1G2.18" )
				)
				( pin "pinalrt_n"
					( attribute "PN" "12"
						( Origin gPackager )
					)
					( objectStatus "EU1G2.12" )
				)
				( pin "reset_n"
					( attribute "PN" "8"
						( Origin gPackager )
					)
					( objectStatus "EU1G2.8" )
				)
				( pin "scl"
					( attribute "PN" "7"
						( Origin gPackager )
					)
					( objectStatus "EU1G2.7" )
				)
				( pin "sda"
					( attribute "PN" "6"
						( Origin gPackager )
					)
					( objectStatus "EU1G2.6" )
				)
				( pin "thpad"
					( attribute "PN" "41"
						( Origin gPackager )
					)
					( objectStatus "EU1G2.41" )
				)
				( pin "valrt_n"
					( attribute "PN" "17"
						( Origin gPackager )
					)
					( objectStatus "EU1G2.17" )
				)
				( pin "vclk"
					( attribute "PN" "15"
						( Origin gPackager )
					)
					( objectStatus "EU1G2.15" )
				)
				( pin "vd12"
					( attribute "PN" "40"
						( Origin gPackager )
					)
					( objectStatus "EU1G2.40" )
				)
				( pin "vdd"
					( attribute "PN" "39"
						( Origin gPackager )
					)
					( objectStatus "EU1G2.39" )
				)
				( pin "vdio"
					( attribute "PN" "16"
						( Origin gPackager )
					)
					( objectStatus "EU1G2.16" )
				)
				( pin "vinsen"
					( attribute "PN" "37"
						( Origin gPackager )
					)
					( objectStatus "EU1G2.37" )
				)
				( pin "vrhot_n"
					( attribute "PN" "11"
						( Origin gPackager )
					)
					( objectStatus "EU1G2.11" )
				)
				( pin "xaddr1"
					( attribute "PN" "36"
						( Origin gPackager )
					)
					( objectStatus "EU1G2.36" )
				)
				( pin "xaddr2"
					( attribute "PN" "33"
						( Origin gPackager )
					)
					( objectStatus "EU1G2.33" )
				)
			)
			( gate "@baseboard_fab2_lib.baseboard_fab2(sch_1):page223_i92"
				( attribute "CDS_LIB" "dev_discrete"
					( Origin gPackager )
				)
				( attribute "CDS_LOCATION" "C9U12"
					( Origin gPackager )
				)
				( attribute "CDS_SEC" "1"
					( Origin gPackager )
				)
				( attribute "LOCATION" "C9U12"
					( Origin gFrontEnd )
				)
				( attribute "MATERIAL" "X7R"
					( Origin gFrontEnd )
				)
				( attribute "PACK_TYPE" "0402V"
					( Origin gFrontEnd )
				)
				( attribute "PART_NUMBER" "A36096-030"
					( Origin gFrontEnd )
				)
				( attribute "PHYS_PAGE" "223"
					( Origin gFrontEnd )
				)
				( attribute "ROOM" "VDDQ_GHJ_PWR_VR"
					( Origin gFrontEnd )
				)
				( attribute "ROT" "2"
					( Origin gFrontEnd )
				)
				( attribute "SEC" "1"
					( Origin gFrontEnd )
				)
				( attribute "SEC_TYPE" "0402V"
					( Origin gFrontEnd )
				)
				( attribute "TOLERANCE" "10%"
					( Origin gFrontEnd )
				)
				( attribute "VALUE" "0.1UF"
					( Origin gFrontEnd )
				)
				( attribute "VER" "1"
					( Origin gFrontEnd )
				)
				( attribute "VOLTAGE" "16V"
					( Units "uVoltage" "V" 1.000000)
					( Origin gFrontEnd )
				)
				( attribute "XY" "(-325,450)"
					( Origin gFrontEnd )
				)
				( attribute "CHIPS_PART_NAME" "CAP_A"
					( Origin gPackager )
				)
				( attribute "CDS_PART_NAME" "CAP_A_0402V-0.1UF,16V,10%,X7R,A"
					( Origin gPackager )
				)
				( objectStatus "C9U12" )
				( pin "a"
					( attribute "PN" "1"
						( Origin gPackager )
					)
					( objectStatus "C9U12.1" )
				)
				( pin "b"
					( attribute "PN" "2"
						( Origin gPackager )
					)
					( objectStatus "C9U12.2" )
				)
			)
			( gate "@baseboard_fab2_lib.baseboard_fab2(sch_1):page224_i6"
				( attribute "BOM_COST" "VDDQ_GHJ_PWR_VR"
					( Origin gFrontEnd )
				)
				( attribute "CDS_LIB" "mstr_discrete"
					( Origin gPackager )
				)
				( attribute "CDS_LOCATION" "C1G17"
					( Origin gPackager )
				)
				( attribute "CDS_SEC" "1"
					( Origin gPackager )
				)
				( attribute "LOCATION" "C1G17"
					( Origin gFrontEnd )
				)
				( attribute "MATERIAL" "X6S"
					( Origin gFrontEnd )
				)
				( attribute "PACK_TYPE" "0805LF"
					( Origin gFrontEnd )
				)
				( attribute "PART_NUMBER" "C95333-002"
					( Origin gFrontEnd )
				)
				( attribute "PHYS_PAGE" "224"
					( Origin gFrontEnd )
				)
				( attribute "ROOM" "VDDQ_GHJ_PWR_VR"
					( Origin gFrontEnd )
				)
				( attribute "ROT" "0"
					( Origin gFrontEnd )
				)
				( attribute "SEC" "1"
					( Origin gFrontEnd )
				)
				( attribute "SEC_TYPE" "0805LF"
					( Origin gFrontEnd )
				)
				( attribute "TOLERANCE" "20%"
					( Origin gFrontEnd )
				)
				( attribute "VALUE" "22UF"
					( Origin gFrontEnd )
				)
				( attribute "VER" "1"
					( Origin gFrontEnd )
				)
				( attribute "VOLTAGE" "4V"
					( Units "uVoltage" "V" 1.000000)
					( Origin gFrontEnd )
				)
				( attribute "XY" "(4000,1750)"
					( Origin gFrontEnd )
				)
				( attribute "CHIPS_PART_NAME" "CAP"
					( Origin gPackager )
				)
				( attribute "CDS_PART_NAME" "CAP_0805LF-22UF,4V,20%,X6S,C95A"
					( Origin gPackager )
				)
				( objectStatus "C1G17" )
				( pin "a"
					( attribute "PN" "1"
						( Origin gPackager )
					)
					( objectStatus "C1G17.1" )
				)
				( pin "b"
					( attribute "PN" "2"
						( Origin gPackager )
					)
					( objectStatus "C1G17.2" )
				)
			)
			( gate "@baseboard_fab2_lib.baseboard_fab2(sch_1):page224_i44"
				( attribute "CDS_LIB" "mstr_discrete"
					( Origin gPackager )
				)
				( attribute "CDS_LOCATION" "C1G11"
					( Origin gPackager )
				)
				( attribute "CDS_SEC" "1"
					( Origin gPackager )
				)
				( attribute "LOCATION" "C1G11"
					( Origin gFrontEnd )
				)
				( attribute "MATERIAL" "X7R"
					( Origin gFrontEnd )
				)
				( attribute "PACK_TYPE" "0402"
					( Origin gFrontEnd )
				)
				( attribute "PART_NUMBER" "A36096-104"
					( Origin gFrontEnd )
				)
				( attribute "PHYS_PAGE" "224"
					( Origin gFrontEnd )
				)
				( attribute "ROOM" "VDDQ_GHJ_PWR_VR"
					( Origin gFrontEnd )
				)
				( attribute "ROT" "2"
					( Origin gFrontEnd )
				)
				( attribute "SEC" "1"
					( Origin gFrontEnd )
				)
				( attribute "SEC_TYPE" "0402"
					( Origin gFrontEnd )
				)
				( attribute "SPOF" "TRUE"
					( Origin gFrontEnd )
				)
				( attribute "TOLERANCE" "10%"
					( Origin gFrontEnd )
				)
				( attribute "VALUE" "0.220UF"
					( Origin gFrontEnd )
				)
				( attribute "VER" "1"
					( Origin gFrontEnd )
				)
				( attribute "VOLTAGE" "16V"
					( Units "uVoltage" "V" 1.000000)
					( Origin gFrontEnd )
				)
				( attribute "XY" "(-1125,1900)"
					( Origin gFrontEnd )
				)
				( attribute "CHIPS_PART_NAME" "CAP"
					( Origin gPackager )
				)
				( attribute "CDS_PART_NAME" "CAP_0402-0.220UF,16V,10%,X7R,AA"
					( Origin gPackager )
				)
				( objectStatus "C1G11" )
				( pin "a"
					( attribute "PN" "1"
						( Origin gPackager )
					)
					( objectStatus "C1G11.1" )
				)
				( pin "b"
					( attribute "PN" "2"
						( Origin gPackager )
					)
					( objectStatus "C1G11.2" )
				)
			)
			( gate "@baseboard_fab2_lib.baseboard_fab2(sch_1):page224_i45"
				( attribute "CDS_LIB" "mstr_discrete"
					( Origin gPackager )
				)
				( attribute "CDS_LOCATION" "C9U6"
					( Origin gPackager )
				)
				( attribute "CDS_SEC" "1"
					( Origin gPackager )
				)
				( attribute "LOCATION" "C9U6"
					( Origin gFrontEnd )
				)
				( attribute "MATERIAL" "X6S"
					( Origin gFrontEnd )
				)
				( attribute "PACK_TYPE" "0805"
					( Origin gFrontEnd )
				)
				( attribute "PART_NUMBER" "C95333-007"
					( Origin gFrontEnd )
				)
				( attribute "PHYS_PAGE" "224"
					( Origin gFrontEnd )
				)
				( attribute "ROOM" "VDDQ_GHJ_PWR_VR"
					( Origin gFrontEnd )
				)
				( attribute "ROT" "0"
					( Origin gFrontEnd )
				)
				( attribute "SEC" "1"
					( Origin gFrontEnd )
				)
				( attribute "SEC_TYPE" "0805"
					( Origin gFrontEnd )
				)
				( attribute "TOLERANCE" "10%"
					( Origin gFrontEnd )
				)
				( attribute "VALUE" "10UF"
					( Origin gFrontEnd )
				)
				( attribute "VER" "1"
					( Origin gFrontEnd )
				)
				( attribute "VOLTAGE" "16V"
					( Units "uVoltage" "V" 1.000000)
					( Origin gFrontEnd )
				)
				( attribute "XY" "(-2700,2525)"
					( Origin gFrontEnd )
				)
				( attribute "CHIPS_PART_NAME" "CAP"
					( Origin gPackager )
				)
				( attribute "CDS_PART_NAME" "CAP_0805-10UF,16V,10%,X6S,C953A"
					( Origin gPackager )
				)
				( objectStatus "C9U6" )
				( pin "a"
					( attribute "PN" "1"
						( Origin gPackager )
					)
					( objectStatus "C9U6.1" )
				)
				( pin "b"
					( attribute "PN" "2"
						( Origin gPackager )
					)
					( objectStatus "C9U6.2" )
				)
			)
			( gate "@baseboard_fab2_lib.baseboard_fab2(sch_1):page224_i46"
				( attribute "CDS_LIB" "mstr_discrete"
					( Origin gPackager )
				)
				( attribute "CDS_LOCATION" "C9U4"
					( Origin gPackager )
				)
				( attribute "CDS_SEC" "1"
					( Origin gPackager )
				)
				( attribute "LOCATION" "C9U4"
					( Origin gFrontEnd )
				)
				( attribute "MATERIAL" "X6S"
					( Origin gFrontEnd )
				)
				( attribute "PACK_TYPE" "0805"
					( Origin gFrontEnd )
				)
				( attribute "PART_NUMBER" "C95333-007"
					( Origin gFrontEnd )
				)
				( attribute "PHYS_PAGE" "224"
					( Origin gFrontEnd )
				)
				( attribute "ROOM" "VDDQ_GHJ_PWR_VR"
					( Origin gFrontEnd )
				)
				( attribute "ROT" "0"
					( Origin gFrontEnd )
				)
				( attribute "SEC" "1"
					( Origin gFrontEnd )
				)
				( attribute "SEC_TYPE" "0805"
					( Origin gFrontEnd )
				)
				( attribute "TOLERANCE" "10%"
					( Origin gFrontEnd )
				)
				( attribute "VALUE" "10UF"
					( Origin gFrontEnd )
				)
				( attribute "VER" "1"
					( Origin gFrontEnd )
				)
				( attribute "VOLTAGE" "16V"
					( Units "uVoltage" "V" 1.000000)
					( Origin gFrontEnd )
				)
				( attribute "XY" "(-2450,2550)"
					( Origin gFrontEnd )
				)
				( attribute "CHIPS_PART_NAME" "CAP"
					( Origin gPackager )
				)
				( attribute "CDS_PART_NAME" "CAP_0805-10UF,16V,10%,X6S,C953A"
					( Origin gPackager )
				)
				( objectStatus "C9U4" )
				( pin "a"
					( attribute "PN" "1"
						( Origin gPackager )
					)
					( objectStatus "C9U4.1" )
				)
				( pin "b"
					( attribute "PN" "2"
						( Origin gPackager )
					)
					( objectStatus "C9U4.2" )
				)
			)
			( gate "@baseboard_fab2_lib.baseboard_fab2(sch_1):page224_i47"
				( attribute "CDS_LIB" "mstr_discrete"
					( Origin gPackager )
				)
				( attribute "CDS_LOCATION" "C9T4"
					( Origin gPackager )
				)
				( attribute "CDS_SEC" "1"
					( Origin gPackager )
				)
				( attribute "LOCATION" "C9T4"
					( Origin gFrontEnd )
				)
				( attribute "MATERIAL" "X6S"
					( Origin gFrontEnd )
				)
				( attribute "PACK_TYPE" "0805"
					( Origin gFrontEnd )
				)
				( attribute "PART_NUMBER" "C95333-007"
					( Origin gFrontEnd )
				)
				( attribute "PHYS_PAGE" "224"
					( Origin gFrontEnd )
				)
				( attribute "ROOM" "VDDQ_GHJ_PWR_VR"
					( Origin gFrontEnd )
				)
				( attribute "ROT" "0"
					( Origin gFrontEnd )
				)
				( attribute "SEC" "1"
					( Origin gFrontEnd )
				)
				( attribute "SEC_TYPE" "0805"
					( Origin gFrontEnd )
				)
				( attribute "TOLERANCE" "10%"
					( Origin gFrontEnd )
				)
				( attribute "VALUE" "10UF"
					( Origin gFrontEnd )
				)
				( attribute "VER" "1"
					( Origin gFrontEnd )
				)
				( attribute "VOLTAGE" "16V"
					( Units "uVoltage" "V" 1.000000)
					( Origin gFrontEnd )
				)
				( attribute "XY" "(-2175,2550)"
					( Origin gFrontEnd )
				)
				( attribute "CHIPS_PART_NAME" "CAP"
					( Origin gPackager )
				)
				( attribute "CDS_PART_NAME" "CAP_0805-10UF,16V,10%,X6S,C953A"
					( Origin gPackager )
				)
				( objectStatus "C9T4" )
				( pin "a"
					( attribute "PN" "1"
						( Origin gPackager )
					)
					( objectStatus "C9T4.1" )
				)
				( pin "b"
					( attribute "PN" "2"
						( Origin gPackager )
					)
					( objectStatus "C9T4.2" )
				)
			)
			( gate "@baseboard_fab2_lib.baseboard_fab2(sch_1):page224_i48"
				( attribute "CDS_LIB" "mstr_discrete"
					( Origin gPackager )
				)
				( attribute "CDS_LOCATION" "C1F27"
					( Origin gPackager )
				)
				( attribute "CDS_SEC" "1"
					( Origin gPackager )
				)
				( attribute "LOCATION" "C1F27"
					( Origin gFrontEnd )
				)
				( attribute "MATERIAL" "X6S"
					( Origin gFrontEnd )
				)
				( attribute "PACK_TYPE" "0402"
					( Origin gFrontEnd )
				)
				( attribute "PART_NUMBER" "D97712-011"
					( Origin gFrontEnd )
				)
				( attribute "PHYS_PAGE" "224"
					( Origin gFrontEnd )
				)
				( attribute "ROOM" "VDDQ_GHJ_PWR_VR"
					( Origin gFrontEnd )
				)
				( attribute "ROT" "0"
					( Origin gFrontEnd )
				)
				( attribute "SEC" "1"
					( Origin gFrontEnd )
				)
				( attribute "SEC_TYPE" "0402"
					( Origin gFrontEnd )
				)
				( attribute "TOLERANCE" "10%"
					( Origin gFrontEnd )
				)
				( attribute "VALUE" "1.0UF"
					( Origin gFrontEnd )
				)
				( attribute "VER" "1"
					( Origin gFrontEnd )
				)
				( attribute "VOLTAGE" "16V"
					( Units "uVoltage" "V" 1.000000)
					( Origin gFrontEnd )
				)
				( attribute "XY" "(-1925,2450)"
					( Origin gFrontEnd )
				)
				( attribute "CHIPS_PART_NAME" "CAP"
					( Origin gPackager )
				)
				( attribute "CDS_PART_NAME" "CAP_0402-1.0UF,16V,10%,X6S,D97A"
					( Origin gPackager )
				)
				( objectStatus "C1F27" )
				( pin "a"
					( attribute "PN" "1"
						( Origin gPackager )
					)
					( objectStatus "C1F27.1" )
				)
				( pin "b"
					( attribute "PN" "2"
						( Origin gPackager )
					)
					( objectStatus "C1F27.2" )
				)
			)
			( gate "@baseboard_fab2_lib.baseboard_fab2(sch_1):page224_i50"
				( attribute "CDS_LIB" "mstr_discrete"
					( Origin gPackager )
				)
				( attribute "CDS_LOCATION" "C1G6"
					( Origin gPackager )
				)
				( attribute "CDS_SEC" "1"
					( Origin gPackager )
				)
				( attribute "LOCATION" "C1G6"
					( Origin gFrontEnd )
				)
				( attribute "MATERIAL" "X6S"
					( Origin gFrontEnd )
				)
				( attribute "PACK_TYPE" "0402"
					( Origin gFrontEnd )
				)
				( attribute "PART_NUMBER" "D97712-011"
					( Origin gFrontEnd )
				)
				( attribute "PHYS_PAGE" "224"
					( Origin gFrontEnd )
				)
				( attribute "ROOM" "VDDQ_GHJ_PWR_VR"
					( Origin gFrontEnd )
				)
				( attribute "ROT" "0"
					( Origin gFrontEnd )
				)
				( attribute "SEC" "1"
					( Origin gFrontEnd )
				)
				( attribute "SEC_TYPE" "0402"
					( Origin gFrontEnd )
				)
				( attribute "TOLERANCE" "10%"
					( Origin gFrontEnd )
				)
				( attribute "VALUE" "1.0UF"
					( Origin gFrontEnd )
				)
				( attribute "VER" "1"
					( Origin gFrontEnd )
				)
				( attribute "VOLTAGE" "16V"
					( Units "uVoltage" "V" 1.000000)
					( Origin gFrontEnd )
				)
				( attribute "XY" "(-1375,2550)"
					( Origin gFrontEnd )
				)
				( attribute "CHIPS_PART_NAME" "CAP"
					( Origin gPackager )
				)
				( attribute "CDS_PART_NAME" "CAP_0402-1.0UF,16V,10%,X6S,D97A"
					( Origin gPackager )
				)
				( objectStatus "C1G6" )
				( pin "a"
					( attribute "PN" "1"
						( Origin gPackager )
					)
					( objectStatus "C1G6.1" )
				)
				( pin "b"
					( attribute "PN" "2"
						( Origin gPackager )
					)
					( objectStatus "C1G6.2" )
				)
			)
			( gate "@baseboard_fab2_lib.baseboard_fab2(sch_1):page224_i51"
				( attribute "CDS_LIB" "dev_discrete"
					( Origin gPackager )
				)
				( attribute "CDS_LOCATION" "C1G14"
					( Origin gPackager )
				)
				( attribute "CDS_SEC" "1"
					( Origin gPackager )
				)
				( attribute "LOCATION" "C1G14"
					( Origin gFrontEnd )
				)
				( attribute "MATERIAL" "X7R"
					( Origin gFrontEnd )
				)
				( attribute "PACK_TYPE" "0402V"
					( Origin gFrontEnd )
				)
				( attribute "PART_NUMBER" "A36096-030"
					( Origin gFrontEnd )
				)
				( attribute "PHYS_PAGE" "224"
					( Origin gFrontEnd )
				)
				( attribute "ROOM" "VDDQ_GHJ_PWR_VR"
					( Origin gFrontEnd )
				)
				( attribute "ROT" "0"
					( Origin gFrontEnd )
				)
				( attribute "SEC" "1"
					( Origin gFrontEnd )
				)
				( attribute "SEC_TYPE" "0402V"
					( Origin gFrontEnd )
				)
				( attribute "TOLERANCE" "10%"
					( Origin gFrontEnd )
				)
				( attribute "VALUE" "0.1UF"
					( Origin gFrontEnd )
				)
				( attribute "VER" "1"
					( Origin gFrontEnd )
				)
				( attribute "VOLTAGE" "16V"
					( Units "uVoltage" "V" 1.000000)
					( Origin gFrontEnd )
				)
				( attribute "XY" "(-1675,2500)"
					( Origin gFrontEnd )
				)
				( attribute "CHIPS_PART_NAME" "CAP_A"
					( Origin gPackager )
				)
				( attribute "CDS_PART_NAME" "CAP_A_0402V-0.1UF,16V,10%,X7R,A"
					( Origin gPackager )
				)
				( objectStatus "C1G14" )
				( pin "a"
					( attribute "PN" "1"
						( Origin gPackager )
					)
					( objectStatus "C1G14.1" )
				)
				( pin "b"
					( attribute "PN" "2"
						( Origin gPackager )
					)
					( objectStatus "C1G14.2" )
				)
			)
			( gate "@baseboard_fab2_lib.baseboard_fab2(sch_1):page224_i52"
				( attribute "CDS_LIB" "mstr_discrete"
					( Origin gPackager )
				)
				( attribute "CDS_LOCATION" "R9U1"
					( Origin gPackager )
				)
				( attribute "CDS_SEC" "1"
					( Origin gPackager )
				)
				( attribute "LOCATION" "R9U1"
					( Origin gFrontEnd )
				)
				( attribute "MATERIAL" "CHIP"
					( Origin gFrontEnd )
				)
				( attribute "PACK_TYPE" "0402"
					( Origin gFrontEnd )
				)
				( attribute "PART_NUMBER" "G21796-090"
					( Origin gFrontEnd )
				)
				( attribute "PHYS_PAGE" "224"
					( Origin gFrontEnd )
				)
				( attribute "ROOM" "VDDQ_GHJ_PWR_VR"
					( Origin gFrontEnd )
				)
				( attribute "ROT" "0"
					( Origin gFrontEnd )
				)
				( attribute "SEC" "1"
					( Origin gFrontEnd )
				)
				( attribute "SEC_TYPE" "0402"
					( Origin gFrontEnd )
				)
				( attribute "TOLERANCE" "1%"
					( Origin gFrontEnd )
				)
				( attribute "VALUE" "1.0"
					( Origin gFrontEnd )
				)
				( attribute "VER" "1"
					( Origin gFrontEnd )
				)
				( attribute "WATTAGE" "1/16W"
					( Origin gFrontEnd )
				)
				( attribute "XY" "(-1125,3050)"
					( Origin gFrontEnd )
				)
				( attribute "CHIPS_PART_NAME" "RES"
					( Origin gPackager )
				)
				( attribute "CDS_PART_NAME" "RES_0402-1.0,1%,1/16W,CHIP,G21A"
					( Origin gPackager )
				)
				( objectStatus "R9U1" )
				( pin "a"
					( attribute "PN" "1"
						( Origin gPackager )
					)
					( objectStatus "R9U1.1" )
				)
				( pin "b"
					( attribute "PN" "2"
						( Origin gPackager )
					)
					( objectStatus "R9U1.2" )
				)
			)
			( gate "@baseboard_fab2_lib.baseboard_fab2(sch_1):page224_i53"
				( attribute "CDS_LIB" "dev_discrete"
					( Origin gPackager )
				)
				( attribute "CDS_LOCATION" "C1G4"
					( Origin gPackager )
				)
				( attribute "CDS_SEC" "1"
					( Origin gPackager )
				)
				( attribute "LOCATION" "C1G4"
					( Origin gFrontEnd )
				)
				( attribute "MATERIAL" "X6S"
					( Origin gFrontEnd )
				)
				( attribute "PACK_TYPE" "0402V"
					( Origin gFrontEnd )
				)
				( attribute "PART_NUMBER" "D97712-004"
					( Origin gFrontEnd )
				)
				( attribute "PHYS_PAGE" "224"
					( Origin gFrontEnd )
				)
				( attribute "ROOM" "VDDQ_GHJ_PWR_VR"
					( Origin gFrontEnd )
				)
				( attribute "ROT" "2"
					( Origin gFrontEnd )
				)
				( attribute "SEC" "1"
					( Origin gFrontEnd )
				)
				( attribute "SEC_TYPE" "0402V"
					( Origin gFrontEnd )
				)
				( attribute "TOLERANCE" "10%"
					( Origin gFrontEnd )
				)
				( attribute "VALUE" "1.0UF"
					( Origin gFrontEnd )
				)
				( attribute "VER" "1"
					( Origin gFrontEnd )
				)
				( attribute "VOLTAGE" "6.3V"
					( Units "uVoltage" "V" 1.000000)
					( Origin gFrontEnd )
				)
				( attribute "XY" "(-525,2500)"
					( Origin gFrontEnd )
				)
				( attribute "CHIPS_PART_NAME" "CAP_A"
					( Origin gPackager )
				)
				( attribute "CDS_PART_NAME" "CAP_A_0402V-1.0UF,6.3V,10%,X6SA"
					( Origin gPackager )
				)
				( objectStatus "C1G4" )
				( pin "a"
					( attribute "PN" "1"
						( Origin gPackager )
					)
					( objectStatus "C1G4.1" )
				)
				( pin "b"
					( attribute "PN" "2"
						( Origin gPackager )
					)
					( objectStatus "C1G4.2" )
				)
			)
			( gate "@baseboard_fab2_lib.baseboard_fab2(sch_1):page224_i54"
				( attribute "CDS_LIB" "mstr_discrete"
					( Origin gPackager )
				)
				( attribute "CDS_LOCATION" "C1G5"
					( Origin gPackager )
				)
				( attribute "CDS_SEC" "1"
					( Origin gPackager )
				)
				( attribute "LOCATION" "C1G5"
					( Origin gFrontEnd )
				)
				( attribute "MATERIAL" "X7R"
					( Origin gFrontEnd )
				)
				( attribute "PACK_TYPE" "0402"
					( Origin gFrontEnd )
				)
				( attribute "PART_NUMBER" "A36096-155"
					( Origin gFrontEnd )
				)
				( attribute "PHYS_PAGE" "224"
					( Origin gFrontEnd )
				)
				( attribute "ROOM" "VDDQ_GHJ_PWR_VR"
					( Origin gFrontEnd )
				)
				( attribute "ROT" "0"
					( Origin gFrontEnd )
				)
				( attribute "SEC" "1"
					( Origin gFrontEnd )
				)
				( attribute "SEC_TYPE" "0402"
					( Origin gFrontEnd )
				)
				( attribute "TOLERANCE" "10%"
					( Origin gFrontEnd )
				)
				( attribute "VALUE" "0.22UF"
					( Origin gFrontEnd )
				)
				( attribute "VER" "1"
					( Origin gFrontEnd )
				)
				( attribute "VOLTAGE" "16V"
					( Units "uVoltage" "V" 1.000000)
					( Origin gFrontEnd )
				)
				( attribute "XY" "(-400,2500)"
					( Origin gFrontEnd )
				)
				( attribute "CHIPS_PART_NAME" "CAP"
					( Origin gPackager )
				)
				( attribute "CDS_PART_NAME" "CAP_0402-0.22UF,16V,10%,X7R,A3A"
					( Origin gPackager )
				)
				( objectStatus "C1G5" )
				( pin "a"
					( attribute "PN" "1"
						( Origin gPackager )
					)
					( objectStatus "C1G5.1" )
				)
				( pin "b"
					( attribute "PN" "2"
						( Origin gPackager )
					)
					( objectStatus "C1G5.2" )
				)
			)
			( gate "@baseboard_fab2_lib.baseboard_fab2(sch_1):page224_i55"
				( attribute "CDS_LIB" "mstr_discrete"
					( Origin gPackager )
				)
				( attribute "CDS_LOCATION" "L1G1"
					( Origin gPackager )
				)
				( attribute "CDS_SEC" "1"
					( Origin gPackager )
				)
				( attribute "LOCATION" "L1G1"
					( Origin gFrontEnd )
				)
				( attribute "MATERIAL" "IND"
					( Origin gFrontEnd )
				)
				( attribute "PACK_TYPE" "SM"
					( Origin gFrontEnd )
				)
				( attribute "PART_NUMBER" "D92183-034"
					( Origin gFrontEnd )
				)
				( attribute "PHYS_PAGE" "224"
					( Origin gFrontEnd )
				)
				( attribute "ROOM" "VDDQ_GHJ_PWR_VR"
					( Origin gFrontEnd )
				)
				( attribute "ROT" "0"
					( Origin gFrontEnd )
				)
				( attribute "SEC" "1"
					( Origin gFrontEnd )
				)
				( attribute "SEC_TYPE" "SM"
					( Origin gFrontEnd )
				)
				( attribute "VALUE" "0.12UH"
					( Origin gFrontEnd )
				)
				( attribute "VER" "1"
					( Origin gFrontEnd )
				)
				( attribute "XY" "(3100,1950)"
					( Origin gFrontEnd )
				)
				( attribute "CHIPS_PART_NAME" "INDUCTOR"
					( Origin gPackager )
				)
				( attribute "CDS_PART_NAME" "INDUCTOR_SM-0.12UH,IND,D92183-A"
					( Origin gPackager )
				)
				( objectStatus "L1G1" )
				( pin "ina"
					( attribute "PN" "1"
						( Origin gPackager )
					)
					( objectStatus "L1G1.1" )
				)
				( pin "inb"
					( attribute "PN" "2"
						( Origin gPackager )
					)
					( objectStatus "L1G1.2" )
				)
			)
			( gate "@baseboard_fab2_lib.baseboard_fab2(sch_1):page224_i65"
				( attribute "CDS_LIB" "mstr_discrete"
					( Origin gPackager )
				)
				( attribute "CDS_LOCATION" "L1F2"
					( Origin gPackager )
				)
				( attribute "CDS_SEC" "1"
					( Origin gPackager )
				)
				( attribute "LOCATION" "L1F2"
					( Origin gFrontEnd )
				)
				( attribute "MATERIAL" "IND"
					( Origin gFrontEnd )
				)
				( attribute "PACK_TYPE" "SM"
					( Origin gFrontEnd )
				)
				( attribute "PART_NUMBER" "D92183-034"
					( Origin gFrontEnd )
				)
				( attribute "PHYS_PAGE" "224"
					( Origin gFrontEnd )
				)
				( attribute "ROOM" "VDDQ_GHJ_PWR_VR"
					( Origin gFrontEnd )
				)
				( attribute "ROT" "0"
					( Origin gFrontEnd )
				)
				( attribute "SEC" "1"
					( Origin gFrontEnd )
				)
				( attribute "SEC_TYPE" "SM"
					( Origin gFrontEnd )
				)
				( attribute "VALUE" "0.12UH"
					( Origin gFrontEnd )
				)
				( attribute "VER" "1"
					( Origin gFrontEnd )
				)
				( attribute "XY" "(3100,-425)"
					( Origin gFrontEnd )
				)
				( attribute "CHIPS_PART_NAME" "INDUCTOR"
					( Origin gPackager )
				)
				( attribute "CDS_PART_NAME" "INDUCTOR_SM-0.12UH,IND,D92183-A"
					( Origin gPackager )
				)
				( objectStatus "L1F2" )
				( pin "ina"
					( attribute "PN" "1"
						( Origin gPackager )
					)
					( objectStatus "L1F2.1" )
				)
				( pin "inb"
					( attribute "PN" "2"
						( Origin gPackager )
					)
					( objectStatus "L1F2.2" )
				)
			)
			( gate "@baseboard_fab2_lib.baseboard_fab2(sch_1):page224_i68"
				( attribute "BOM_COST" "VDDQ_GHJ_PWR_VR"
					( Origin gFrontEnd )
				)
				( attribute "CDS_LIB" "mstr_discrete"
					( Origin gPackager )
				)
				( attribute "CDS_LOCATION" "C1G20"
					( Origin gPackager )
				)
				( attribute "CDS_SEC" "1"
					( Origin gPackager )
				)
				( attribute "LOCATION" "C1G20"
					( Origin gFrontEnd )
				)
				( attribute "MATERIAL" "X6S"
					( Origin gFrontEnd )
				)
				( attribute "PACK_TYPE" "0805LF"
					( Origin gFrontEnd )
				)
				( attribute "PART_NUMBER" "C95333-002"
					( Origin gFrontEnd )
				)
				( attribute "PHYS_PAGE" "224"
					( Origin gFrontEnd )
				)
				( attribute "ROOM" "VDDQ_GHJ_PWR_VR"
					( Origin gFrontEnd )
				)
				( attribute "ROT" "0"
					( Origin gFrontEnd )
				)
				( attribute "SEC" "1"
					( Origin gFrontEnd )
				)
				( attribute "SEC_TYPE" "0805LF"
					( Origin gFrontEnd )
				)
				( attribute "TOLERANCE" "20%"
					( Origin gFrontEnd )
				)
				( attribute "VALUE" "22UF"
					( Origin gFrontEnd )
				)
				( attribute "VER" "1"
					( Origin gFrontEnd )
				)
				( attribute "VOLTAGE" "4V"
					( Units "uVoltage" "V" 1.000000)
					( Origin gFrontEnd )
				)
				( attribute "XY" "(4000,-625)"
					( Origin gFrontEnd )
				)
				( attribute "CHIPS_PART_NAME" "CAP"
					( Origin gPackager )
				)
				( attribute "CDS_PART_NAME" "CAP_0805LF-22UF,4V,20%,X6S,C95A"
					( Origin gPackager )
				)
				( objectStatus "C1G20" )
				( pin "a"
					( attribute "PN" "1"
						( Origin gPackager )
					)
					( objectStatus "C1G20.1" )
				)
				( pin "b"
					( attribute "PN" "2"
						( Origin gPackager )
					)
					( objectStatus "C1G20.2" )
				)
			)
			( gate "@baseboard_fab2_lib.baseboard_fab2(sch_1):page224_i72"
				( attribute "CDS_LIB" "mstr_discrete"
					( Origin gPackager )
				)
				( attribute "CDS_LOCATION" "C1G29"
					( Origin gPackager )
				)
				( attribute "CDS_SEC" "1"
					( Origin gPackager )
				)
				( attribute "LOCATION" "C1G29"
					( Origin gFrontEnd )
				)
				( attribute "MATERIAL" "X7R"
					( Origin gFrontEnd )
				)
				( attribute "PACK_TYPE" "0402"
					( Origin gFrontEnd )
				)
				( attribute "PART_NUMBER" "A36096-155"
					( Origin gFrontEnd )
				)
				( attribute "PHYS_PAGE" "224"
					( Origin gFrontEnd )
				)
				( attribute "ROOM" "VDDQ_GHJ_PWR_VR"
					( Origin gFrontEnd )
				)
				( attribute "ROT" "0"
					( Origin gFrontEnd )
				)
				( attribute "SEC" "1"
					( Origin gFrontEnd )
				)
				( attribute "SEC_TYPE" "0402"
					( Origin gFrontEnd )
				)
				( attribute "TOLERANCE" "10%"
					( Origin gFrontEnd )
				)
				( attribute "VALUE" "0.22UF"
					( Origin gFrontEnd )
				)
				( attribute "VER" "1"
					( Origin gFrontEnd )
				)
				( attribute "VOLTAGE" "16V"
					( Units "uVoltage" "V" 1.000000)
					( Origin gFrontEnd )
				)
				( attribute "XY" "(-475,150)"
					( Origin gFrontEnd )
				)
				( attribute "CHIPS_PART_NAME" "CAP"
					( Origin gPackager )
				)
				( attribute "CDS_PART_NAME" "CAP_0402-0.22UF,16V,10%,X7R,A3A"
					( Origin gPackager )
				)
				( objectStatus "C1G29" )
				( pin "a"
					( attribute "PN" "1"
						( Origin gPackager )
					)
					( objectStatus "C1G29.1" )
				)
				( pin "b"
					( attribute "PN" "2"
						( Origin gPackager )
					)
					( objectStatus "C1G29.2" )
				)
			)
			( gate "@baseboard_fab2_lib.baseboard_fab2(sch_1):page224_i73"
				( attribute "CDS_LIB" "dev_discrete"
					( Origin gPackager )
				)
				( attribute "CDS_LOCATION" "C1F21"
					( Origin gPackager )
				)
				( attribute "CDS_SEC" "1"
					( Origin gPackager )
				)
				( attribute "LOCATION" "C1F21"
					( Origin gFrontEnd )
				)
				( attribute "MATERIAL" "X6S"
					( Origin gFrontEnd )
				)
				( attribute "PACK_TYPE" "0402V"
					( Origin gFrontEnd )
				)
				( attribute "PART_NUMBER" "D97712-004"
					( Origin gFrontEnd )
				)
				( attribute "PHYS_PAGE" "224"
					( Origin gFrontEnd )
				)
				( attribute "ROOM" "VDDQ_GHJ_PWR_VR"
					( Origin gFrontEnd )
				)
				( attribute "ROT" "2"
					( Origin gFrontEnd )
				)
				( attribute "SEC" "1"
					( Origin gFrontEnd )
				)
				( attribute "SEC_TYPE" "0402V"
					( Origin gFrontEnd )
				)
				( attribute "TOLERANCE" "10%"
					( Origin gFrontEnd )
				)
				( attribute "VALUE" "1.0UF"
					( Origin gFrontEnd )
				)
				( attribute "VER" "1"
					( Origin gFrontEnd )
				)
				( attribute "VOLTAGE" "6.3V"
					( Units "uVoltage" "V" 1.000000)
					( Origin gFrontEnd )
				)
				( attribute "XY" "(-575,150)"
					( Origin gFrontEnd )
				)
				( attribute "CHIPS_PART_NAME" "CAP_A"
					( Origin gPackager )
				)
				( attribute "CDS_PART_NAME" "CAP_A_0402V-1.0UF,6.3V,10%,X6SA"
					( Origin gPackager )
				)
				( objectStatus "C1F21" )
				( pin "a"
					( attribute "PN" "1"
						( Origin gPackager )
					)
					( objectStatus "C1F21.1" )
				)
				( pin "b"
					( attribute "PN" "2"
						( Origin gPackager )
					)
					( objectStatus "C1F21.2" )
				)
			)
			( gate "@baseboard_fab2_lib.baseboard_fab2(sch_1):page224_i75"
				( attribute "CDS_LIB" "mstr_discrete"
					( Origin gPackager )
				)
				( attribute "CDS_LOCATION" "C1F26"
					( Origin gPackager )
				)
				( attribute "CDS_SEC" "1"
					( Origin gPackager )
				)
				( attribute "LOCATION" "C1F26"
					( Origin gFrontEnd )
				)
				( attribute "MATERIAL" "X7R"
					( Origin gFrontEnd )
				)
				( attribute "PACK_TYPE" "0402"
					( Origin gFrontEnd )
				)
				( attribute "PART_NUMBER" "A36096-104"
					( Origin gFrontEnd )
				)
				( attribute "PHYS_PAGE" "224"
					( Origin gFrontEnd )
				)
				( attribute "ROOM" "VDDQ_GHJ_PWR_VR"
					( Origin gFrontEnd )
				)
				( attribute "ROT" "2"
					( Origin gFrontEnd )
				)
				( attribute "SEC" "1"
					( Origin gFrontEnd )
				)
				( attribute "SEC_TYPE" "0402"
					( Origin gFrontEnd )
				)
				( attribute "SPOF" "TRUE"
					( Origin gFrontEnd )
				)
				( attribute "TOLERANCE" "10%"
					( Origin gFrontEnd )
				)
				( attribute "VALUE" "0.220UF"
					( Origin gFrontEnd )
				)
				( attribute "VER" "1"
					( Origin gFrontEnd )
				)
				( attribute "VOLTAGE" "16V"
					( Units "uVoltage" "V" 1.000000)
					( Origin gFrontEnd )
				)
				( attribute "XY" "(-975,-475)"
					( Origin gFrontEnd )
				)
				( attribute "CHIPS_PART_NAME" "CAP"
					( Origin gPackager )
				)
				( attribute "CDS_PART_NAME" "CAP_0402-0.220UF,16V,10%,X7R,AA"
					( Origin gPackager )
				)
				( objectStatus "C1F26" )
				( pin "a"
					( attribute "PN" "1"
						( Origin gPackager )
					)
					( objectStatus "C1F26.1" )
				)
				( pin "b"
					( attribute "PN" "2"
						( Origin gPackager )
					)
					( objectStatus "C1F26.2" )
				)
			)
			( gate "@baseboard_fab2_lib.baseboard_fab2(sch_1):page224_i76"
				( attribute "CDS_LIB" "mstr_discrete"
					( Origin gPackager )
				)
				( attribute "CDS_LOCATION" "R9U12"
					( Origin gPackager )
				)
				( attribute "CDS_SEC" "1"
					( Origin gPackager )
				)
				( attribute "LOCATION" "R9U12"
					( Origin gFrontEnd )
				)
				( attribute "MATERIAL" "CHIP"
					( Origin gFrontEnd )
				)
				( attribute "PACK_TYPE" "0402"
					( Origin gFrontEnd )
				)
				( attribute "PART_NUMBER" "G21796-090"
					( Origin gFrontEnd )
				)
				( attribute "PHYS_PAGE" "224"
					( Origin gFrontEnd )
				)
				( attribute "ROOM" "VDDQ_GHJ_PWR_VR"
					( Origin gFrontEnd )
				)
				( attribute "ROT" "0"
					( Origin gFrontEnd )
				)
				( attribute "SEC" "1"
					( Origin gFrontEnd )
				)
				( attribute "SEC_TYPE" "0402"
					( Origin gFrontEnd )
				)
				( attribute "TOLERANCE" "1%"
					( Origin gFrontEnd )
				)
				( attribute "VALUE" "1.0"
					( Origin gFrontEnd )
				)
				( attribute "VER" "1"
					( Origin gFrontEnd )
				)
				( attribute "WATTAGE" "1/16W"
					( Origin gFrontEnd )
				)
				( attribute "XY" "(-1175,675)"
					( Origin gFrontEnd )
				)
				( attribute "CHIPS_PART_NAME" "RES"
					( Origin gPackager )
				)
				( attribute "CDS_PART_NAME" "RES_0402-1.0,1%,1/16W,CHIP,G21A"
					( Origin gPackager )
				)
				( objectStatus "R9U12" )
				( pin "a"
					( attribute "PN" "1"
						( Origin gPackager )
					)
					( objectStatus "R9U12.1" )
				)
				( pin "b"
					( attribute "PN" "2"
						( Origin gPackager )
					)
					( objectStatus "R9U12.2" )
				)
			)
			( gate "@baseboard_fab2_lib.baseboard_fab2(sch_1):page224_i77"
				( attribute "CDS_LIB" "mstr_discrete"
					( Origin gPackager )
				)
				( attribute "CDS_LOCATION" "C1G28"
					( Origin gPackager )
				)
				( attribute "CDS_SEC" "1"
					( Origin gPackager )
				)
				( attribute "LOCATION" "C1G28"
					( Origin gFrontEnd )
				)
				( attribute "MATERIAL" "X6S"
					( Origin gFrontEnd )
				)
				( attribute "PACK_TYPE" "0402"
					( Origin gFrontEnd )
				)
				( attribute "PART_NUMBER" "D97712-011"
					( Origin gFrontEnd )
				)
				( attribute "PHYS_PAGE" "224"
					( Origin gFrontEnd )
				)
				( attribute "ROOM" "VDDQ_GHJ_PWR_VR"
					( Origin gFrontEnd )
				)
				( attribute "ROT" "0"
					( Origin gFrontEnd )
				)
				( attribute "SEC" "1"
					( Origin gFrontEnd )
				)
				( attribute "SEC_TYPE" "0402"
					( Origin gFrontEnd )
				)
				( attribute "TOLERANCE" "10%"
					( Origin gFrontEnd )
				)
				( attribute "VALUE" "1.0UF"
					( Origin gFrontEnd )
				)
				( attribute "VER" "1"
					( Origin gFrontEnd )
				)
				( attribute "VOLTAGE" "16V"
					( Units "uVoltage" "V" 1.000000)
					( Origin gFrontEnd )
				)
				( attribute "XY" "(-1425,75)"
					( Origin gFrontEnd )
				)
				( attribute "CHIPS_PART_NAME" "CAP"
					( Origin gPackager )
				)
				( attribute "CDS_PART_NAME" "CAP_0402-1.0UF,16V,10%,X6S,D97A"
					( Origin gPackager )
				)
				( objectStatus "C1G28" )
				( pin "a"
					( attribute "PN" "1"
						( Origin gPackager )
					)
					( objectStatus "C1G28.1" )
				)
				( pin "b"
					( attribute "PN" "2"
						( Origin gPackager )
					)
					( objectStatus "C1G28.2" )
				)
			)
			( gate "@baseboard_fab2_lib.baseboard_fab2(sch_1):page224_i78"
				( attribute "CDS_LIB" "dev_discrete"
					( Origin gPackager )
				)
				( attribute "CDS_LOCATION" "C1F28"
					( Origin gPackager )
				)
				( attribute "CDS_SEC" "1"
					( Origin gPackager )
				)
				( attribute "LOCATION" "C1F28"
					( Origin gFrontEnd )
				)
				( attribute "MATERIAL" "X7R"
					( Origin gFrontEnd )
				)
				( attribute "PACK_TYPE" "0402V"
					( Origin gFrontEnd )
				)
				( attribute "PART_NUMBER" "A36096-030"
					( Origin gFrontEnd )
				)
				( attribute "PHYS_PAGE" "224"
					( Origin gFrontEnd )
				)
				( attribute "ROOM" "VDDQ_GHJ_PWR_VR"
					( Origin gFrontEnd )
				)
				( attribute "ROT" "0"
					( Origin gFrontEnd )
				)
				( attribute "SEC" "1"
					( Origin gFrontEnd )
				)
				( attribute "SEC_TYPE" "0402V"
					( Origin gFrontEnd )
				)
				( attribute "TOLERANCE" "10%"
					( Origin gFrontEnd )
				)
				( attribute "VALUE" "0.1UF"
					( Origin gFrontEnd )
				)
				( attribute "VER" "1"
					( Origin gFrontEnd )
				)
				( attribute "VOLTAGE" "16V"
					( Units "uVoltage" "V" 1.000000)
					( Origin gFrontEnd )
				)
				( attribute "XY" "(-1725,125)"
					( Origin gFrontEnd )
				)
				( attribute "CHIPS_PART_NAME" "CAP_A"
					( Origin gPackager )
				)
				( attribute "CDS_PART_NAME" "CAP_A_0402V-0.1UF,16V,10%,X7R,A"
					( Origin gPackager )
				)
				( objectStatus "C1F28" )
				( pin "a"
					( attribute "PN" "1"
						( Origin gPackager )
					)
					( objectStatus "C1F28.1" )
				)
				( pin "b"
					( attribute "PN" "2"
						( Origin gPackager )
					)
					( objectStatus "C1F28.2" )
				)
			)
			( gate "@baseboard_fab2_lib.baseboard_fab2(sch_1):page224_i79"
				( attribute "CDS_LIB" "mstr_discrete"
					( Origin gPackager )
				)
				( attribute "CDS_LOCATION" "C1G13"
					( Origin gPackager )
				)
				( attribute "CDS_SEC" "1"
					( Origin gPackager )
				)
				( attribute "LOCATION" "C1G13"
					( Origin gFrontEnd )
				)
				( attribute "MATERIAL" "X6S"
					( Origin gFrontEnd )
				)
				( attribute "PACK_TYPE" "0402"
					( Origin gFrontEnd )
				)
				( attribute "PART_NUMBER" "D97712-011"
					( Origin gFrontEnd )
				)
				( attribute "PHYS_PAGE" "224"
					( Origin gFrontEnd )
				)
				( attribute "ROOM" "VDDQ_GHJ_PWR_VR"
					( Origin gFrontEnd )
				)
				( attribute "ROT" "0"
					( Origin gFrontEnd )
				)
				( attribute "SEC" "1"
					( Origin gFrontEnd )
				)
				( attribute "SEC_TYPE" "0402"
					( Origin gFrontEnd )
				)
				( attribute "TOLERANCE" "10%"
					( Origin gFrontEnd )
				)
				( attribute "VALUE" "1.0UF"
					( Origin gFrontEnd )
				)
				( attribute "VER" "1"
					( Origin gFrontEnd )
				)
				( attribute "VOLTAGE" "16V"
					( Units "uVoltage" "V" 1.000000)
					( Origin gFrontEnd )
				)
				( attribute "XY" "(-1975,100)"
					( Origin gFrontEnd )
				)
				( attribute "CHIPS_PART_NAME" "CAP"
					( Origin gPackager )
				)
				( attribute "CDS_PART_NAME" "CAP_0402-1.0UF,16V,10%,X6S,D97A"
					( Origin gPackager )
				)
				( objectStatus "C1G13" )
				( pin "a"
					( attribute "PN" "1"
						( Origin gPackager )
					)
					( objectStatus "C1G13.1" )
				)
				( pin "b"
					( attribute "PN" "2"
						( Origin gPackager )
					)
					( objectStatus "C1G13.2" )
				)
			)
			( gate "@baseboard_fab2_lib.baseboard_fab2(sch_1):page224_i80"
				( attribute "CDS_LIB" "mstr_discrete"
					( Origin gPackager )
				)
				( attribute "CDS_LOCATION" "C9U3"
					( Origin gPackager )
				)
				( attribute "CDS_SEC" "1"
					( Origin gPackager )
				)
				( attribute "LOCATION" "C9U3"
					( Origin gFrontEnd )
				)
				( attribute "MATERIAL" "X6S"
					( Origin gFrontEnd )
				)
				( attribute "PACK_TYPE" "0805"
					( Origin gFrontEnd )
				)
				( attribute "PART_NUMBER" "C95333-007"
					( Origin gFrontEnd )
				)
				( attribute "PHYS_PAGE" "224"
					( Origin gFrontEnd )
				)
				( attribute "ROOM" "VDDQ_GHJ_PWR_VR"
					( Origin gFrontEnd )
				)
				( attribute "ROT" "0"
					( Origin gFrontEnd )
				)
				( attribute "SEC" "1"
					( Origin gFrontEnd )
				)
				( attribute "SEC_TYPE" "0805"
					( Origin gFrontEnd )
				)
				( attribute "TOLERANCE" "10%"
					( Origin gFrontEnd )
				)
				( attribute "VALUE" "10UF"
					( Origin gFrontEnd )
				)
				( attribute "VER" "1"
					( Origin gFrontEnd )
				)
				( attribute "VOLTAGE" "16V"
					( Units "uVoltage" "V" 1.000000)
					( Origin gFrontEnd )
				)
				( attribute "XY" "(-2225,100)"
					( Origin gFrontEnd )
				)
				( attribute "CHIPS_PART_NAME" "CAP"
					( Origin gPackager )
				)
				( attribute "CDS_PART_NAME" "CAP_0805-10UF,16V,10%,X6S,C953A"
					( Origin gPackager )
				)
				( objectStatus "C9U3" )
				( pin "a"
					( attribute "PN" "1"
						( Origin gPackager )
					)
					( objectStatus "C9U3.1" )
				)
				( pin "b"
					( attribute "PN" "2"
						( Origin gPackager )
					)
					( objectStatus "C9U3.2" )
				)
			)
			( gate "@baseboard_fab2_lib.baseboard_fab2(sch_1):page224_i81"
				( attribute "CDS_LIB" "mstr_discrete"
					( Origin gPackager )
				)
				( attribute "CDS_LOCATION" "C9T6"
					( Origin gPackager )
				)
				( attribute "CDS_SEC" "1"
					( Origin gPackager )
				)
				( attribute "LOCATION" "C9T6"
					( Origin gFrontEnd )
				)
				( attribute "MATERIAL" "X6S"
					( Origin gFrontEnd )
				)
				( attribute "PACK_TYPE" "0805"
					( Origin gFrontEnd )
				)
				( attribute "PART_NUMBER" "C95333-007"
					( Origin gFrontEnd )
				)
				( attribute "PHYS_PAGE" "224"
					( Origin gFrontEnd )
				)
				( attribute "ROOM" "VDDQ_GHJ_PWR_VR"
					( Origin gFrontEnd )
				)
				( attribute "ROT" "0"
					( Origin gFrontEnd )
				)
				( attribute "SEC" "1"
					( Origin gFrontEnd )
				)
				( attribute "SEC_TYPE" "0805"
					( Origin gFrontEnd )
				)
				( attribute "TOLERANCE" "10%"
					( Origin gFrontEnd )
				)
				( attribute "VALUE" "10UF"
					( Origin gFrontEnd )
				)
				( attribute "VER" "1"
					( Origin gFrontEnd )
				)
				( attribute "VOLTAGE" "16V"
					( Units "uVoltage" "V" 1.000000)
					( Origin gFrontEnd )
				)
				( attribute "XY" "(-2475,150)"
					( Origin gFrontEnd )
				)
				( attribute "CHIPS_PART_NAME" "CAP"
					( Origin gPackager )
				)
				( attribute "CDS_PART_NAME" "CAP_0805-10UF,16V,10%,X6S,C953A"
					( Origin gPackager )
				)
				( objectStatus "C9T6" )
				( pin "a"
					( attribute "PN" "1"
						( Origin gPackager )
					)
					( objectStatus "C9T6.1" )
				)
				( pin "b"
					( attribute "PN" "2"
						( Origin gPackager )
					)
					( objectStatus "C9T6.2" )
				)
			)
			( gate "@baseboard_fab2_lib.baseboard_fab2(sch_1):page224_i84"
				( attribute "CDS_LIB" "mstr_discrete"
					( Origin gPackager )
				)
				( attribute "CDS_LOCATION" "C9T9"
					( Origin gPackager )
				)
				( attribute "CDS_SEC" "1"
					( Origin gPackager )
				)
				( attribute "LOCATION" "C9T9"
					( Origin gFrontEnd )
				)
				( attribute "MATERIAL" "X6S"
					( Origin gFrontEnd )
				)
				( attribute "PACK_TYPE" "0805"
					( Origin gFrontEnd )
				)
				( attribute "PART_NUMBER" "C95333-007"
					( Origin gFrontEnd )
				)
				( attribute "PHYS_PAGE" "224"
					( Origin gFrontEnd )
				)
				( attribute "ROOM" "VDDQ_GHJ_PWR_VR"
					( Origin gFrontEnd )
				)
				( attribute "ROT" "0"
					( Origin gFrontEnd )
				)
				( attribute "SEC" "1"
					( Origin gFrontEnd )
				)
				( attribute "SEC_TYPE" "0805"
					( Origin gFrontEnd )
				)
				( attribute "TOLERANCE" "10%"
					( Origin gFrontEnd )
				)
				( attribute "VALUE" "10UF"
					( Origin gFrontEnd )
				)
				( attribute "VER" "1"
					( Origin gFrontEnd )
				)
				( attribute "VOLTAGE" "16V"
					( Units "uVoltage" "V" 1.000000)
					( Origin gFrontEnd )
				)
				( attribute "XY" "(-2725,125)"
					( Origin gFrontEnd )
				)
				( attribute "CHIPS_PART_NAME" "CAP"
					( Origin gPackager )
				)
				( attribute "CDS_PART_NAME" "CAP_0805-10UF,16V,10%,X6S,C953A"
					( Origin gPackager )
				)
				( objectStatus "C9T9" )
				( pin "a"
					( attribute "PN" "1"
						( Origin gPackager )
					)
					( objectStatus "C9T9.1" )
				)
				( pin "b"
					( attribute "PN" "2"
						( Origin gPackager )
					)
					( objectStatus "C9T9.2" )
				)
			)
			( gate "@baseboard_fab2_lib.baseboard_fab2(sch_1):page224_i110"
				( attribute "CDS_LIB" "mstr_discrete"
					( Origin gPackager )
				)
				( attribute "CDS_LOCATION" "EU1G1"
					( Origin gPackager )
				)
				( attribute "CDS_SEC" "1"
					( Origin gPackager )
				)
				( attribute "LOCATION" "EU1G1"
					( Origin gFrontEnd )
				)
				( attribute "MATERIAL" "IC"
					( Origin gFrontEnd )
				)
				( attribute "NO_XNET_CONNECTION" "1"
					( Origin gFrontEnd )
				)
				( attribute "PACK_TYPE" "SM"
					( Origin gFrontEnd )
				)
				( attribute "PART_NUMBER" "H73688-001"
					( Origin gFrontEnd )
				)
				( attribute "PHYS_PAGE" "224"
					( Origin gFrontEnd )
				)
				( attribute "ROT" "0"
					( Origin gFrontEnd )
				)
				( attribute "SEC" "1"
					( Origin gFrontEnd )
				)
				( attribute "SEC_TYPE" "SM"
					( Origin gFrontEnd )
				)
				( attribute "VALUE" "IR35411"
					( Origin gFrontEnd )
				)
				( attribute "VER" "1"
					( Origin gFrontEnd )
				)
				( attribute "XY" "(1475,2250)"
					( Origin gFrontEnd )
				)
				( attribute "CHIPS_PART_NAME" "IR354XX"
					( Origin gPackager )
				)
				( attribute "CDS_PART_NAME" "IR354XX_SM-IR35411,IC,H73688-0A"
					( Origin gPackager )
				)
				( objectStatus "EU1G1" )
				( pin "boost"
					( attribute "PN" "33"
						( Origin gPackager )
					)
					( objectStatus "EU1G1.33" )
				)
				( pin "en"
					( attribute "PN" "35"
						( Origin gPackager )
					)
					( objectStatus "EU1G1.35" )
				)
				( pin "gl(0)"
					( attribute "PN" "6"
						( Origin gPackager )
					)
					( objectStatus "EU1G1.6" )
				)
				( pin "gl(1)"
					( attribute "PN" "41"
						( Origin gPackager )
					)
					( objectStatus "EU1G1.41" )
				)
				( pin "iout"
					( attribute "PN" "38"
						( Origin gPackager )
					)
					( objectStatus "EU1G1.38" )
				)
				( pin "lgnd"
					( attribute "PN" "2"
						( Origin gPackager )
					)
					( objectStatus "EU1G1.2" )
				)
				( pin "nc"
					( attribute "PN" "31"
						( Origin gPackager )
					)
					( objectStatus "EU1G1.31" )
				)
				( pin "ocset"
					( attribute "PN" "37"
						( Origin gPackager )
					)
					( objectStatus "EU1G1.37" )
				)
				( pin "pgnd(0)"
					( attribute "PN" "5"
						( Origin gPackager )
					)
					( objectStatus "EU1G1.5" )
				)
				( pin "pgnd(1)"
					( attribute "PN" "7"
						( Origin gPackager )
					)
					( objectStatus "EU1G1.7" )
				)
				( pin "pgnd(2)"
					( attribute "PN" "40"
						( Origin gPackager )
					)
					( objectStatus "EU1G1.40" )
				)
				( pin "phase"
					( attribute "PN" "32"
						( Origin gPackager )
					)
					( objectStatus "EU1G1.32" )
				)
				( pin "pwm"
					( attribute "PN" "34"
						( Origin gPackager )
					)
					( objectStatus "EU1G1.34" )
				)
				( pin "refin"
					( attribute "PN" "39"
						( Origin gPackager )
					)
					( objectStatus "EU1G1.39" )
				)
				( pin "sw"
					( attribute "PN" "10"
						( Origin gPackager )
					)
					( objectStatus "EU1G1.10" )
				)
				( pin "tout_flt"
					( attribute "PN" "36"
						( Origin gPackager )
					)
					( objectStatus "EU1G1.36" )
				)
				( pin "vcc"
					( attribute "PN" "3"
						( Origin gPackager )
					)
					( objectStatus "EU1G1.3" )
				)
				( pin "vdrv"
					( attribute "PN" "4"
						( Origin gPackager )
					)
					( objectStatus "EU1G1.4" )
				)
				( pin "vin(0)"
					( attribute "PN" "25"
						( Origin gPackager )
					)
					( objectStatus "EU1G1.25" )
				)
				( pin "vin(1)"
					( attribute "PN" "30"
						( Origin gPackager )
					)
					( objectStatus "EU1G1.30" )
				)
				( pin "vos"
					( attribute "PN" "1"
						( Origin gPackager )
					)
					( objectStatus "EU1G1.1" )
				)
			)
			( gate "@baseboard_fab2_lib.baseboard_fab2(sch_1):page224_i111"
				( attribute "CDS_LIB" "mstr_discrete"
					( Origin gPackager )
				)
				( attribute "CDS_LOCATION" "EU1F1"
					( Origin gPackager )
				)
				( attribute "CDS_SEC" "1"
					( Origin gPackager )
				)
				( attribute "LOCATION" "EU1F1"
					( Origin gFrontEnd )
				)
				( attribute "MATERIAL" "IC"
					( Origin gFrontEnd )
				)
				( attribute "PACK_TYPE" "SM"
					( Origin gFrontEnd )
				)
				( attribute "PART_NUMBER" "H73688-001"
					( Origin gFrontEnd )
				)
				( attribute "PHYS_PAGE" "224"
					( Origin gFrontEnd )
				)
				( attribute "ROT" "0"
					( Origin gFrontEnd )
				)
				( attribute "SEC" "1"
					( Origin gFrontEnd )
				)
				( attribute "SEC_TYPE" "SM"
					( Origin gFrontEnd )
				)
				( attribute "VALUE" "IR35411"
					( Origin gFrontEnd )
				)
				( attribute "VER" "1"
					( Origin gFrontEnd )
				)
				( attribute "XY" "(1500,-125)"
					( Origin gFrontEnd )
				)
				( attribute "CHIPS_PART_NAME" "IR354XX"
					( Origin gPackager )
				)
				( attribute "CDS_PART_NAME" "IR354XX_SM-IR35411,IC,H73688-0A"
					( Origin gPackager )
				)
				( objectStatus "EU1F1" )
				( pin "boost"
					( attribute "PN" "33"
						( Origin gPackager )
					)
					( objectStatus "EU1F1.33" )
				)
				( pin "en"
					( attribute "PN" "35"
						( Origin gPackager )
					)
					( objectStatus "EU1F1.35" )
				)
				( pin "gl(0)"
					( attribute "PN" "6"
						( Origin gPackager )
					)
					( objectStatus "EU1F1.6" )
				)
				( pin "gl(1)"
					( attribute "PN" "41"
						( Origin gPackager )
					)
					( objectStatus "EU1F1.41" )
				)
				( pin "iout"
					( attribute "PN" "38"
						( Origin gPackager )
					)
					( objectStatus "EU1F1.38" )
				)
				( pin "lgnd"
					( attribute "PN" "2"
						( Origin gPackager )
					)
					( objectStatus "EU1F1.2" )
				)
				( pin "nc"
					( attribute "PN" "31"
						( Origin gPackager )
					)
					( objectStatus "EU1F1.31" )
				)
				( pin "ocset"
					( attribute "PN" "37"
						( Origin gPackager )
					)
					( objectStatus "EU1F1.37" )
				)
				( pin "pgnd(0)"
					( attribute "PN" "5"
						( Origin gPackager )
					)
					( objectStatus "EU1F1.5" )
				)
				( pin "pgnd(1)"
					( attribute "PN" "7"
						( Origin gPackager )
					)
					( objectStatus "EU1F1.7" )
				)
				( pin "pgnd(2)"
					( attribute "PN" "40"
						( Origin gPackager )
					)
					( objectStatus "EU1F1.40" )
				)
				( pin "phase"
					( attribute "PN" "32"
						( Origin gPackager )
					)
					( objectStatus "EU1F1.32" )
				)
				( pin "pwm"
					( attribute "PN" "34"
						( Origin gPackager )
					)
					( objectStatus "EU1F1.34" )
				)
				( pin "refin"
					( attribute "PN" "39"
						( Origin gPackager )
					)
					( objectStatus "EU1F1.39" )
				)
				( pin "sw"
					( attribute "PN" "10"
						( Origin gPackager )
					)
					( objectStatus "EU1F1.10" )
				)
				( pin "tout_flt"
					( attribute "PN" "36"
						( Origin gPackager )
					)
					( objectStatus "EU1F1.36" )
				)
				( pin "vcc"
					( attribute "PN" "3"
						( Origin gPackager )
					)
					( objectStatus "EU1F1.3" )
				)
				( pin "vdrv"
					( attribute "PN" "4"
						( Origin gPackager )
					)
					( objectStatus "EU1F1.4" )
				)
				( pin "vin(0)"
					( attribute "PN" "25"
						( Origin gPackager )
					)
					( objectStatus "EU1F1.25" )
				)
				( pin "vin(1)"
					( attribute "PN" "30"
						( Origin gPackager )
					)
					( objectStatus "EU1F1.30" )
				)
				( pin "vos"
					( attribute "PN" "1"
						( Origin gPackager )
					)
					( objectStatus "EU1F1.1" )
				)
			)
			( gate "@baseboard_fab2_lib.baseboard_fab2(sch_1):page224_i112"
				( attribute "CDS_LIB" "mstr_discrete"
					( Origin gPackager )
				)
				( attribute "CDS_LOCATION" "R1G26"
					( Origin gPackager )
				)
				( attribute "CDS_SEC" "1"
					( Origin gPackager )
				)
				( attribute "LOCATION" "R1G26"
					( Origin gFrontEnd )
				)
				( attribute "MATERIAL" "EMPTY"
					( Origin gFrontEnd )
				)
				( attribute "PACK_TYPE" "0402"
					( Origin gFrontEnd )
				)
				( attribute "PART_NUMBER" "G21796-187"
					( Origin gFrontEnd )
				)
				( attribute "PHYS_PAGE" "224"
					( Origin gFrontEnd )
				)
				( attribute "ROT" "0"
					( Origin gFrontEnd )
				)
				( attribute "SEC" "1"
					( Origin gPackager )
				)
				( attribute "TOLERANCE" "1%"
					( Origin gFrontEnd )
				)
				( attribute "VALUE" "68.1K"
					( Origin gFrontEnd )
				)
				( attribute "VER" "2"
					( Origin gFrontEnd )
				)
				( attribute "WATTAGE" "1/16W"
					( Origin gFrontEnd )
				)
				( attribute "XY" "(4275,2400)"
					( Origin gFrontEnd )
				)
				( attribute "CHIPS_PART_NAME" "RES"
					( Origin gPackager )
				)
				( attribute "CDS_PART_NAME" "RES_0402-68.1K,1%,1/16W,EMPTY,A"
					( Origin gPackager )
				)
				( objectStatus "R1G26" )
				( pin "a"
					( attribute "PN" "1"
						( Origin gPackager )
					)
					( objectStatus "R1G26.1" )
				)
				( pin "b"
					( attribute "PN" "2"
						( Origin gPackager )
					)
					( objectStatus "R1G26.2" )
				)
			)
			( gate "@baseboard_fab2_lib.baseboard_fab2(sch_1):page224_i114"
				( attribute "CDS_LIB" "mstr_discrete"
					( Origin gPackager )
				)
				( attribute "CDS_LOCATION" "R1G25"
					( Origin gPackager )
				)
				( attribute "CDS_SEC" "1"
					( Origin gPackager )
				)
				( attribute "LOCATION" "R1G25"
					( Origin gFrontEnd )
				)
				( attribute "MATERIAL" "EMPTY"
					( Origin gFrontEnd )
				)
				( attribute "PACK_TYPE" "0402"
					( Origin gFrontEnd )
				)
				( attribute "PART_NUMBER" "G21796-187"
					( Origin gFrontEnd )
				)
				( attribute "PHYS_PAGE" "224"
					( Origin gFrontEnd )
				)
				( attribute "ROT" "0"
					( Origin gFrontEnd )
				)
				( attribute "SEC" "1"
					( Origin gPackager )
				)
				( attribute "TOLERANCE" "1%"
					( Origin gFrontEnd )
				)
				( attribute "VALUE" "68.1K"
					( Origin gFrontEnd )
				)
				( attribute "VER" "2"
					( Origin gFrontEnd )
				)
				( attribute "WATTAGE" "1/16W"
					( Origin gFrontEnd )
				)
				( attribute "XY" "(4300,25)"
					( Origin gFrontEnd )
				)
				( attribute "CHIPS_PART_NAME" "RES"
					( Origin gPackager )
				)
				( attribute "CDS_PART_NAME" "RES_0402-68.1K,1%,1/16W,EMPTY,A"
					( Origin gPackager )
				)
				( objectStatus "R1G25" )
				( pin "a"
					( attribute "PN" "1"
						( Origin gPackager )
					)
					( objectStatus "R1G25.1" )
				)
				( pin "b"
					( attribute "PN" "2"
						( Origin gPackager )
					)
					( objectStatus "R1G25.2" )
				)
			)
			( gate "@baseboard_fab2_lib.baseboard_fab2(sch_1):page225_i58"
				( attribute "BOM_COST" "MEM_VRD_PVPP_AB"
					( Origin gFrontEnd )
				)
				( attribute "CDS_LIB" "mstr_discrete"
					( Origin gPackager )
				)
				( attribute "CDS_LOCATION" "R1G20"
					( Origin gPackager )
				)
				( attribute "CDS_SEC" "1"
					( Origin gPackager )
				)
				( attribute "LOCATION" "R1G20"
					( Origin gFrontEnd )
				)
				( attribute "MATERIAL" "CHIP"
					( Origin gFrontEnd )
				)
				( attribute "PACK_TYPE" "0603"
					( Origin gFrontEnd )
				)
				( attribute "PART_NUMBER" "G22026-003"
					( Origin gFrontEnd )
				)
				( attribute "PHYS_PAGE" "225"
					( Origin gFrontEnd )
				)
				( attribute "ROOM" "VDDQ_GHJ_PWR_VR"
					( Origin gFrontEnd )
				)
				( attribute "ROT" "0"
					( Origin gFrontEnd )
				)
				( attribute "SEC" "1"
					( Origin gPackager )
				)
				( attribute "TOLERANCE" "1%"
					( Origin gFrontEnd )
				)
				( attribute "VALUE" "120.0"
					( Origin gFrontEnd )
				)
				( attribute "VER" "2"
					( Origin gFrontEnd )
				)
				( attribute "WATTAGE" "1/10W"
					( Origin gFrontEnd )
				)
				( attribute "XY" "(4325,-75)"
					( Origin gFrontEnd )
				)
				( attribute "CHIPS_PART_NAME" "RES"
					( Origin gPackager )
				)
				( attribute "CDS_PART_NAME" "RES_0603-120.0,1%,1/10W,CHIP,GA"
					( Origin gPackager )
				)
				( objectStatus "R1G20" )
				( pin "a"
					( attribute "PN" "1"
						( Origin gPackager )
					)
					( objectStatus "R1G20.1" )
				)
				( pin "b"
					( attribute "PN" "2"
						( Origin gPackager )
					)
					( objectStatus "R1G20.2" )
				)
			)
			( gate "@baseboard_fab2_lib.baseboard_fab2(sch_1):page225_i74"
				( attribute "CDS_LIB" "mstr_discrete"
					( Origin gPackager )
				)
				( attribute "CDS_LOCATION" "R7U2"
					( Origin gPackager )
				)
				( attribute "CDS_SEC" "1"
					( Origin gPackager )
				)
				( attribute "LOCATION" "R7U2"
					( Origin gFrontEnd )
				)
				( attribute "MATERIAL" "EMPTY"
					( Origin gFrontEnd )
				)
				( attribute "PACK_TYPE" "0402"
					( Origin gFrontEnd )
				)
				( attribute "PART_NUMBER" "G21796-017"
					( Origin gFrontEnd )
				)
				( attribute "PHYS_PAGE" "225"
					( Origin gFrontEnd )
				)
				( attribute "ROOM" "VDDQ_GHJ_PWR_VR"
					( Origin gFrontEnd )
				)
				( attribute "ROT" "0"
					( Origin gFrontEnd )
				)
				( attribute "SEC" "1"
					( Origin gFrontEnd )
				)
				( attribute "SEC_TYPE" "0402"
					( Origin gFrontEnd )
				)
				( attribute "TOLERANCE" "1%"
					( Origin gFrontEnd )
				)
				( attribute "VALUE" "100.0"
					( Origin gFrontEnd )
				)
				( attribute "VER" "2"
					( Origin gFrontEnd )
				)
				( attribute "WATTAGE" "1/16W"
					( Origin gFrontEnd )
				)
				( attribute "XY" "(-650,2075)"
					( Origin gFrontEnd )
				)
				( attribute "CHIPS_PART_NAME" "RES"
					( Origin gPackager )
				)
				( attribute "CDS_PART_NAME" "RES_0402-100.0,1%,1/16W,EMPTY,A"
					( Origin gPackager )
				)
				( objectStatus "R7U2" )
				( pin "a"
					( attribute "PN" "1"
						( Origin gPackager )
					)
					( objectStatus "R7U2.1" )
				)
				( pin "b"
					( attribute "PN" "2"
						( Origin gPackager )
					)
					( objectStatus "R7U2.2" )
				)
			)
			( gate "@baseboard_fab2_lib.baseboard_fab2(sch_1):page225_i75"
				( attribute "CDS_LIB" "mstr_discrete"
					( Origin gPackager )
				)
				( attribute "CDS_LOCATION" "C9T5"
					( Origin gPackager )
				)
				( attribute "CDS_SEC" "1"
					( Origin gPackager )
				)
				( attribute "LOCATION" "C9T5"
					( Origin gFrontEnd )
				)
				( attribute "MATERIAL" "ALUM"
					( Origin gFrontEnd )
				)
				( attribute "PACK_TYPE" "3018"
					( Origin gFrontEnd )
				)
				( attribute "PART_NUMBER" "699013-049"
					( Origin gFrontEnd )
				)
				( attribute "PHYS_PAGE" "225"
					( Origin gFrontEnd )
				)
				( attribute "ROOM" "VDDQ_GHJ_PWR_VR"
					( Origin gFrontEnd )
				)
				( attribute "ROT" "0"
					( Origin gFrontEnd )
				)
				( attribute "SEC" "1"
					( Origin gFrontEnd )
				)
				( attribute "SEC_TYPE" "3018"
					( Origin gFrontEnd )
				)
				( attribute "TOLERANCE" "20%"
					( Origin gFrontEnd )
				)
				( attribute "VALUE" "470UF"
					( Origin gFrontEnd )
				)
				( attribute "VER" "1"
					( Origin gFrontEnd )
				)
				( attribute "VOLTAGE" "2.5V"
					( Units "uVoltage" "V" 1.000000)
					( Origin gFrontEnd )
				)
				( attribute "XY" "(2700,-75)"
					( Origin gFrontEnd )
				)
				( attribute "CHIPS_PART_NAME" "CAPP"
					( Origin gPackager )
				)
				( attribute "CDS_PART_NAME" "CAPP_3018-470UF,2.5V,20%,ALUM,A"
					( Origin gPackager )
				)
				( objectStatus "C9T5" )
				( pin "a"
					( attribute "PN" "1"
						( Origin gPackager )
					)
					( objectStatus "C9T5.1" )
				)
				( pin "b"
					( attribute "PN" "2"
						( Origin gPackager )
					)
					( objectStatus "C9T5.2" )
				)
			)
			( gate "@baseboard_fab2_lib.baseboard_fab2(sch_1):page225_i76"
				( attribute "CDS_LIB" "mstr_discrete"
					( Origin gPackager )
				)
				( attribute "CDS_LOCATION" "C9U2"
					( Origin gPackager )
				)
				( attribute "CDS_SEC" "1"
					( Origin gPackager )
				)
				( attribute "LOCATION" "C9U2"
					( Origin gFrontEnd )
				)
				( attribute "MATERIAL" "ALUM"
					( Origin gFrontEnd )
				)
				( attribute "PACK_TYPE" "3018"
					( Origin gFrontEnd )
				)
				( attribute "PART_NUMBER" "699013-049"
					( Origin gFrontEnd )
				)
				( attribute "PHYS_PAGE" "225"
					( Origin gFrontEnd )
				)
				( attribute "ROOM" "VDDQ_GHJ_PWR_VR"
					( Origin gFrontEnd )
				)
				( attribute "ROT" "0"
					( Origin gFrontEnd )
				)
				( attribute "SEC" "1"
					( Origin gFrontEnd )
				)
				( attribute "SEC_TYPE" "3018"
					( Origin gFrontEnd )
				)
				( attribute "TOLERANCE" "20%"
					( Origin gFrontEnd )
				)
				( attribute "VALUE" "470UF"
					( Origin gFrontEnd )
				)
				( attribute "VER" "1"
					( Origin gFrontEnd )
				)
				( attribute "VOLTAGE" "2.5V"
					( Units "uVoltage" "V" 1.000000)
					( Origin gFrontEnd )
				)
				( attribute "XY" "(3125,-75)"
					( Origin gFrontEnd )
				)
				( attribute "CHIPS_PART_NAME" "CAPP"
					( Origin gPackager )
				)
				( attribute "CDS_PART_NAME" "CAPP_3018-470UF,2.5V,20%,ALUM,A"
					( Origin gPackager )
				)
				( objectStatus "C9U2" )
				( pin "a"
					( attribute "PN" "1"
						( Origin gPackager )
					)
					( objectStatus "C9U2.1" )
				)
				( pin "b"
					( attribute "PN" "2"
						( Origin gPackager )
					)
					( objectStatus "C9U2.2" )
				)
			)
			( gate "@baseboard_fab2_lib.baseboard_fab2(sch_1):page225_i77"
				( attribute "CDS_LIB" "mstr_discrete"
					( Origin gPackager )
				)
				( attribute "CDS_LOCATION" "C9U9"
					( Origin gPackager )
				)
				( attribute "CDS_SEC" "1"
					( Origin gPackager )
				)
				( attribute "LOCATION" "C9U9"
					( Origin gFrontEnd )
				)
				( attribute "MATERIAL" "ALUM"
					( Origin gFrontEnd )
				)
				( attribute "PACK_TYPE" "3018"
					( Origin gFrontEnd )
				)
				( attribute "PART_NUMBER" "699013-049"
					( Origin gFrontEnd )
				)
				( attribute "PHYS_PAGE" "225"
					( Origin gFrontEnd )
				)
				( attribute "ROOM" "VDDQ_GHJ_PWR_VR"
					( Origin gFrontEnd )
				)
				( attribute "ROT" "0"
					( Origin gFrontEnd )
				)
				( attribute "SEC" "1"
					( Origin gFrontEnd )
				)
				( attribute "SEC_TYPE" "3018"
					( Origin gFrontEnd )
				)
				( attribute "TOLERANCE" "20%"
					( Origin gFrontEnd )
				)
				( attribute "VALUE" "470UF"
					( Origin gFrontEnd )
				)
				( attribute "VER" "1"
					( Origin gFrontEnd )
				)
				( attribute "VOLTAGE" "2.5V"
					( Units "uVoltage" "V" 1.000000)
					( Origin gFrontEnd )
				)
				( attribute "XY" "(3550,-75)"
					( Origin gFrontEnd )
				)
				( attribute "CHIPS_PART_NAME" "CAPP"
					( Origin gPackager )
				)
				( attribute "CDS_PART_NAME" "CAPP_3018-470UF,2.5V,20%,ALUM,A"
					( Origin gPackager )
				)
				( objectStatus "C9U9" )
				( pin "a"
					( attribute "PN" "1"
						( Origin gPackager )
					)
					( objectStatus "C9U9.1" )
				)
				( pin "b"
					( attribute "PN" "2"
						( Origin gPackager )
					)
					( objectStatus "C9U9.2" )
				)
			)
			( gate "@baseboard_fab2_lib.baseboard_fab2(sch_1):page225_i78"
				( attribute "CDS_LIB" "mstr_discrete"
					( Origin gPackager )
				)
				( attribute "CDS_LOCATION" "C9U5"
					( Origin gPackager )
				)
				( attribute "CDS_SEC" "1"
					( Origin gPackager )
				)
				( attribute "LOCATION" "C9U5"
					( Origin gFrontEnd )
				)
				( attribute "MATERIAL" "ALUM"
					( Origin gFrontEnd )
				)
				( attribute "PACK_TYPE" "3018"
					( Origin gFrontEnd )
				)
				( attribute "PART_NUMBER" "699013-049"
					( Origin gFrontEnd )
				)
				( attribute "PHYS_PAGE" "225"
					( Origin gFrontEnd )
				)
				( attribute "ROOM" "VDDQ_GHJ_PWR_VR"
					( Origin gFrontEnd )
				)
				( attribute "ROT" "0"
					( Origin gFrontEnd )
				)
				( attribute "SEC" "1"
					( Origin gFrontEnd )
				)
				( attribute "SEC_TYPE" "3018"
					( Origin gFrontEnd )
				)
				( attribute "TOLERANCE" "20%"
					( Origin gFrontEnd )
				)
				( attribute "VALUE" "470UF"
					( Origin gFrontEnd )
				)
				( attribute "VER" "1"
					( Origin gFrontEnd )
				)
				( attribute "VOLTAGE" "2.5V"
					( Units "uVoltage" "V" 1.000000)
					( Origin gFrontEnd )
				)
				( attribute "XY" "(3950,-100)"
					( Origin gFrontEnd )
				)
				( attribute "CHIPS_PART_NAME" "CAPP"
					( Origin gPackager )
				)
				( attribute "CDS_PART_NAME" "CAPP_3018-470UF,2.5V,20%,ALUM,A"
					( Origin gPackager )
				)
				( objectStatus "C9U5" )
				( pin "a"
					( attribute "PN" "1"
						( Origin gPackager )
					)
					( objectStatus "C9U5.1" )
				)
				( pin "b"
					( attribute "PN" "2"
						( Origin gPackager )
					)
					( objectStatus "C9U5.2" )
				)
			)
			( gate "@baseboard_fab2_lib.baseboard_fab2(sch_1):page225_i82"
				( attribute "BOM_COST" "MEM_VRD_PVDDQ_CD"
					( Origin gFrontEnd )
				)
				( attribute "CDS_LIB" "mstr_discrete"
					( Origin gPackager )
				)
				( attribute "CDS_LOCATION" "C8U1"
					( Origin gPackager )
				)
				( attribute "CDS_SEC" "1"
					( Origin gPackager )
				)
				( attribute "LOCATION" "C8U1"
					( Origin gFrontEnd )
				)
				( attribute "MATERIAL" "X5R"
					( Origin gFrontEnd )
				)
				( attribute "PACK_TYPE" "0805"
					( Origin gFrontEnd )
				)
				( attribute "PART_NUMBER" "602433-112"
					( Origin gFrontEnd )
				)
				( attribute "PHYS_PAGE" "225"
					( Origin gFrontEnd )
				)
				( attribute "ROOM" "VDDQ_GHJ_PWR_VR"
					( Origin gFrontEnd )
				)
				( attribute "ROT" "0"
					( Origin gFrontEnd )
				)
				( attribute "SEC" "1"
					( Origin gFrontEnd )
				)
				( attribute "SEC_TYPE" "0805"
					( Origin gFrontEnd )
				)
				( attribute "TOLERANCE" "20%"
					( Origin gFrontEnd )
				)
				( attribute "VALUE" "100UF"
					( Origin gFrontEnd )
				)
				( attribute "VER" "1"
					( Origin gFrontEnd )
				)
				( attribute "VOLTAGE" "4V"
					( Units "uVoltage" "V" 1.000000)
					( Origin gFrontEnd )
				)
				( attribute "XY" "(5000,2825)"
					( Origin gFrontEnd )
				)
				( attribute "CHIPS_PART_NAME" "CAP"
					( Origin gPackager )
				)
				( attribute "CDS_PART_NAME" "CAP_0805-100UF,4V,20%,X5R,6024A"
					( Origin gPackager )
				)
				( objectStatus "C8U1" )
				( pin "a"
					( attribute "PN" "1"
						( Origin gPackager )
					)
					( objectStatus "C8U1.1" )
				)
				( pin "b"
					( attribute "PN" "2"
						( Origin gPackager )
					)
					( objectStatus "C8U1.2" )
				)
			)
			( gate "@baseboard_fab2_lib.baseboard_fab2(sch_1):page225_i83"
				( attribute "BOM_COST" "MEM_VRD_PVDDQ_CD"
					( Origin gFrontEnd )
				)
				( attribute "CDS_LIB" "mstr_discrete"
					( Origin gPackager )
				)
				( attribute "CDS_LOCATION" "C8U8"
					( Origin gPackager )
				)
				( attribute "CDS_SEC" "1"
					( Origin gPackager )
				)
				( attribute "LOCATION" "C8U8"
					( Origin gFrontEnd )
				)
				( attribute "MATERIAL" "X5R"
					( Origin gFrontEnd )
				)
				( attribute "PACK_TYPE" "0805"
					( Origin gFrontEnd )
				)
				( attribute "PART_NUMBER" "602433-112"
					( Origin gFrontEnd )
				)
				( attribute "PHYS_PAGE" "225"
					( Origin gFrontEnd )
				)
				( attribute "ROOM" "VDDQ_GHJ_PWR_VR"
					( Origin gFrontEnd )
				)
				( attribute "ROT" "0"
					( Origin gFrontEnd )
				)
				( attribute "SEC" "1"
					( Origin gFrontEnd )
				)
				( attribute "SEC_TYPE" "0805"
					( Origin gFrontEnd )
				)
				( attribute "TOLERANCE" "20%"
					( Origin gFrontEnd )
				)
				( attribute "VALUE" "100UF"
					( Origin gFrontEnd )
				)
				( attribute "VER" "1"
					( Origin gFrontEnd )
				)
				( attribute "VOLTAGE" "4V"
					( Units "uVoltage" "V" 1.000000)
					( Origin gFrontEnd )
				)
				( attribute "XY" "(4600,2825)"
					( Origin gFrontEnd )
				)
				( attribute "CHIPS_PART_NAME" "CAP"
					( Origin gPackager )
				)
				( attribute "CDS_PART_NAME" "CAP_0805-100UF,4V,20%,X5R,6024A"
					( Origin gPackager )
				)
				( objectStatus "C8U8" )
				( pin "a"
					( attribute "PN" "1"
						( Origin gPackager )
					)
					( objectStatus "C8U8.1" )
				)
				( pin "b"
					( attribute "PN" "2"
						( Origin gPackager )
					)
					( objectStatus "C8U8.2" )
				)
			)
			( gate "@baseboard_fab2_lib.baseboard_fab2(sch_1):page225_i88"
				( attribute "BOM_COST" "MEM_VRD_PVDDQ_CD"
					( Origin gFrontEnd )
				)
				( attribute "CDS_LIB" "mstr_discrete"
					( Origin gPackager )
				)
				( attribute "CDS_LOCATION" "C8U12"
					( Origin gPackager )
				)
				( attribute "CDS_SEC" "1"
					( Origin gPackager )
				)
				( attribute "LOCATION" "C8U12"
					( Origin gFrontEnd )
				)
				( attribute "MATERIAL" "X5R"
					( Origin gFrontEnd )
				)
				( attribute "PACK_TYPE" "0805"
					( Origin gFrontEnd )
				)
				( attribute "PART_NUMBER" "602433-112"
					( Origin gFrontEnd )
				)
				( attribute "PHYS_PAGE" "225"
					( Origin gFrontEnd )
				)
				( attribute "ROOM" "VDDQ_GHJ_PWR_VR"
					( Origin gFrontEnd )
				)
				( attribute "ROT" "0"
					( Origin gFrontEnd )
				)
				( attribute "SEC" "1"
					( Origin gFrontEnd )
				)
				( attribute "SEC_TYPE" "0805"
					( Origin gFrontEnd )
				)
				( attribute "TOLERANCE" "20%"
					( Origin gFrontEnd )
				)
				( attribute "VALUE" "100UF"
					( Origin gFrontEnd )
				)
				( attribute "VER" "1"
					( Origin gFrontEnd )
				)
				( attribute "VOLTAGE" "4V"
					( Units "uVoltage" "V" 1.000000)
					( Origin gFrontEnd )
				)
				( attribute "XY" "(4250,2825)"
					( Origin gFrontEnd )
				)
				( attribute "CHIPS_PART_NAME" "CAP"
					( Origin gPackager )
				)
				( attribute "CDS_PART_NAME" "CAP_0805-100UF,4V,20%,X5R,6024A"
					( Origin gPackager )
				)
				( objectStatus "C8U12" )
				( pin "a"
					( attribute "PN" "1"
						( Origin gPackager )
					)
					( objectStatus "C8U12.1" )
				)
				( pin "b"
					( attribute "PN" "2"
						( Origin gPackager )
					)
					( objectStatus "C8U12.2" )
				)
			)
			( gate "@baseboard_fab2_lib.baseboard_fab2(sch_1):page225_i89"
				( attribute "BOM_COST" "MEM_VRD_PVDDQ_CD"
					( Origin gFrontEnd )
				)
				( attribute "CDS_LIB" "mstr_discrete"
					( Origin gPackager )
				)
				( attribute "CDS_LOCATION" "C8U11"
					( Origin gPackager )
				)
				( attribute "CDS_SEC" "1"
					( Origin gPackager )
				)
				( attribute "LOCATION" "C8U11"
					( Origin gFrontEnd )
				)
				( attribute "MATERIAL" "X5R"
					( Origin gFrontEnd )
				)
				( attribute "PACK_TYPE" "0805"
					( Origin gFrontEnd )
				)
				( attribute "PART_NUMBER" "602433-112"
					( Origin gFrontEnd )
				)
				( attribute "PHYS_PAGE" "225"
					( Origin gFrontEnd )
				)
				( attribute "ROOM" "VDDQ_GHJ_PWR_VR"
					( Origin gFrontEnd )
				)
				( attribute "ROT" "0"
					( Origin gFrontEnd )
				)
				( attribute "SEC" "1"
					( Origin gFrontEnd )
				)
				( attribute "SEC_TYPE" "0805"
					( Origin gFrontEnd )
				)
				( attribute "TOLERANCE" "20%"
					( Origin gFrontEnd )
				)
				( attribute "VALUE" "100UF"
					( Origin gFrontEnd )
				)
				( attribute "VER" "1"
					( Origin gFrontEnd )
				)
				( attribute "VOLTAGE" "4V"
					( Units "uVoltage" "V" 1.000000)
					( Origin gFrontEnd )
				)
				( attribute "XY" "(3850,2825)"
					( Origin gFrontEnd )
				)
				( attribute "CHIPS_PART_NAME" "CAP"
					( Origin gPackager )
				)
				( attribute "CDS_PART_NAME" "CAP_0805-100UF,4V,20%,X5R,6024A"
					( Origin gPackager )
				)
				( objectStatus "C8U11" )
				( pin "a"
					( attribute "PN" "1"
						( Origin gPackager )
					)
					( objectStatus "C8U11.1" )
				)
				( pin "b"
					( attribute "PN" "2"
						( Origin gPackager )
					)
					( objectStatus "C8U11.2" )
				)
			)
			( gate "@baseboard_fab2_lib.baseboard_fab2(sch_1):page225_i90"
				( attribute "BOM_COST" "MEM_VRD_PVDDQ_CD"
					( Origin gFrontEnd )
				)
				( attribute "CDS_LIB" "mstr_discrete"
					( Origin gPackager )
				)
				( attribute "CDS_LOCATION" "C7T1"
					( Origin gPackager )
				)
				( attribute "CDS_SEC" "1"
					( Origin gPackager )
				)
				( attribute "LOCATION" "C7T1"
					( Origin gFrontEnd )
				)
				( attribute "MATERIAL" "X5R"
					( Origin gFrontEnd )
				)
				( attribute "PACK_TYPE" "0805"
					( Origin gFrontEnd )
				)
				( attribute "PART_NUMBER" "602433-112"
					( Origin gFrontEnd )
				)
				( attribute "PHYS_PAGE" "225"
					( Origin gFrontEnd )
				)
				( attribute "ROOM" "VDDQ_GHJ_PWR_VR"
					( Origin gFrontEnd )
				)
				( attribute "ROT" "0"
					( Origin gFrontEnd )
				)
				( attribute "SEC" "1"
					( Origin gFrontEnd )
				)
				( attribute "SEC_TYPE" "0805"
					( Origin gFrontEnd )
				)
				( attribute "TOLERANCE" "20%"
					( Origin gFrontEnd )
				)
				( attribute "VALUE" "100UF"
					( Origin gFrontEnd )
				)
				( attribute "VER" "1"
					( Origin gFrontEnd )
				)
				( attribute "VOLTAGE" "4V"
					( Units "uVoltage" "V" 1.000000)
					( Origin gFrontEnd )
				)
				( attribute "XY" "(3500,2825)"
					( Origin gFrontEnd )
				)
				( attribute "CHIPS_PART_NAME" "CAP"
					( Origin gPackager )
				)
				( attribute "CDS_PART_NAME" "CAP_0805-100UF,4V,20%,X5R,6024A"
					( Origin gPackager )
				)
				( objectStatus "C7T1" )
				( pin "a"
					( attribute "PN" "1"
						( Origin gPackager )
					)
					( objectStatus "C7T1.1" )
				)
				( pin "b"
					( attribute "PN" "2"
						( Origin gPackager )
					)
					( objectStatus "C7T1.2" )
				)
			)
			( gate "@baseboard_fab2_lib.baseboard_fab2(sch_1):page225_i91"
				( attribute "BOM_COST" "MEM_VRD_PVDDQ_CD"
					( Origin gFrontEnd )
				)
				( attribute "CDS_LIB" "mstr_discrete"
					( Origin gPackager )
				)
				( attribute "CDS_LOCATION" "C7U7"
					( Origin gPackager )
				)
				( attribute "CDS_SEC" "1"
					( Origin gPackager )
				)
				( attribute "LOCATION" "C7U7"
					( Origin gFrontEnd )
				)
				( attribute "MATERIAL" "X5R"
					( Origin gFrontEnd )
				)
				( attribute "PACK_TYPE" "0805"
					( Origin gFrontEnd )
				)
				( attribute "PART_NUMBER" "602433-112"
					( Origin gFrontEnd )
				)
				( attribute "PHYS_PAGE" "225"
					( Origin gFrontEnd )
				)
				( attribute "ROOM" "VDDQ_GHJ_PWR_VR"
					( Origin gFrontEnd )
				)
				( attribute "ROT" "0"
					( Origin gFrontEnd )
				)
				( attribute "SEC" "1"
					( Origin gFrontEnd )
				)
				( attribute "SEC_TYPE" "0805"
					( Origin gFrontEnd )
				)
				( attribute "TOLERANCE" "20%"
					( Origin gFrontEnd )
				)
				( attribute "VALUE" "100UF"
					( Origin gFrontEnd )
				)
				( attribute "VER" "1"
					( Origin gFrontEnd )
				)
				( attribute "VOLTAGE" "4V"
					( Units "uVoltage" "V" 1.000000)
					( Origin gFrontEnd )
				)
				( attribute "XY" "(3150,2825)"
					( Origin gFrontEnd )
				)
				( attribute "CHIPS_PART_NAME" "CAP"
					( Origin gPackager )
				)
				( attribute "CDS_PART_NAME" "CAP_0805-100UF,4V,20%,X5R,6024A"
					( Origin gPackager )
				)
				( objectStatus "C7U7" )
				( pin "a"
					( attribute "PN" "1"
						( Origin gPackager )
					)
					( objectStatus "C7U7.1" )
				)
				( pin "b"
					( attribute "PN" "2"
						( Origin gPackager )
					)
					( objectStatus "C7U7.2" )
				)
			)
			( gate "@baseboard_fab2_lib.baseboard_fab2(sch_1):page225_i92"
				( attribute "BOM_COST" "MEM_VRD_PVDDQ_CD"
					( Origin gFrontEnd )
				)
				( attribute "CDS_LIB" "mstr_discrete"
					( Origin gPackager )
				)
				( attribute "CDS_LOCATION" "C2G7"
					( Origin gPackager )
				)
				( attribute "CDS_SEC" "1"
					( Origin gPackager )
				)
				( attribute "LOCATION" "C2G7"
					( Origin gFrontEnd )
				)
				( attribute "MATERIAL" "X5R"
					( Origin gFrontEnd )
				)
				( attribute "PACK_TYPE" "0805"
					( Origin gFrontEnd )
				)
				( attribute "PART_NUMBER" "602433-112"
					( Origin gFrontEnd )
				)
				( attribute "PHYS_PAGE" "225"
					( Origin gFrontEnd )
				)
				( attribute "ROOM" "VDDQ_GHJ_PWR_VR"
					( Origin gFrontEnd )
				)
				( attribute "ROT" "0"
					( Origin gFrontEnd )
				)
				( attribute "SEC" "1"
					( Origin gFrontEnd )
				)
				( attribute "SEC_TYPE" "0805"
					( Origin gFrontEnd )
				)
				( attribute "TOLERANCE" "20%"
					( Origin gFrontEnd )
				)
				( attribute "VALUE" "100UF"
					( Origin gFrontEnd )
				)
				( attribute "VER" "1"
					( Origin gFrontEnd )
				)
				( attribute "VOLTAGE" "4V"
					( Units "uVoltage" "V" 1.000000)
					( Origin gFrontEnd )
				)
				( attribute "XY" "(2750,2825)"
					( Origin gFrontEnd )
				)
				( attribute "CHIPS_PART_NAME" "CAP"
					( Origin gPackager )
				)
				( attribute "CDS_PART_NAME" "CAP_0805-100UF,4V,20%,X5R,6024A"
					( Origin gPackager )
				)
				( objectStatus "C2G7" )
				( pin "a"
					( attribute "PN" "1"
						( Origin gPackager )
					)
					( objectStatus "C2G7.1" )
				)
				( pin "b"
					( attribute "PN" "2"
						( Origin gPackager )
					)
					( objectStatus "C2G7.2" )
				)
			)
			( gate "@baseboard_fab2_lib.baseboard_fab2(sch_1):page225_i110"
				( attribute "BOM_COST" "MEM_VRD_PVDDQ_CD"
					( Origin gFrontEnd )
				)
				( attribute "CDS_LIB" "mstr_discrete"
					( Origin gPackager )
				)
				( attribute "CDS_LOCATION" "C2G16"
					( Origin gPackager )
				)
				( attribute "CDS_SEC" "1"
					( Origin gPackager )
				)
				( attribute "LOCATION" "C2G16"
					( Origin gFrontEnd )
				)
				( attribute "MATERIAL" "X5R"
					( Origin gFrontEnd )
				)
				( attribute "PACK_TYPE" "0805"
					( Origin gFrontEnd )
				)
				( attribute "PART_NUMBER" "602433-112"
					( Origin gFrontEnd )
				)
				( attribute "PHYS_PAGE" "225"
					( Origin gFrontEnd )
				)
				( attribute "ROOM" "VDDQ_GHJ_PWR_VR"
					( Origin gFrontEnd )
				)
				( attribute "ROT" "0"
					( Origin gFrontEnd )
				)
				( attribute "SEC" "1"
					( Origin gFrontEnd )
				)
				( attribute "SEC_TYPE" "0805"
					( Origin gFrontEnd )
				)
				( attribute "TOLERANCE" "20%"
					( Origin gFrontEnd )
				)
				( attribute "VALUE" "100UF"
					( Origin gFrontEnd )
				)
				( attribute "VER" "1"
					( Origin gFrontEnd )
				)
				( attribute "VOLTAGE" "4V"
					( Units "uVoltage" "V" 1.000000)
					( Origin gFrontEnd )
				)
				( attribute "XY" "(2400,2825)"
					( Origin gFrontEnd )
				)
				( attribute "CHIPS_PART_NAME" "CAP"
					( Origin gPackager )
				)
				( attribute "CDS_PART_NAME" "CAP_0805-100UF,4V,20%,X5R,6024A"
					( Origin gPackager )
				)
				( objectStatus "C2G16" )
				( pin "a"
					( attribute "PN" "1"
						( Origin gPackager )
					)
					( objectStatus "C2G16.1" )
				)
				( pin "b"
					( attribute "PN" "2"
						( Origin gPackager )
					)
					( objectStatus "C2G16.2" )
				)
			)
			( gate "@baseboard_fab2_lib.baseboard_fab2(sch_1):page225_i124"
				( attribute "BOM_COST" "MEM_VRD_PVDDQ_CD"
					( Origin gFrontEnd )
				)
				( attribute "CDS_LIB" "mstr_discrete"
					( Origin gPackager )
				)
				( attribute "CDS_LOCATION" "L1F1"
					( Origin gPackager )
				)
				( attribute "CDS_SEC" "1"
					( Origin gPackager )
				)
				( attribute "LOCATION" "L1F1"
					( Origin gFrontEnd )
				)
				( attribute "MATERIAL" "IND"
					( Origin gFrontEnd )
				)
				( attribute "PACK_TYPE" "SM"
					( Origin gFrontEnd )
				)
				( attribute "PART_NUMBER" "D92183-020"
					( Origin gFrontEnd )
				)
				( attribute "PHYS_PAGE" "225"
					( Origin gFrontEnd )
				)
				( attribute "ROOM" "VDDQ_GHJ_PWR_VR"
					( Origin gFrontEnd )
				)
				( attribute "ROT" "0"
					( Origin gFrontEnd )
				)
				( attribute "SEC" "1"
					( Origin gFrontEnd )
				)
				( attribute "SEC_TYPE" "SM"
					( Origin gFrontEnd )
				)
				( attribute "VALUE" "100NH"
					( Origin gFrontEnd )
				)
				( attribute "VER" "1"
					( Origin gFrontEnd )
				)
				( attribute "XY" "(-1675,1375)"
					( Origin gFrontEnd )
				)
				( attribute "CHIPS_PART_NAME" "INDUCTOR"
					( Origin gPackager )
				)
				( attribute "CDS_PART_NAME" "INDUCTOR_SM-100NH,IND,D92183-0B"
					( Origin gPackager )
				)
				( objectStatus "L1F1" )
				( pin "ina"
					( attribute "PN" "1"
						( Origin gPackager )
					)
					( objectStatus "L1F1.1" )
				)
				( pin "inb"
					( attribute "PN" "2"
						( Origin gPackager )
					)
					( objectStatus "L1F1.2" )
				)
			)
			( gate "@baseboard_fab2_lib.baseboard_fab2(sch_1):page225_i178"
				( attribute "BOM_COST" "MEM_VRD_PVDDQ_GHJ"
					( Origin gFrontEnd )
				)
				( attribute "CDS_LIB" "mstr_discrete"
					( Origin gPackager )
				)
				( attribute "CDS_LOCATION" "C8P31"
					( Origin gPackager )
				)
				( attribute "CDS_SEC" "1"
					( Origin gPackager )
				)
				( attribute "LOCATION" "C8P31"
					( Origin gFrontEnd )
				)
				( attribute "MATERIAL" "X6S"
					( Origin gFrontEnd )
				)
				( attribute "PACK_TYPE" "0805LF"
					( Origin gFrontEnd )
				)
				( attribute "PART_NUMBER" "C95333-002"
					( Origin gFrontEnd )
				)
				( attribute "PHYS_PAGE" "225"
					( Origin gFrontEnd )
				)
				( attribute "ROOM" "VDDQ_GHJ_CPU1"
					( Origin gFrontEnd )
				)
				( attribute "ROT" "0"
					( Origin gFrontEnd )
				)
				( attribute "SEC" "1"
					( Origin gFrontEnd )
				)
				( attribute "SEC_TYPE" "0805LF"
					( Origin gFrontEnd )
				)
				( attribute "TOLERANCE" "20%"
					( Origin gFrontEnd )
				)
				( attribute "VALUE" "22UF"
					( Origin gFrontEnd )
				)
				( attribute "VER" "1"
					( Origin gFrontEnd )
				)
				( attribute "VOLTAGE" "4V"
					( Units "uVoltage" "V" 1.000000)
					( Origin gFrontEnd )
				)
				( attribute "XY" "(-1950,3050)"
					( Origin gFrontEnd )
				)
				( attribute "CHIPS_PART_NAME" "CAP"
					( Origin gPackager )
				)
				( attribute "CDS_PART_NAME" "CAP_0805LF-22UF,4V,20%,X6S,C95A"
					( Origin gPackager )
				)
				( objectStatus "C8P31" )
				( pin "a"
					( attribute "PN" "1"
						( Origin gPackager )
					)
					( objectStatus "C8P31.1" )
				)
				( pin "b"
					( attribute "PN" "2"
						( Origin gPackager )
					)
					( objectStatus "C8P31.2" )
				)
			)
			( gate "@baseboard_fab2_lib.baseboard_fab2(sch_1):page225_i179"
				( attribute "BOM_COST" "MEM_VRD_PVDDQ_GHJ"
					( Origin gFrontEnd )
				)
				( attribute "CDS_LIB" "mstr_discrete"
					( Origin gPackager )
				)
				( attribute "CDS_LOCATION" "C2D43"
					( Origin gPackager )
				)
				( attribute "CDS_SEC" "1"
					( Origin gPackager )
				)
				( attribute "LOCATION" "C2D43"
					( Origin gFrontEnd )
				)
				( attribute "MATERIAL" "X6S"
					( Origin gFrontEnd )
				)
				( attribute "PACK_TYPE" "0603LF"
					( Origin gFrontEnd )
				)
				( attribute "PART_NUMBER" "E15431-001"
					( Origin gFrontEnd )
				)
				( attribute "PHYS_PAGE" "225"
					( Origin gFrontEnd )
				)
				( attribute "ROOM" "VDDQ_GHJ_CPU1"
					( Origin gFrontEnd )
				)
				( attribute "ROT" "0"
					( Origin gFrontEnd )
				)
				( attribute "SEC" "1"
					( Origin gFrontEnd )
				)
				( attribute "SEC_TYPE" "0603LF"
					( Origin gFrontEnd )
				)
				( attribute "TOLERANCE" "20%"
					( Origin gFrontEnd )
				)
				( attribute "VALUE" "10UF"
					( Origin gFrontEnd )
				)
				( attribute "VER" "1"
					( Origin gFrontEnd )
				)
				( attribute "VOLTAGE" "4V"
					( Units "uVoltage" "V" 1.000000)
					( Origin gFrontEnd )
				)
				( attribute "XY" "(-1550,3050)"
					( Origin gFrontEnd )
				)
				( attribute "CHIPS_PART_NAME" "CAP"
					( Origin gPackager )
				)
				( attribute "CDS_PART_NAME" "CAP_0603LF-10UF,4V,20%,X6S,E15A"
					( Origin gPackager )
				)
				( objectStatus "C2D43" )
				( pin "a"
					( attribute "PN" "1"
						( Origin gPackager )
					)
					( objectStatus "C2D43.1" )
				)
				( pin "b"
					( attribute "PN" "2"
						( Origin gPackager )
					)
					( objectStatus "C2D43.2" )
				)
			)
			( gate "@baseboard_fab2_lib.baseboard_fab2(sch_1):page225_i180"
				( attribute "BOM_COST" "MEM_VRD_PVDDQ_GHJ"
					( Origin gFrontEnd )
				)
				( attribute "CDS_LIB" "mstr_discrete"
					( Origin gPackager )
				)
				( attribute "CDS_LOCATION" "C2D41"
					( Origin gPackager )
				)
				( attribute "CDS_SEC" "1"
					( Origin gPackager )
				)
				( attribute "LOCATION" "C2D41"
					( Origin gFrontEnd )
				)
				( attribute "MATERIAL" "X6S"
					( Origin gFrontEnd )
				)
				( attribute "PACK_TYPE" "0603LF"
					( Origin gFrontEnd )
				)
				( attribute "PART_NUMBER" "E15431-001"
					( Origin gFrontEnd )
				)
				( attribute "PHYS_PAGE" "225"
					( Origin gFrontEnd )
				)
				( attribute "ROOM" "VDDQ_GHJ_CPU1"
					( Origin gFrontEnd )
				)
				( attribute "ROT" "0"
					( Origin gFrontEnd )
				)
				( attribute "SEC" "1"
					( Origin gFrontEnd )
				)
				( attribute "SEC_TYPE" "0603LF"
					( Origin gFrontEnd )
				)
				( attribute "TOLERANCE" "20%"
					( Origin gFrontEnd )
				)
				( attribute "VALUE" "10UF"
					( Origin gFrontEnd )
				)
				( attribute "VER" "1"
					( Origin gFrontEnd )
				)
				( attribute "VOLTAGE" "4V"
					( Units "uVoltage" "V" 1.000000)
					( Origin gFrontEnd )
				)
				( attribute "XY" "(-1200,3050)"
					( Origin gFrontEnd )
				)
				( attribute "CHIPS_PART_NAME" "CAP"
					( Origin gPackager )
				)
				( attribute "CDS_PART_NAME" "CAP_0603LF-10UF,4V,20%,X6S,E15A"
					( Origin gPackager )
				)
				( objectStatus "C2D41" )
				( pin "a"
					( attribute "PN" "1"
						( Origin gPackager )
					)
					( objectStatus "C2D41.1" )
				)
				( pin "b"
					( attribute "PN" "2"
						( Origin gPackager )
					)
					( objectStatus "C2D41.2" )
				)
			)
			( gate "@baseboard_fab2_lib.baseboard_fab2(sch_1):page225_i181"
				( attribute "BOM_COST" "MEM_VRD_PVDDQ_GHJ"
					( Origin gFrontEnd )
				)
				( attribute "CDS_LIB" "mstr_discrete"
					( Origin gPackager )
				)
				( attribute "CDS_LOCATION" "C2D44"
					( Origin gPackager )
				)
				( attribute "CDS_SEC" "1"
					( Origin gPackager )
				)
				( attribute "LOCATION" "C2D44"
					( Origin gFrontEnd )
				)
				( attribute "MATERIAL" "X6S"
					( Origin gFrontEnd )
				)
				( attribute "PACK_TYPE" "0603LF"
					( Origin gFrontEnd )
				)
				( attribute "PART_NUMBER" "E15431-001"
					( Origin gFrontEnd )
				)
				( attribute "PHYS_PAGE" "225"
					( Origin gFrontEnd )
				)
				( attribute "ROOM" "VDDQ_GHJ_CPU1"
					( Origin gFrontEnd )
				)
				( attribute "ROT" "0"
					( Origin gFrontEnd )
				)
				( attribute "SEC" "1"
					( Origin gFrontEnd )
				)
				( attribute "SEC_TYPE" "0603LF"
					( Origin gFrontEnd )
				)
				( attribute "TOLERANCE" "20%"
					( Origin gFrontEnd )
				)
				( attribute "VALUE" "10UF"
					( Origin gFrontEnd )
				)
				( attribute "VER" "1"
					( Origin gFrontEnd )
				)
				( attribute "VOLTAGE" "4V"
					( Units "uVoltage" "V" 1.000000)
					( Origin gFrontEnd )
				)
				( attribute "XY" "(-850,3050)"
					( Origin gFrontEnd )
				)
				( attribute "CHIPS_PART_NAME" "CAP"
					( Origin gPackager )
				)
				( attribute "CDS_PART_NAME" "CAP_0603LF-10UF,4V,20%,X6S,E15A"
					( Origin gPackager )
				)
				( objectStatus "C2D44" )
				( pin "a"
					( attribute "PN" "1"
						( Origin gPackager )
					)
					( objectStatus "C2D44.1" )
				)
				( pin "b"
					( attribute "PN" "2"
						( Origin gPackager )
					)
					( objectStatus "C2D44.2" )
				)
			)
			( gate "@baseboard_fab2_lib.baseboard_fab2(sch_1):page225_i183"
				( attribute "BOM_COST" "MEM_VRD_PVDDQ_GHJ"
					( Origin gFrontEnd )
				)
				( attribute "CDS_LIB" "mstr_discrete"
					( Origin gPackager )
				)
				( attribute "CDS_LOCATION" "C2D42"
					( Origin gPackager )
				)
				( attribute "CDS_SEC" "1"
					( Origin gPackager )
				)
				( attribute "LOCATION" "C2D42"
					( Origin gFrontEnd )
				)
				( attribute "MATERIAL" "X6S"
					( Origin gFrontEnd )
				)
				( attribute "PACK_TYPE" "0603LF"
					( Origin gFrontEnd )
				)
				( attribute "PART_NUMBER" "E15431-001"
					( Origin gFrontEnd )
				)
				( attribute "PHYS_PAGE" "225"
					( Origin gFrontEnd )
				)
				( attribute "ROOM" "VDDQ_GHJ_CPU1"
					( Origin gFrontEnd )
				)
				( attribute "ROT" "0"
					( Origin gFrontEnd )
				)
				( attribute "SEC" "1"
					( Origin gFrontEnd )
				)
				( attribute "SEC_TYPE" "0603LF"
					( Origin gFrontEnd )
				)
				( attribute "TOLERANCE" "20%"
					( Origin gFrontEnd )
				)
				( attribute "VALUE" "10UF"
					( Origin gFrontEnd )
				)
				( attribute "VER" "1"
					( Origin gFrontEnd )
				)
				( attribute "VOLTAGE" "4V"
					( Units "uVoltage" "V" 1.000000)
					( Origin gFrontEnd )
				)
				( attribute "XY" "(-450,3050)"
					( Origin gFrontEnd )
				)
				( attribute "CHIPS_PART_NAME" "CAP"
					( Origin gPackager )
				)
				( attribute "CDS_PART_NAME" "CAP_0603LF-10UF,4V,20%,X6S,E15A"
					( Origin gPackager )
				)
				( objectStatus "C2D42" )
				( pin "a"
					( attribute "PN" "1"
						( Origin gPackager )
					)
					( objectStatus "C2D42.1" )
				)
				( pin "b"
					( attribute "PN" "2"
						( Origin gPackager )
					)
					( objectStatus "C2D42.2" )
				)
			)
			( gate "@baseboard_fab2_lib.baseboard_fab2(sch_1):page225_i184"
				( attribute "BOM_COST" "MEM_VRD_PVDDQ_GHJ"
					( Origin gFrontEnd )
				)
				( attribute "CDS_LIB" "mstr_discrete"
					( Origin gPackager )
				)
				( attribute "CDS_LOCATION" "C8P30"
					( Origin gPackager )
				)
				( attribute "CDS_SEC" "1"
					( Origin gPackager )
				)
				( attribute "LOCATION" "C8P30"
					( Origin gFrontEnd )
				)
				( attribute "MATERIAL" "X6S"
					( Origin gFrontEnd )
				)
				( attribute "PACK_TYPE" "0805LF"
					( Origin gFrontEnd )
				)
				( attribute "PART_NUMBER" "C95333-002"
					( Origin gFrontEnd )
				)
				( attribute "PHYS_PAGE" "225"
					( Origin gFrontEnd )
				)
				( attribute "ROOM" "VDDQ_GHJ_CPU1"
					( Origin gFrontEnd )
				)
				( attribute "ROT" "0"
					( Origin gFrontEnd )
				)
				( attribute "SEC" "1"
					( Origin gFrontEnd )
				)
				( attribute "SEC_TYPE" "0805LF"
					( Origin gFrontEnd )
				)
				( attribute "TOLERANCE" "20%"
					( Origin gFrontEnd )
				)
				( attribute "VALUE" "22UF"
					( Origin gFrontEnd )
				)
				( attribute "VER" "1"
					( Origin gFrontEnd )
				)
				( attribute "VOLTAGE" "4V"
					( Units "uVoltage" "V" 1.000000)
					( Origin gFrontEnd )
				)
				( attribute "XY" "(-2300,3050)"
					( Origin gFrontEnd )
				)
				( attribute "CHIPS_PART_NAME" "CAP"
					( Origin gPackager )
				)
				( attribute "CDS_PART_NAME" "CAP_0805LF-22UF,4V,20%,X6S,C95A"
					( Origin gPackager )
				)
				( objectStatus "C8P30" )
				( pin "a"
					( attribute "PN" "1"
						( Origin gPackager )
					)
					( objectStatus "C8P30.1" )
				)
				( pin "b"
					( attribute "PN" "2"
						( Origin gPackager )
					)
					( objectStatus "C8P30.2" )
				)
			)
			( gate "@baseboard_fab2_lib.baseboard_fab2(sch_1):page225_i192"
				( attribute "CDS_LIB" "mstr_discrete"
					( Origin gPackager )
				)
				( attribute "CDS_LOCATION" "C1G15"
					( Origin gPackager )
				)
				( attribute "CDS_SEC" "1"
					( Origin gPackager )
				)
				( attribute "LOCATION" "C1G15"
					( Origin gFrontEnd )
				)
				( attribute "MATERIAL" "X6S"
					( Origin gFrontEnd )
				)
				( attribute "PACK_TYPE" "1210"
					( Origin gFrontEnd )
				)
				( attribute "PART_NUMBER" "D38464-007"
					( Origin gFrontEnd )
				)
				( attribute "PHYS_PAGE" "225"
					( Origin gFrontEnd )
				)
				( attribute "ROT" "0"
					( Origin gFrontEnd )
				)
				( attribute "SEC" "1"
					( Origin gFrontEnd )
				)
				( attribute "SEC_TYPE" "1210"
					( Origin gFrontEnd )
				)
				( attribute "TOLERANCE" "20%"
					( Origin gFrontEnd )
				)
				( attribute "VALUE" "47UF"
					( Origin gFrontEnd )
				)
				( attribute "VER" "1"
					( Origin gFrontEnd )
				)
				( attribute "VOLTAGE" "16V"
					( Units "uVoltage" "V" 1.000000)
					( Origin gFrontEnd )
				)
				( attribute "XY" "(-1250,1175)"
					( Origin gFrontEnd )
				)
				( attribute "CHIPS_PART_NAME" "CAP"
					( Origin gPackager )
				)
				( attribute "CDS_PART_NAME" "CAP_1210-47UF,16V,20%,X6S,D384A"
					( Origin gPackager )
				)
				( objectStatus "C1G15" )
				( pin "a"
					( attribute "PN" "1"
						( Origin gPackager )
					)
					( objectStatus "C1G15.1" )
				)
				( pin "b"
					( attribute "PN" "2"
						( Origin gPackager )
					)
					( objectStatus "C1G15.2" )
				)
			)
			( gate "@baseboard_fab2_lib.baseboard_fab2(sch_1):page225_i193"
				( attribute "CDS_LIB" "mstr_discrete"
					( Origin gPackager )
				)
				( attribute "CDS_LOCATION" "C1G12"
					( Origin gPackager )
				)
				( attribute "CDS_SEC" "1"
					( Origin gPackager )
				)
				( attribute "LOCATION" "C1G12"
					( Origin gFrontEnd )
				)
				( attribute "MATERIAL" "X6S"
					( Origin gFrontEnd )
				)
				( attribute "PACK_TYPE" "1210"
					( Origin gFrontEnd )
				)
				( attribute "PART_NUMBER" "D38464-007"
					( Origin gFrontEnd )
				)
				( attribute "PHYS_PAGE" "225"
					( Origin gFrontEnd )
				)
				( attribute "ROT" "0"
					( Origin gFrontEnd )
				)
				( attribute "SEC" "1"
					( Origin gFrontEnd )
				)
				( attribute "SEC_TYPE" "1210"
					( Origin gFrontEnd )
				)
				( attribute "TOLERANCE" "20%"
					( Origin gFrontEnd )
				)
				( attribute "VALUE" "47UF"
					( Origin gFrontEnd )
				)
				( attribute "VER" "1"
					( Origin gFrontEnd )
				)
				( attribute "VOLTAGE" "16V"
					( Units "uVoltage" "V" 1.000000)
					( Origin gFrontEnd )
				)
				( attribute "XY" "(-800,1175)"
					( Origin gFrontEnd )
				)
				( attribute "CHIPS_PART_NAME" "CAP"
					( Origin gPackager )
				)
				( attribute "CDS_PART_NAME" "CAP_1210-47UF,16V,20%,X6S,D384A"
					( Origin gPackager )
				)
				( objectStatus "C1G12" )
				( pin "a"
					( attribute "PN" "1"
						( Origin gPackager )
					)
					( objectStatus "C1G12.1" )
				)
				( pin "b"
					( attribute "PN" "2"
						( Origin gPackager )
					)
					( objectStatus "C1G12.2" )
				)
			)
			( gate "@baseboard_fab2_lib.baseboard_fab2(sch_1):page225_i194"
				( attribute "CDS_LIB" "mstr_discrete"
					( Origin gPackager )
				)
				( attribute "CDS_LOCATION" "C1G2"
					( Origin gPackager )
				)
				( attribute "CDS_SEC" "1"
					( Origin gPackager )
				)
				( attribute "LOCATION" "C1G2"
					( Origin gFrontEnd )
				)
				( attribute "MATERIAL" "X6S"
					( Origin gFrontEnd )
				)
				( attribute "PACK_TYPE" "1210"
					( Origin gFrontEnd )
				)
				( attribute "PART_NUMBER" "D38464-007"
					( Origin gFrontEnd )
				)
				( attribute "PHYS_PAGE" "225"
					( Origin gFrontEnd )
				)
				( attribute "ROT" "0"
					( Origin gFrontEnd )
				)
				( attribute "SEC" "1"
					( Origin gFrontEnd )
				)
				( attribute "SEC_TYPE" "1210"
					( Origin gFrontEnd )
				)
				( attribute "TOLERANCE" "20%"
					( Origin gFrontEnd )
				)
				( attribute "VALUE" "47UF"
					( Origin gFrontEnd )
				)
				( attribute "VER" "1"
					( Origin gFrontEnd )
				)
				( attribute "VOLTAGE" "16V"
					( Units "uVoltage" "V" 1.000000)
					( Origin gFrontEnd )
				)
				( attribute "XY" "(-375,1175)"
					( Origin gFrontEnd )
				)
				( attribute "CHIPS_PART_NAME" "CAP"
					( Origin gPackager )
				)
				( attribute "CDS_PART_NAME" "CAP_1210-47UF,16V,20%,X6S,D384A"
					( Origin gPackager )
				)
				( objectStatus "C1G2" )
				( pin "a"
					( attribute "PN" "1"
						( Origin gPackager )
					)
					( objectStatus "C1G2.1" )
				)
				( pin "b"
					( attribute "PN" "2"
						( Origin gPackager )
					)
					( objectStatus "C1G2.2" )
				)
			)
			( gate "@baseboard_fab2_lib.baseboard_fab2(sch_1):page225_i195"
				( attribute "CDS_LIB" "mstr_discrete"
					( Origin gPackager )
				)
				( attribute "CDS_LOCATION" "C1G7"
					( Origin gPackager )
				)
				( attribute "CDS_SEC" "1"
					( Origin gPackager )
				)
				( attribute "LOCATION" "C1G7"
					( Origin gFrontEnd )
				)
				( attribute "MATERIAL" "X6S"
					( Origin gFrontEnd )
				)
				( attribute "PACK_TYPE" "1210"
					( Origin gFrontEnd )
				)
				( attribute "PART_NUMBER" "D38464-007"
					( Origin gFrontEnd )
				)
				( attribute "PHYS_PAGE" "225"
					( Origin gFrontEnd )
				)
				( attribute "ROT" "0"
					( Origin gFrontEnd )
				)
				( attribute "SEC" "1"
					( Origin gFrontEnd )
				)
				( attribute "SEC_TYPE" "1210"
					( Origin gFrontEnd )
				)
				( attribute "TOLERANCE" "20%"
					( Origin gFrontEnd )
				)
				( attribute "VALUE" "47UF"
					( Origin gFrontEnd )
				)
				( attribute "VER" "1"
					( Origin gFrontEnd )
				)
				( attribute "VOLTAGE" "16V"
					( Units "uVoltage" "V" 1.000000)
					( Origin gFrontEnd )
				)
				( attribute "XY" "(50,1175)"
					( Origin gFrontEnd )
				)
				( attribute "CHIPS_PART_NAME" "CAP"
					( Origin gPackager )
				)
				( attribute "CDS_PART_NAME" "CAP_1210-47UF,16V,20%,X6S,D384A"
					( Origin gPackager )
				)
				( objectStatus "C1G7" )
				( pin "a"
					( attribute "PN" "1"
						( Origin gPackager )
					)
					( objectStatus "C1G7.1" )
				)
				( pin "b"
					( attribute "PN" "2"
						( Origin gPackager )
					)
					( objectStatus "C1G7.2" )
				)
			)
			( gate "@baseboard_fab2_lib.baseboard_fab2(sch_1):page225_i196"
				( attribute "CDS_LIB" "dev_discrete"
					( Origin gPackager )
				)
				( attribute "CDS_LOCATION" "C8T4"
					( Origin gPackager )
				)
				( attribute "CDS_SEC" "1"
					( Origin gPackager )
				)
				( attribute "LOCATION" "C8T4"
					( Origin gFrontEnd )
				)
				( attribute "MATERIAL" "X5R"
					( Origin gFrontEnd )
				)
				( attribute "PACK_TYPE" "0603V"
					( Origin gFrontEnd )
				)
				( attribute "PART_NUMBER" "602433-106"
					( Origin gFrontEnd )
				)
				( attribute "PHYS_PAGE" "225"
					( Origin gFrontEnd )
				)
				( attribute "ROT" "0"
					( Origin gFrontEnd )
				)
				( attribute "SEC" "1"
					( Origin gFrontEnd )
				)
				( attribute "SEC_TYPE" "0603V"
					( Origin gFrontEnd )
				)
				( attribute "TOLERANCE" "20%"
					( Origin gFrontEnd )
				)
				( attribute "VALUE" "47UF"
					( Origin gFrontEnd )
				)
				( attribute "VER" "1"
					( Origin gFrontEnd )
				)
				( attribute "VOLTAGE" "4V"
					( Units "uVoltage" "V" 1.000000)
					( Origin gFrontEnd )
				)
				( attribute "XY" "(2600,975)"
					( Origin gFrontEnd )
				)
				( attribute "CHIPS_PART_NAME" "CAP_A"
					( Origin gPackager )
				)
				( attribute "CDS_PART_NAME" "CAP_A_0603V-47UF,4V,20%,X5R,60A"
					( Origin gPackager )
				)
				( objectStatus "C8T4" )
				( pin "a"
					( attribute "PN" "1"
						( Origin gPackager )
					)
					( objectStatus "C8T4.1" )
				)
				( pin "b"
					( attribute "PN" "2"
						( Origin gPackager )
					)
					( objectStatus "C8T4.2" )
				)
			)
			( gate "@baseboard_fab2_lib.baseboard_fab2(sch_1):page225_i197"
				( attribute "CDS_LIB" "dev_discrete"
					( Origin gPackager )
				)
				( attribute "CDS_LOCATION" "C2G8"
					( Origin gPackager )
				)
				( attribute "CDS_SEC" "1"
					( Origin gPackager )
				)
				( attribute "LOCATION" "C2G8"
					( Origin gFrontEnd )
				)
				( attribute "MATERIAL" "X5R"
					( Origin gFrontEnd )
				)
				( attribute "PACK_TYPE" "0603V"
					( Origin gFrontEnd )
				)
				( attribute "PART_NUMBER" "602433-106"
					( Origin gFrontEnd )
				)
				( attribute "PHYS_PAGE" "225"
					( Origin gFrontEnd )
				)
				( attribute "ROT" "0"
					( Origin gFrontEnd )
				)
				( attribute "SEC" "1"
					( Origin gFrontEnd )
				)
				( attribute "SEC_TYPE" "0603V"
					( Origin gFrontEnd )
				)
				( attribute "TOLERANCE" "20%"
					( Origin gFrontEnd )
				)
				( attribute "VALUE" "47UF"
					( Origin gFrontEnd )
				)
				( attribute "VER" "1"
					( Origin gFrontEnd )
				)
				( attribute "VOLTAGE" "4V"
					( Units "uVoltage" "V" 1.000000)
					( Origin gFrontEnd )
				)
				( attribute "XY" "(2950,975)"
					( Origin gFrontEnd )
				)
				( attribute "CHIPS_PART_NAME" "CAP_A"
					( Origin gPackager )
				)
				( attribute "CDS_PART_NAME" "CAP_A_0603V-47UF,4V,20%,X5R,60A"
					( Origin gPackager )
				)
				( objectStatus "C2G8" )
				( pin "a"
					( attribute "PN" "1"
						( Origin gPackager )
					)
					( objectStatus "C2G8.1" )
				)
				( pin "b"
					( attribute "PN" "2"
						( Origin gPackager )
					)
					( objectStatus "C2G8.2" )
				)
			)
			( gate "@baseboard_fab2_lib.baseboard_fab2(sch_1):page225_i198"
				( attribute "CDS_LIB" "dev_discrete"
					( Origin gPackager )
				)
				( attribute "CDS_LOCATION" "C8T2"
					( Origin gPackager )
				)
				( attribute "CDS_SEC" "1"
					( Origin gPackager )
				)
				( attribute "LOCATION" "C8T2"
					( Origin gFrontEnd )
				)
				( attribute "MATERIAL" "X5R"
					( Origin gFrontEnd )
				)
				( attribute "PACK_TYPE" "0603V"
					( Origin gFrontEnd )
				)
				( attribute "PART_NUMBER" "602433-106"
					( Origin gFrontEnd )
				)
				( attribute "PHYS_PAGE" "225"
					( Origin gFrontEnd )
				)
				( attribute "ROT" "0"
					( Origin gFrontEnd )
				)
				( attribute "SEC" "1"
					( Origin gFrontEnd )
				)
				( attribute "SEC_TYPE" "0603V"
					( Origin gFrontEnd )
				)
				( attribute "TOLERANCE" "20%"
					( Origin gFrontEnd )
				)
				( attribute "VALUE" "47UF"
					( Origin gFrontEnd )
				)
				( attribute "VER" "1"
					( Origin gFrontEnd )
				)
				( attribute "VOLTAGE" "4V"
					( Units "uVoltage" "V" 1.000000)
					( Origin gFrontEnd )
				)
				( attribute "XY" "(3350,975)"
					( Origin gFrontEnd )
				)
				( attribute "CHIPS_PART_NAME" "CAP_A"
					( Origin gPackager )
				)
				( attribute "CDS_PART_NAME" "CAP_A_0603V-47UF,4V,20%,X5R,60A"
					( Origin gPackager )
				)
				( objectStatus "C8T2" )
				( pin "a"
					( attribute "PN" "1"
						( Origin gPackager )
					)
					( objectStatus "C8T2.1" )
				)
				( pin "b"
					( attribute "PN" "2"
						( Origin gPackager )
					)
					( objectStatus "C8T2.2" )
				)
			)
			( gate "@baseboard_fab2_lib.baseboard_fab2(sch_1):page225_i199"
				( attribute "CDS_LIB" "dev_discrete"
					( Origin gPackager )
				)
				( attribute "CDS_LOCATION" "C8U13"
					( Origin gPackager )
				)
				( attribute "CDS_SEC" "1"
					( Origin gPackager )
				)
				( attribute "LOCATION" "C8U13"
					( Origin gFrontEnd )
				)
				( attribute "MATERIAL" "X5R"
					( Origin gFrontEnd )
				)
				( attribute "PACK_TYPE" "0603V"
					( Origin gFrontEnd )
				)
				( attribute "PART_NUMBER" "602433-106"
					( Origin gFrontEnd )
				)
				( attribute "PHYS_PAGE" "225"
					( Origin gFrontEnd )
				)
				( attribute "ROT" "0"
					( Origin gFrontEnd )
				)
				( attribute "SEC" "1"
					( Origin gFrontEnd )
				)
				( attribute "SEC_TYPE" "0603V"
					( Origin gFrontEnd )
				)
				( attribute "TOLERANCE" "20%"
					( Origin gFrontEnd )
				)
				( attribute "VALUE" "47UF"
					( Origin gFrontEnd )
				)
				( attribute "VER" "1"
					( Origin gFrontEnd )
				)
				( attribute "VOLTAGE" "4V"
					( Units "uVoltage" "V" 1.000000)
					( Origin gFrontEnd )
				)
				( attribute "XY" "(2550,1725)"
					( Origin gFrontEnd )
				)
				( attribute "CHIPS_PART_NAME" "CAP_A"
					( Origin gPackager )
				)
				( attribute "CDS_PART_NAME" "CAP_A_0603V-47UF,4V,20%,X5R,60A"
					( Origin gPackager )
				)
				( objectStatus "C8U13" )
				( pin "a"
					( attribute "PN" "1"
						( Origin gPackager )
					)
					( objectStatus "C8U13.1" )
				)
				( pin "b"
					( attribute "PN" "2"
						( Origin gPackager )
					)
					( objectStatus "C8U13.2" )
				)
			)
			( gate "@baseboard_fab2_lib.baseboard_fab2(sch_1):page225_i200"
				( attribute "CDS_LIB" "dev_discrete"
					( Origin gPackager )
				)
				( attribute "CDS_LOCATION" "C2G15"
					( Origin gPackager )
				)
				( attribute "CDS_SEC" "1"
					( Origin gPackager )
				)
				( attribute "LOCATION" "C2G15"
					( Origin gFrontEnd )
				)
				( attribute "MATERIAL" "X5R"
					( Origin gFrontEnd )
				)
				( attribute "PACK_TYPE" "0603V"
					( Origin gFrontEnd )
				)
				( attribute "PART_NUMBER" "602433-106"
					( Origin gFrontEnd )
				)
				( attribute "PHYS_PAGE" "225"
					( Origin gFrontEnd )
				)
				( attribute "ROT" "0"
					( Origin gFrontEnd )
				)
				( attribute "SEC" "1"
					( Origin gFrontEnd )
				)
				( attribute "SEC_TYPE" "0603V"
					( Origin gFrontEnd )
				)
				( attribute "TOLERANCE" "20%"
					( Origin gFrontEnd )
				)
				( attribute "VALUE" "47UF"
					( Origin gFrontEnd )
				)
				( attribute "VER" "1"
					( Origin gFrontEnd )
				)
				( attribute "VOLTAGE" "4V"
					( Units "uVoltage" "V" 1.000000)
					( Origin gFrontEnd )
				)
				( attribute "XY" "(2900,1725)"
					( Origin gFrontEnd )
				)
				( attribute "CHIPS_PART_NAME" "CAP_A"
					( Origin gPackager )
				)
				( attribute "CDS_PART_NAME" "CAP_A_0603V-47UF,4V,20%,X5R,60A"
					( Origin gPackager )
				)
				( objectStatus "C2G15" )
				( pin "a"
					( attribute "PN" "1"
						( Origin gPackager )
					)
					( objectStatus "C2G15.1" )
				)
				( pin "b"
					( attribute "PN" "2"
						( Origin gPackager )
					)
					( objectStatus "C2G15.2" )
				)
			)
			( gate "@baseboard_fab2_lib.baseboard_fab2(sch_1):page225_i201"
				( attribute "CDS_LIB" "dev_discrete"
					( Origin gPackager )
				)
				( attribute "CDS_LOCATION" "C2F1"
					( Origin gPackager )
				)
				( attribute "CDS_SEC" "1"
					( Origin gPackager )
				)
				( attribute "LOCATION" "C2F1"
					( Origin gFrontEnd )
				)
				( attribute "MATERIAL" "X5R"
					( Origin gFrontEnd )
				)
				( attribute "PACK_TYPE" "0603V"
					( Origin gFrontEnd )
				)
				( attribute "PART_NUMBER" "602433-106"
					( Origin gFrontEnd )
				)
				( attribute "PHYS_PAGE" "225"
					( Origin gFrontEnd )
				)
				( attribute "ROT" "0"
					( Origin gFrontEnd )
				)
				( attribute "SEC" "1"
					( Origin gFrontEnd )
				)
				( attribute "SEC_TYPE" "0603V"
					( Origin gFrontEnd )
				)
				( attribute "TOLERANCE" "20%"
					( Origin gFrontEnd )
				)
				( attribute "VALUE" "47UF"
					( Origin gFrontEnd )
				)
				( attribute "VER" "1"
					( Origin gFrontEnd )
				)
				( attribute "VOLTAGE" "4V"
					( Units "uVoltage" "V" 1.000000)
					( Origin gFrontEnd )
				)
				( attribute "XY" "(3300,1725)"
					( Origin gFrontEnd )
				)
				( attribute "CHIPS_PART_NAME" "CAP_A"
					( Origin gPackager )
				)
				( attribute "CDS_PART_NAME" "CAP_A_0603V-47UF,4V,20%,X5R,60A"
					( Origin gPackager )
				)
				( objectStatus "C2F1" )
				( pin "a"
					( attribute "PN" "1"
						( Origin gPackager )
					)
					( objectStatus "C2F1.1" )
				)
				( pin "b"
					( attribute "PN" "2"
						( Origin gPackager )
					)
					( objectStatus "C2F1.2" )
				)
			)
			( gate "@baseboard_fab2_lib.baseboard_fab2(sch_1):page225_i202"
				( attribute "CDS_LIB" "dev_discrete"
					( Origin gPackager )
				)
				( attribute "CDS_LOCATION" "C8T1"
					( Origin gPackager )
				)
				( attribute "CDS_SEC" "1"
					( Origin gPackager )
				)
				( attribute "LOCATION" "C8T1"
					( Origin gFrontEnd )
				)
				( attribute "MATERIAL" "X5R"
					( Origin gFrontEnd )
				)
				( attribute "PACK_TYPE" "0603V"
					( Origin gFrontEnd )
				)
				( attribute "PART_NUMBER" "602433-106"
					( Origin gFrontEnd )
				)
				( attribute "PHYS_PAGE" "225"
					( Origin gFrontEnd )
				)
				( attribute "ROT" "0"
					( Origin gFrontEnd )
				)
				( attribute "SEC" "1"
					( Origin gFrontEnd )
				)
				( attribute "SEC_TYPE" "0603V"
					( Origin gFrontEnd )
				)
				( attribute "TOLERANCE" "20%"
					( Origin gFrontEnd )
				)
				( attribute "VALUE" "47UF"
					( Origin gFrontEnd )
				)
				( attribute "VER" "1"
					( Origin gFrontEnd )
				)
				( attribute "VOLTAGE" "4V"
					( Units "uVoltage" "V" 1.000000)
					( Origin gFrontEnd )
				)
				( attribute "XY" "(3650,1725)"
					( Origin gFrontEnd )
				)
				( attribute "CHIPS_PART_NAME" "CAP_A"
					( Origin gPackager )
				)
				( attribute "CDS_PART_NAME" "CAP_A_0603V-47UF,4V,20%,X5R,60A"
					( Origin gPackager )
				)
				( objectStatus "C8T1" )
				( pin "a"
					( attribute "PN" "1"
						( Origin gPackager )
					)
					( objectStatus "C8T1.1" )
				)
				( pin "b"
					( attribute "PN" "2"
						( Origin gPackager )
					)
					( objectStatus "C8T1.2" )
				)
			)
			( gate "@baseboard_fab2_lib.baseboard_fab2(sch_1):page225_i203"
				( attribute "CDS_LIB" "dev_discrete"
					( Origin gPackager )
				)
				( attribute "CDS_LOCATION" "C8U9"
					( Origin gPackager )
				)
				( attribute "CDS_SEC" "1"
					( Origin gPackager )
				)
				( attribute "LOCATION" "C8U9"
					( Origin gFrontEnd )
				)
				( attribute "MATERIAL" "X5R"
					( Origin gFrontEnd )
				)
				( attribute "PACK_TYPE" "0603V"
					( Origin gFrontEnd )
				)
				( attribute "PART_NUMBER" "602433-106"
					( Origin gFrontEnd )
				)
				( attribute "PHYS_PAGE" "225"
					( Origin gFrontEnd )
				)
				( attribute "ROT" "0"
					( Origin gFrontEnd )
				)
				( attribute "SEC" "1"
					( Origin gFrontEnd )
				)
				( attribute "SEC_TYPE" "0603V"
					( Origin gFrontEnd )
				)
				( attribute "TOLERANCE" "20%"
					( Origin gFrontEnd )
				)
				( attribute "VALUE" "47UF"
					( Origin gFrontEnd )
				)
				( attribute "VER" "1"
					( Origin gFrontEnd )
				)
				( attribute "VOLTAGE" "4V"
					( Units "uVoltage" "V" 1.000000)
					( Origin gFrontEnd )
				)
				( attribute "XY" "(4000,1725)"
					( Origin gFrontEnd )
				)
				( attribute "CHIPS_PART_NAME" "CAP_A"
					( Origin gPackager )
				)
				( attribute "CDS_PART_NAME" "CAP_A_0603V-47UF,4V,20%,X5R,60A"
					( Origin gPackager )
				)
				( objectStatus "C8U9" )
				( pin "a"
					( attribute "PN" "1"
						( Origin gPackager )
					)
					( objectStatus "C8U9.1" )
				)
				( pin "b"
					( attribute "PN" "2"
						( Origin gPackager )
					)
					( objectStatus "C8U9.2" )
				)
			)
			( gate "@baseboard_fab2_lib.baseboard_fab2(sch_1):page225_i204"
				( attribute "CDS_LIB" "dev_discrete"
					( Origin gPackager )
				)
				( attribute "CDS_LOCATION" "C8T11"
					( Origin gPackager )
				)
				( attribute "CDS_SEC" "1"
					( Origin gPackager )
				)
				( attribute "LOCATION" "C8T11"
					( Origin gFrontEnd )
				)
				( attribute "MATERIAL" "X5R"
					( Origin gFrontEnd )
				)
				( attribute "PACK_TYPE" "0603V"
					( Origin gFrontEnd )
				)
				( attribute "PART_NUMBER" "602433-106"
					( Origin gFrontEnd )
				)
				( attribute "PHYS_PAGE" "225"
					( Origin gFrontEnd )
				)
				( attribute "ROT" "0"
					( Origin gFrontEnd )
				)
				( attribute "SEC" "1"
					( Origin gFrontEnd )
				)
				( attribute "SEC_TYPE" "0603V"
					( Origin gFrontEnd )
				)
				( attribute "TOLERANCE" "20%"
					( Origin gFrontEnd )
				)
				( attribute "VALUE" "47UF"
					( Origin gFrontEnd )
				)
				( attribute "VER" "1"
					( Origin gFrontEnd )
				)
				( attribute "VOLTAGE" "4V"
					( Units "uVoltage" "V" 1.000000)
					( Origin gFrontEnd )
				)
				( attribute "XY" "(4400,1725)"
					( Origin gFrontEnd )
				)
				( attribute "CHIPS_PART_NAME" "CAP_A"
					( Origin gPackager )
				)
				( attribute "CDS_PART_NAME" "CAP_A_0603V-47UF,4V,20%,X5R,60A"
					( Origin gPackager )
				)
				( objectStatus "C8T11" )
				( pin "a"
					( attribute "PN" "1"
						( Origin gPackager )
					)
					( objectStatus "C8T11.1" )
				)
				( pin "b"
					( attribute "PN" "2"
						( Origin gPackager )
					)
					( objectStatus "C8T11.2" )
				)
			)
			( gate "@baseboard_fab2_lib.baseboard_fab2(sch_1):page225_i207"
				( attribute "CDS_LIB" "dev_discrete"
					( Origin gPackager )
				)
				( attribute "CDS_LOCATION" "C3G6"
					( Origin gPackager )
				)
				( attribute "CDS_SEC" "1"
					( Origin gPackager )
				)
				( attribute "LOCATION" "C3G6"
					( Origin gFrontEnd )
				)
				( attribute "MATERIAL" "X6S"
					( Origin gFrontEnd )
				)
				( attribute "PACK_TYPE" "0603V"
					( Origin gFrontEnd )
				)
				( attribute "PART_NUMBER" "E15431-004"
					( Origin gFrontEnd )
				)
				( attribute "PHYS_PAGE" "225"
					( Origin gFrontEnd )
				)
				( attribute "ROOM" "PVDDQ_GHJ"
					( Origin gFrontEnd )
				)
				( attribute "ROT" "0"
					( Origin gFrontEnd )
				)
				( attribute "SEC" "1"
					( Origin gFrontEnd )
				)
				( attribute "SEC_TYPE" "0603V"
					( Origin gFrontEnd )
				)
				( attribute "TOLERANCE" "20%"
					( Origin gFrontEnd )
				)
				( attribute "VALUE" "22.0UF"
					( Origin gFrontEnd )
				)
				( attribute "VER" "1"
					( Origin gFrontEnd )
				)
				( attribute "VOLTAGE" "4V"
					( Units "uVoltage" "V" 1.000000)
					( Origin gFrontEnd )
				)
				( attribute "XY" "(2100,250)"
					( Origin gFrontEnd )
				)
				( attribute "CHIPS_PART_NAME" "CAP_A"
					( Origin gPackager )
				)
				( attribute "CDS_PART_NAME" "CAP_A_0603V-22.0UF,4V,20%,X6S,A"
					( Origin gPackager )
				)
				( objectStatus "C3G6" )
				( pin "a"
					( attribute "PN" "1"
						( Origin gPackager )
					)
					( objectStatus "C3G6.1" )
				)
				( pin "b"
					( attribute "PN" "2"
						( Origin gPackager )
					)
					( objectStatus "C3G6.2" )
				)
			)
			( gate "@baseboard_fab2_lib.baseboard_fab2(sch_1):page225_i208"
				( attribute "CDS_LIB" "dev_discrete"
					( Origin gPackager )
				)
				( attribute "CDS_LOCATION" "C3G5"
					( Origin gPackager )
				)
				( attribute "CDS_SEC" "1"
					( Origin gPackager )
				)
				( attribute "LOCATION" "C3G5"
					( Origin gFrontEnd )
				)
				( attribute "MATERIAL" "X6S"
					( Origin gFrontEnd )
				)
				( attribute "PACK_TYPE" "0603V"
					( Origin gFrontEnd )
				)
				( attribute "PART_NUMBER" "E15431-004"
					( Origin gFrontEnd )
				)
				( attribute "PHYS_PAGE" "225"
					( Origin gFrontEnd )
				)
				( attribute "ROOM" "PVDDQ_GHJ"
					( Origin gFrontEnd )
				)
				( attribute "ROT" "0"
					( Origin gFrontEnd )
				)
				( attribute "SEC" "1"
					( Origin gFrontEnd )
				)
				( attribute "SEC_TYPE" "0603V"
					( Origin gFrontEnd )
				)
				( attribute "TOLERANCE" "20%"
					( Origin gFrontEnd )
				)
				( attribute "VALUE" "22.0UF"
					( Origin gFrontEnd )
				)
				( attribute "VER" "1"
					( Origin gFrontEnd )
				)
				( attribute "VOLTAGE" "4V"
					( Units "uVoltage" "V" 1.000000)
					( Origin gFrontEnd )
				)
				( attribute "XY" "(1825,250)"
					( Origin gFrontEnd )
				)
				( attribute "CHIPS_PART_NAME" "CAP_A"
					( Origin gPackager )
				)
				( attribute "CDS_PART_NAME" "CAP_A_0603V-22.0UF,4V,20%,X6S,A"
					( Origin gPackager )
				)
				( objectStatus "C3G5" )
				( pin "a"
					( attribute "PN" "1"
						( Origin gPackager )
					)
					( objectStatus "C3G5.1" )
				)
				( pin "b"
					( attribute "PN" "2"
						( Origin gPackager )
					)
					( objectStatus "C3G5.2" )
				)
			)
			( gate "@baseboard_fab2_lib.baseboard_fab2(sch_1):page225_i209"
				( attribute "CDS_LIB" "dev_discrete"
					( Origin gPackager )
				)
				( attribute "CDS_LOCATION" "C2G14"
					( Origin gPackager )
				)
				( attribute "CDS_SEC" "1"
					( Origin gPackager )
				)
				( attribute "LOCATION" "C2G14"
					( Origin gFrontEnd )
				)
				( attribute "MATERIAL" "X6S"
					( Origin gFrontEnd )
				)
				( attribute "PACK_TYPE" "0603V"
					( Origin gFrontEnd )
				)
				( attribute "PART_NUMBER" "E15431-004"
					( Origin gFrontEnd )
				)
				( attribute "PHYS_PAGE" "225"
					( Origin gFrontEnd )
				)
				( attribute "ROOM" "PVDDQ_GHJ"
					( Origin gFrontEnd )
				)
				( attribute "ROT" "0"
					( Origin gFrontEnd )
				)
				( attribute "SEC" "1"
					( Origin gFrontEnd )
				)
				( attribute "SEC_TYPE" "0603V"
					( Origin gFrontEnd )
				)
				( attribute "TOLERANCE" "20%"
					( Origin gFrontEnd )
				)
				( attribute "VALUE" "22.0UF"
					( Origin gFrontEnd )
				)
				( attribute "VER" "1"
					( Origin gFrontEnd )
				)
				( attribute "VOLTAGE" "4V"
					( Units "uVoltage" "V" 1.000000)
					( Origin gFrontEnd )
				)
				( attribute "XY" "(1525,250)"
					( Origin gFrontEnd )
				)
				( attribute "CHIPS_PART_NAME" "CAP_A"
					( Origin gPackager )
				)
				( attribute "CDS_PART_NAME" "CAP_A_0603V-22.0UF,4V,20%,X6S,A"
					( Origin gPackager )
				)
				( objectStatus "C2G14" )
				( pin "a"
					( attribute "PN" "1"
						( Origin gPackager )
					)
					( objectStatus "C2G14.1" )
				)
				( pin "b"
					( attribute "PN" "2"
						( Origin gPackager )
					)
					( objectStatus "C2G14.2" )
				)
			)
			( gate "@baseboard_fab2_lib.baseboard_fab2(sch_1):page225_i210"
				( attribute "CDS_LIB" "dev_discrete"
					( Origin gPackager )
				)
				( attribute "CDS_LOCATION" "C2G13"
					( Origin gPackager )
				)
				( attribute "CDS_SEC" "1"
					( Origin gPackager )
				)
				( attribute "LOCATION" "C2G13"
					( Origin gFrontEnd )
				)
				( attribute "MATERIAL" "X6S"
					( Origin gFrontEnd )
				)
				( attribute "PACK_TYPE" "0603V"
					( Origin gFrontEnd )
				)
				( attribute "PART_NUMBER" "E15431-004"
					( Origin gFrontEnd )
				)
				( attribute "PHYS_PAGE" "225"
					( Origin gFrontEnd )
				)
				( attribute "ROOM" "PVDDQ_GHJ"
					( Origin gFrontEnd )
				)
				( attribute "ROT" "0"
					( Origin gFrontEnd )
				)
				( attribute "SEC" "1"
					( Origin gFrontEnd )
				)
				( attribute "SEC_TYPE" "0603V"
					( Origin gFrontEnd )
				)
				( attribute "TOLERANCE" "20%"
					( Origin gFrontEnd )
				)
				( attribute "VALUE" "22.0UF"
					( Origin gFrontEnd )
				)
				( attribute "VER" "1"
					( Origin gFrontEnd )
				)
				( attribute "VOLTAGE" "4V"
					( Units "uVoltage" "V" 1.000000)
					( Origin gFrontEnd )
				)
				( attribute "XY" "(1225,250)"
					( Origin gFrontEnd )
				)
				( attribute "CHIPS_PART_NAME" "CAP_A"
					( Origin gPackager )
				)
				( attribute "CDS_PART_NAME" "CAP_A_0603V-22.0UF,4V,20%,X6S,A"
					( Origin gPackager )
				)
				( objectStatus "C2G13" )
				( pin "a"
					( attribute "PN" "1"
						( Origin gPackager )
					)
					( objectStatus "C2G13.1" )
				)
				( pin "b"
					( attribute "PN" "2"
						( Origin gPackager )
					)
					( objectStatus "C2G13.2" )
				)
			)
			( gate "@baseboard_fab2_lib.baseboard_fab2(sch_1):page225_i211"
				( attribute "CDS_LIB" "dev_discrete"
					( Origin gPackager )
				)
				( attribute "CDS_LOCATION" "C3G2"
					( Origin gPackager )
				)
				( attribute "CDS_SEC" "1"
					( Origin gPackager )
				)
				( attribute "LOCATION" "C3G2"
					( Origin gFrontEnd )
				)
				( attribute "MATERIAL" "X6S"
					( Origin gFrontEnd )
				)
				( attribute "PACK_TYPE" "0603V"
					( Origin gFrontEnd )
				)
				( attribute "PART_NUMBER" "E15431-004"
					( Origin gFrontEnd )
				)
				( attribute "PHYS_PAGE" "225"
					( Origin gFrontEnd )
				)
				( attribute "ROOM" "PVDDQ_GHJ"
					( Origin gFrontEnd )
				)
				( attribute "ROT" "0"
					( Origin gFrontEnd )
				)
				( attribute "SEC" "1"
					( Origin gFrontEnd )
				)
				( attribute "SEC_TYPE" "0603V"
					( Origin gFrontEnd )
				)
				( attribute "TOLERANCE" "20%"
					( Origin gFrontEnd )
				)
				( attribute "VALUE" "22.0UF"
					( Origin gFrontEnd )
				)
				( attribute "VER" "1"
					( Origin gFrontEnd )
				)
				( attribute "VOLTAGE" "4V"
					( Units "uVoltage" "V" 1.000000)
					( Origin gFrontEnd )
				)
				( attribute "XY" "(950,250)"
					( Origin gFrontEnd )
				)
				( attribute "CHIPS_PART_NAME" "CAP_A"
					( Origin gPackager )
				)
				( attribute "CDS_PART_NAME" "CAP_A_0603V-22.0UF,4V,20%,X6S,A"
					( Origin gPackager )
				)
				( objectStatus "C3G2" )
				( pin "a"
					( attribute "PN" "1"
						( Origin gPackager )
					)
					( objectStatus "C3G2.1" )
				)
				( pin "b"
					( attribute "PN" "2"
						( Origin gPackager )
					)
					( objectStatus "C3G2.2" )
				)
			)
			( gate "@baseboard_fab2_lib.baseboard_fab2(sch_1):page225_i212"
				( attribute "CDS_LIB" "dev_discrete"
					( Origin gPackager )
				)
				( attribute "CDS_LOCATION" "C3G1"
					( Origin gPackager )
				)
				( attribute "CDS_SEC" "1"
					( Origin gPackager )
				)
				( attribute "LOCATION" "C3G1"
					( Origin gFrontEnd )
				)
				( attribute "MATERIAL" "X6S"
					( Origin gFrontEnd )
				)
				( attribute "PACK_TYPE" "0603V"
					( Origin gFrontEnd )
				)
				( attribute "PART_NUMBER" "E15431-004"
					( Origin gFrontEnd )
				)
				( attribute "PHYS_PAGE" "225"
					( Origin gFrontEnd )
				)
				( attribute "ROOM" "PVDDQ_GHJ"
					( Origin gFrontEnd )
				)
				( attribute "ROT" "0"
					( Origin gFrontEnd )
				)
				( attribute "SEC" "1"
					( Origin gFrontEnd )
				)
				( attribute "SEC_TYPE" "0603V"
					( Origin gFrontEnd )
				)
				( attribute "TOLERANCE" "20%"
					( Origin gFrontEnd )
				)
				( attribute "VALUE" "22.0UF"
					( Origin gFrontEnd )
				)
				( attribute "VER" "1"
					( Origin gFrontEnd )
				)
				( attribute "VOLTAGE" "4V"
					( Units "uVoltage" "V" 1.000000)
					( Origin gFrontEnd )
				)
				( attribute "XY" "(675,250)"
					( Origin gFrontEnd )
				)
				( attribute "CHIPS_PART_NAME" "CAP_A"
					( Origin gPackager )
				)
				( attribute "CDS_PART_NAME" "CAP_A_0603V-22.0UF,4V,20%,X6S,A"
					( Origin gPackager )
				)
				( objectStatus "C3G1" )
				( pin "a"
					( attribute "PN" "1"
						( Origin gPackager )
					)
					( objectStatus "C3G1.1" )
				)
				( pin "b"
					( attribute "PN" "2"
						( Origin gPackager )
					)
					( objectStatus "C3G1.2" )
				)
			)
			( gate "@baseboard_fab2_lib.baseboard_fab2(sch_1):page225_i213"
				( attribute "CDS_LIB" "dev_discrete"
					( Origin gPackager )
				)
				( attribute "CDS_LOCATION" "C2G6"
					( Origin gPackager )
				)
				( attribute "CDS_SEC" "1"
					( Origin gPackager )
				)
				( attribute "LOCATION" "C2G6"
					( Origin gFrontEnd )
				)
				( attribute "MATERIAL" "X6S"
					( Origin gFrontEnd )
				)
				( attribute "PACK_TYPE" "0603V"
					( Origin gFrontEnd )
				)
				( attribute "PART_NUMBER" "E15431-004"
					( Origin gFrontEnd )
				)
				( attribute "PHYS_PAGE" "225"
					( Origin gFrontEnd )
				)
				( attribute "ROOM" "PVDDQ_GHJ"
					( Origin gFrontEnd )
				)
				( attribute "ROT" "0"
					( Origin gFrontEnd )
				)
				( attribute "SEC" "1"
					( Origin gFrontEnd )
				)
				( attribute "SEC_TYPE" "0603V"
					( Origin gFrontEnd )
				)
				( attribute "TOLERANCE" "20%"
					( Origin gFrontEnd )
				)
				( attribute "VALUE" "22.0UF"
					( Origin gFrontEnd )
				)
				( attribute "VER" "1"
					( Origin gFrontEnd )
				)
				( attribute "VOLTAGE" "4V"
					( Units "uVoltage" "V" 1.000000)
					( Origin gFrontEnd )
				)
				( attribute "XY" "(375,250)"
					( Origin gFrontEnd )
				)
				( attribute "CHIPS_PART_NAME" "CAP_A"
					( Origin gPackager )
				)
				( attribute "CDS_PART_NAME" "CAP_A_0603V-22.0UF,4V,20%,X6S,A"
					( Origin gPackager )
				)
				( objectStatus "C2G6" )
				( pin "a"
					( attribute "PN" "1"
						( Origin gPackager )
					)
					( objectStatus "C2G6.1" )
				)
				( pin "b"
					( attribute "PN" "2"
						( Origin gPackager )
					)
					( objectStatus "C2G6.2" )
				)
			)
			( gate "@baseboard_fab2_lib.baseboard_fab2(sch_1):page225_i214"
				( attribute "CDS_LIB" "dev_discrete"
					( Origin gPackager )
				)
				( attribute "CDS_LOCATION" "C2G5"
					( Origin gPackager )
				)
				( attribute "CDS_SEC" "1"
					( Origin gPackager )
				)
				( attribute "LOCATION" "C2G5"
					( Origin gFrontEnd )
				)
				( attribute "MATERIAL" "X6S"
					( Origin gFrontEnd )
				)
				( attribute "PACK_TYPE" "0603V"
					( Origin gFrontEnd )
				)
				( attribute "PART_NUMBER" "E15431-004"
					( Origin gFrontEnd )
				)
				( attribute "PHYS_PAGE" "225"
					( Origin gFrontEnd )
				)
				( attribute "ROOM" "PVDDQ_GHJ"
					( Origin gFrontEnd )
				)
				( attribute "ROT" "0"
					( Origin gFrontEnd )
				)
				( attribute "SEC" "1"
					( Origin gFrontEnd )
				)
				( attribute "SEC_TYPE" "0603V"
					( Origin gFrontEnd )
				)
				( attribute "TOLERANCE" "20%"
					( Origin gFrontEnd )
				)
				( attribute "VALUE" "22.0UF"
					( Origin gFrontEnd )
				)
				( attribute "VER" "1"
					( Origin gFrontEnd )
				)
				( attribute "VOLTAGE" "4V"
					( Units "uVoltage" "V" 1.000000)
					( Origin gFrontEnd )
				)
				( attribute "XY" "(75,250)"
					( Origin gFrontEnd )
				)
				( attribute "CHIPS_PART_NAME" "CAP_A"
					( Origin gPackager )
				)
				( attribute "CDS_PART_NAME" "CAP_A_0603V-22.0UF,4V,20%,X6S,A"
					( Origin gPackager )
				)
				( objectStatus "C2G5" )
				( pin "a"
					( attribute "PN" "1"
						( Origin gPackager )
					)
					( objectStatus "C2G5.1" )
				)
				( pin "b"
					( attribute "PN" "2"
						( Origin gPackager )
					)
					( objectStatus "C2G5.2" )
				)
			)
			( gate "@baseboard_fab2_lib.baseboard_fab2(sch_1):page225_i215"
				( attribute "CDS_LIB" "dev_discrete"
					( Origin gPackager )
				)
				( attribute "CDS_LOCATION" "C2G4"
					( Origin gPackager )
				)
				( attribute "CDS_SEC" "1"
					( Origin gPackager )
				)
				( attribute "LOCATION" "C2G4"
					( Origin gFrontEnd )
				)
				( attribute "MATERIAL" "X6S"
					( Origin gFrontEnd )
				)
				( attribute "PACK_TYPE" "0603V"
					( Origin gFrontEnd )
				)
				( attribute "PART_NUMBER" "E15431-004"
					( Origin gFrontEnd )
				)
				( attribute "PHYS_PAGE" "225"
					( Origin gFrontEnd )
				)
				( attribute "ROOM" "PVDDQ_GHJ"
					( Origin gFrontEnd )
				)
				( attribute "ROT" "0"
					( Origin gFrontEnd )
				)
				( attribute "SEC" "1"
					( Origin gFrontEnd )
				)
				( attribute "SEC_TYPE" "0603V"
					( Origin gFrontEnd )
				)
				( attribute "TOLERANCE" "20%"
					( Origin gFrontEnd )
				)
				( attribute "VALUE" "22.0UF"
					( Origin gFrontEnd )
				)
				( attribute "VER" "1"
					( Origin gFrontEnd )
				)
				( attribute "VOLTAGE" "4V"
					( Units "uVoltage" "V" 1.000000)
					( Origin gFrontEnd )
				)
				( attribute "XY" "(-250,250)"
					( Origin gFrontEnd )
				)
				( attribute "CHIPS_PART_NAME" "CAP_A"
					( Origin gPackager )
				)
				( attribute "CDS_PART_NAME" "CAP_A_0603V-22.0UF,4V,20%,X6S,A"
					( Origin gPackager )
				)
				( objectStatus "C2G4" )
				( pin "a"
					( attribute "PN" "1"
						( Origin gPackager )
					)
					( objectStatus "C2G4.1" )
				)
				( pin "b"
					( attribute "PN" "2"
						( Origin gPackager )
					)
					( objectStatus "C2G4.2" )
				)
			)
			( gate "@baseboard_fab2_lib.baseboard_fab2(sch_1):page225_i216"
				( attribute "CDS_LIB" "dev_discrete"
					( Origin gPackager )
				)
				( attribute "CDS_LOCATION" "C2G3"
					( Origin gPackager )
				)
				( attribute "CDS_SEC" "1"
					( Origin gPackager )
				)
				( attribute "LOCATION" "C2G3"
					( Origin gFrontEnd )
				)
				( attribute "MATERIAL" "X6S"
					( Origin gFrontEnd )
				)
				( attribute "PACK_TYPE" "0603V"
					( Origin gFrontEnd )
				)
				( attribute "PART_NUMBER" "E15431-004"
					( Origin gFrontEnd )
				)
				( attribute "PHYS_PAGE" "225"
					( Origin gFrontEnd )
				)
				( attribute "ROOM" "PVDDQ_GHJ"
					( Origin gFrontEnd )
				)
				( attribute "ROT" "0"
					( Origin gFrontEnd )
				)
				( attribute "SEC" "1"
					( Origin gFrontEnd )
				)
				( attribute "SEC_TYPE" "0603V"
					( Origin gFrontEnd )
				)
				( attribute "TOLERANCE" "20%"
					( Origin gFrontEnd )
				)
				( attribute "VALUE" "22.0UF"
					( Origin gFrontEnd )
				)
				( attribute "VER" "1"
					( Origin gFrontEnd )
				)
				( attribute "VOLTAGE" "4V"
					( Units "uVoltage" "V" 1.000000)
					( Origin gFrontEnd )
				)
				( attribute "XY" "(-525,250)"
					( Origin gFrontEnd )
				)
				( attribute "CHIPS_PART_NAME" "CAP_A"
					( Origin gPackager )
				)
				( attribute "CDS_PART_NAME" "CAP_A_0603V-22.0UF,4V,20%,X6S,A"
					( Origin gPackager )
				)
				( objectStatus "C2G3" )
				( pin "a"
					( attribute "PN" "1"
						( Origin gPackager )
					)
					( objectStatus "C2G3.1" )
				)
				( pin "b"
					( attribute "PN" "2"
						( Origin gPackager )
					)
					( objectStatus "C2G3.2" )
				)
			)
			( gate "@baseboard_fab2_lib.baseboard_fab2(sch_1):page225_i217"
				( attribute "CDS_LIB" "dev_discrete"
					( Origin gPackager )
				)
				( attribute "CDS_LOCATION" "C2G2"
					( Origin gPackager )
				)
				( attribute "CDS_SEC" "1"
					( Origin gPackager )
				)
				( attribute "LOCATION" "C2G2"
					( Origin gFrontEnd )
				)
				( attribute "MATERIAL" "X6S"
					( Origin gFrontEnd )
				)
				( attribute "PACK_TYPE" "0603V"
					( Origin gFrontEnd )
				)
				( attribute "PART_NUMBER" "E15431-004"
					( Origin gFrontEnd )
				)
				( attribute "PHYS_PAGE" "225"
					( Origin gFrontEnd )
				)
				( attribute "ROOM" "PVDDQ_GHJ"
					( Origin gFrontEnd )
				)
				( attribute "ROT" "0"
					( Origin gFrontEnd )
				)
				( attribute "SEC" "1"
					( Origin gFrontEnd )
				)
				( attribute "SEC_TYPE" "0603V"
					( Origin gFrontEnd )
				)
				( attribute "TOLERANCE" "20%"
					( Origin gFrontEnd )
				)
				( attribute "VALUE" "22.0UF"
					( Origin gFrontEnd )
				)
				( attribute "VER" "1"
					( Origin gFrontEnd )
				)
				( attribute "VOLTAGE" "4V"
					( Units "uVoltage" "V" 1.000000)
					( Origin gFrontEnd )
				)
				( attribute "XY" "(-825,250)"
					( Origin gFrontEnd )
				)
				( attribute "CHIPS_PART_NAME" "CAP_A"
					( Origin gPackager )
				)
				( attribute "CDS_PART_NAME" "CAP_A_0603V-22.0UF,4V,20%,X6S,A"
					( Origin gPackager )
				)
				( objectStatus "C2G2" )
				( pin "a"
					( attribute "PN" "1"
						( Origin gPackager )
					)
					( objectStatus "C2G2.1" )
				)
				( pin "b"
					( attribute "PN" "2"
						( Origin gPackager )
					)
					( objectStatus "C2G2.2" )
				)
			)
			( gate "@baseboard_fab2_lib.baseboard_fab2(sch_1):page225_i218"
				( attribute "CDS_LIB" "dev_discrete"
					( Origin gPackager )
				)
				( attribute "CDS_LOCATION" "C2G9"
					( Origin gPackager )
				)
				( attribute "CDS_SEC" "1"
					( Origin gPackager )
				)
				( attribute "LOCATION" "C2G9"
					( Origin gFrontEnd )
				)
				( attribute "MATERIAL" "X6S"
					( Origin gFrontEnd )
				)
				( attribute "PACK_TYPE" "0603V"
					( Origin gFrontEnd )
				)
				( attribute "PART_NUMBER" "E15431-004"
					( Origin gFrontEnd )
				)
				( attribute "PHYS_PAGE" "225"
					( Origin gFrontEnd )
				)
				( attribute "ROOM" "PVDDQ_ABC"
					( Origin gFrontEnd )
				)
				( attribute "ROT" "0"
					( Origin gFrontEnd )
				)
				( attribute "SEC" "1"
					( Origin gFrontEnd )
				)
				( attribute "SEC_TYPE" "0603V"
					( Origin gFrontEnd )
				)
				( attribute "TOLERANCE" "20%"
					( Origin gFrontEnd )
				)
				( attribute "VALUE" "22.0UF"
					( Origin gFrontEnd )
				)
				( attribute "VER" "1"
					( Origin gFrontEnd )
				)
				( attribute "VOLTAGE" "4V"
					( Units "uVoltage" "V" 1.000000)
					( Origin gFrontEnd )
				)
				( attribute "XY" "(-1125,250)"
					( Origin gFrontEnd )
				)
				( attribute "CHIPS_PART_NAME" "CAP_A"
					( Origin gPackager )
				)
				( attribute "CDS_PART_NAME" "CAP_A_0603V-22.0UF,4V,20%,X6S,A"
					( Origin gPackager )
				)
				( objectStatus "C2G9" )
				( pin "a"
					( attribute "PN" "1"
						( Origin gPackager )
					)
					( objectStatus "C2G9.1" )
				)
				( pin "b"
					( attribute "PN" "2"
						( Origin gPackager )
					)
					( objectStatus "C2G9.2" )
				)
			)
			( gate "@baseboard_fab2_lib.baseboard_fab2(sch_1):page225_i219"
				( attribute "CDS_LIB" "dev_discrete"
					( Origin gPackager )
				)
				( attribute "CDS_LOCATION" "C2G1"
					( Origin gPackager )
				)
				( attribute "CDS_SEC" "1"
					( Origin gPackager )
				)
				( attribute "LOCATION" "C2G1"
					( Origin gFrontEnd )
				)
				( attribute "MATERIAL" "X6S"
					( Origin gFrontEnd )
				)
				( attribute "PACK_TYPE" "0603V"
					( Origin gFrontEnd )
				)
				( attribute "PART_NUMBER" "E15431-004"
					( Origin gFrontEnd )
				)
				( attribute "PHYS_PAGE" "225"
					( Origin gFrontEnd )
				)
				( attribute "ROOM" "PVDDQ_GHJ"
					( Origin gFrontEnd )
				)
				( attribute "ROT" "0"
					( Origin gFrontEnd )
				)
				( attribute "SEC" "1"
					( Origin gFrontEnd )
				)
				( attribute "SEC_TYPE" "0603V"
					( Origin gFrontEnd )
				)
				( attribute "TOLERANCE" "20%"
					( Origin gFrontEnd )
				)
				( attribute "VALUE" "22.0UF"
					( Origin gFrontEnd )
				)
				( attribute "VER" "1"
					( Origin gFrontEnd )
				)
				( attribute "VOLTAGE" "4V"
					( Units "uVoltage" "V" 1.000000)
					( Origin gFrontEnd )
				)
				( attribute "XY" "(-1400,250)"
					( Origin gFrontEnd )
				)
				( attribute "CHIPS_PART_NAME" "CAP_A"
					( Origin gPackager )
				)
				( attribute "CDS_PART_NAME" "CAP_A_0603V-22.0UF,4V,20%,X6S,A"
					( Origin gPackager )
				)
				( objectStatus "C2G1" )
				( pin "a"
					( attribute "PN" "1"
						( Origin gPackager )
					)
					( objectStatus "C2G1.1" )
				)
				( pin "b"
					( attribute "PN" "2"
						( Origin gPackager )
					)
					( objectStatus "C2G1.2" )
				)
			)
			( gate "@baseboard_fab2_lib.baseboard_fab2(sch_1):page225_i220"
				( attribute "CDS_LIB" "dev_discrete"
					( Origin gPackager )
				)
				( attribute "CDS_LOCATION" "C2G12"
					( Origin gPackager )
				)
				( attribute "CDS_SEC" "1"
					( Origin gPackager )
				)
				( attribute "LOCATION" "C2G12"
					( Origin gFrontEnd )
				)
				( attribute "MATERIAL" "X6S"
					( Origin gFrontEnd )
				)
				( attribute "PACK_TYPE" "0603V"
					( Origin gFrontEnd )
				)
				( attribute "PART_NUMBER" "E15431-004"
					( Origin gFrontEnd )
				)
				( attribute "PHYS_PAGE" "225"
					( Origin gFrontEnd )
				)
				( attribute "ROOM" "PVDDQ_GHJ"
					( Origin gFrontEnd )
				)
				( attribute "ROT" "0"
					( Origin gFrontEnd )
				)
				( attribute "SEC" "1"
					( Origin gFrontEnd )
				)
				( attribute "SEC_TYPE" "0603V"
					( Origin gFrontEnd )
				)
				( attribute "TOLERANCE" "20%"
					( Origin gFrontEnd )
				)
				( attribute "VALUE" "22.0UF"
					( Origin gFrontEnd )
				)
				( attribute "VER" "1"
					( Origin gFrontEnd )
				)
				( attribute "VOLTAGE" "4V"
					( Units "uVoltage" "V" 1.000000)
					( Origin gFrontEnd )
				)
				( attribute "XY" "(-1675,250)"
					( Origin gFrontEnd )
				)
				( attribute "CHIPS_PART_NAME" "CAP_A"
					( Origin gPackager )
				)
				( attribute "CDS_PART_NAME" "CAP_A_0603V-22.0UF,4V,20%,X6S,A"
					( Origin gPackager )
				)
				( objectStatus "C2G12" )
				( pin "a"
					( attribute "PN" "1"
						( Origin gPackager )
					)
					( objectStatus "C2G12.1" )
				)
				( pin "b"
					( attribute "PN" "2"
						( Origin gPackager )
					)
					( objectStatus "C2G12.2" )
				)
			)
			( gate "@baseboard_fab2_lib.baseboard_fab2(sch_1):page225_i221"
				( attribute "CDS_LIB" "dev_discrete"
					( Origin gPackager )
				)
				( attribute "CDS_LOCATION" "C2G11"
					( Origin gPackager )
				)
				( attribute "CDS_SEC" "1"
					( Origin gPackager )
				)
				( attribute "LOCATION" "C2G11"
					( Origin gFrontEnd )
				)
				( attribute "MATERIAL" "X6S"
					( Origin gFrontEnd )
				)
				( attribute "PACK_TYPE" "0603V"
					( Origin gFrontEnd )
				)
				( attribute "PART_NUMBER" "E15431-004"
					( Origin gFrontEnd )
				)
				( attribute "PHYS_PAGE" "225"
					( Origin gFrontEnd )
				)
				( attribute "ROOM" "PVDDQ_GHJ"
					( Origin gFrontEnd )
				)
				( attribute "ROT" "0"
					( Origin gFrontEnd )
				)
				( attribute "SEC" "1"
					( Origin gFrontEnd )
				)
				( attribute "SEC_TYPE" "0603V"
					( Origin gFrontEnd )
				)
				( attribute "TOLERANCE" "20%"
					( Origin gFrontEnd )
				)
				( attribute "VALUE" "22.0UF"
					( Origin gFrontEnd )
				)
				( attribute "VER" "1"
					( Origin gFrontEnd )
				)
				( attribute "VOLTAGE" "4V"
					( Units "uVoltage" "V" 1.000000)
					( Origin gFrontEnd )
				)
				( attribute "XY" "(-1975,250)"
					( Origin gFrontEnd )
				)
				( attribute "CHIPS_PART_NAME" "CAP_A"
					( Origin gPackager )
				)
				( attribute "CDS_PART_NAME" "CAP_A_0603V-22.0UF,4V,20%,X6S,A"
					( Origin gPackager )
				)
				( objectStatus "C2G11" )
				( pin "a"
					( attribute "PN" "1"
						( Origin gPackager )
					)
					( objectStatus "C2G11.1" )
				)
				( pin "b"
					( attribute "PN" "2"
						( Origin gPackager )
					)
					( objectStatus "C2G11.2" )
				)
			)
			( gate "@baseboard_fab2_lib.baseboard_fab2(sch_1):page225_i223"
				( attribute "CDS_LIB" "dev_discrete"
					( Origin gPackager )
				)
				( attribute "CDS_LOCATION" "C2G10"
					( Origin gPackager )
				)
				( attribute "CDS_SEC" "1"
					( Origin gPackager )
				)
				( attribute "LOCATION" "C2G10"
					( Origin gFrontEnd )
				)
				( attribute "MATERIAL" "X6S"
					( Origin gFrontEnd )
				)
				( attribute "PACK_TYPE" "0603V"
					( Origin gFrontEnd )
				)
				( attribute "PART_NUMBER" "E15431-004"
					( Origin gFrontEnd )
				)
				( attribute "PHYS_PAGE" "225"
					( Origin gFrontEnd )
				)
				( attribute "ROOM" "PVDDQ_GHJ"
					( Origin gFrontEnd )
				)
				( attribute "ROT" "0"
					( Origin gFrontEnd )
				)
				( attribute "SEC" "1"
					( Origin gFrontEnd )
				)
				( attribute "SEC_TYPE" "0603V"
					( Origin gFrontEnd )
				)
				( attribute "TOLERANCE" "20%"
					( Origin gFrontEnd )
				)
				( attribute "VALUE" "22.0UF"
					( Origin gFrontEnd )
				)
				( attribute "VER" "1"
					( Origin gFrontEnd )
				)
				( attribute "VOLTAGE" "4V"
					( Units "uVoltage" "V" 1.000000)
					( Origin gFrontEnd )
				)
				( attribute "XY" "(-2275,250)"
					( Origin gFrontEnd )
				)
				( attribute "CHIPS_PART_NAME" "CAP_A"
					( Origin gPackager )
				)
				( attribute "CDS_PART_NAME" "CAP_A_0603V-22.0UF,4V,20%,X6S,A"
					( Origin gPackager )
				)
				( objectStatus "C2G10" )
				( pin "a"
					( attribute "PN" "1"
						( Origin gPackager )
					)
					( objectStatus "C2G10.1" )
				)
				( pin "b"
					( attribute "PN" "2"
						( Origin gPackager )
					)
					( objectStatus "C2G10.2" )
				)
			)
			( gate "@baseboard_fab2_lib.baseboard_fab2(sch_1):page225_i225"
				( attribute "CDS_LIB" "dev_discrete"
					( Origin gPackager )
				)
				( attribute "CDS_LOCATION" "C8U4"
					( Origin gPackager )
				)
				( attribute "CDS_SEC" "1"
					( Origin gPackager )
				)
				( attribute "LOCATION" "C8U4"
					( Origin gFrontEnd )
				)
				( attribute "MATERIAL" "X6S"
					( Origin gFrontEnd )
				)
				( attribute "PACK_TYPE" "0603V"
					( Origin gFrontEnd )
				)
				( attribute "PART_NUMBER" "E15431-004"
					( Origin gFrontEnd )
				)
				( attribute "PHYS_PAGE" "225"
					( Origin gFrontEnd )
				)
				( attribute "ROOM" "PVDDQ_GHJ"
					( Origin gFrontEnd )
				)
				( attribute "ROT" "0"
					( Origin gFrontEnd )
				)
				( attribute "SEC" "1"
					( Origin gFrontEnd )
				)
				( attribute "SEC_TYPE" "0603V"
					( Origin gFrontEnd )
				)
				( attribute "TOLERANCE" "20%"
					( Origin gFrontEnd )
				)
				( attribute "VALUE" "22.0UF"
					( Origin gFrontEnd )
				)
				( attribute "VER" "1"
					( Origin gFrontEnd )
				)
				( attribute "VOLTAGE" "4V"
					( Units "uVoltage" "V" 1.000000)
					( Origin gFrontEnd )
				)
				( attribute "XY" "(2125,-450)"
					( Origin gFrontEnd )
				)
				( attribute "CHIPS_PART_NAME" "CAP_A"
					( Origin gPackager )
				)
				( attribute "CDS_PART_NAME" "CAP_A_0603V-22.0UF,4V,20%,X6S,A"
					( Origin gPackager )
				)
				( objectStatus "C8U4" )
				( pin "a"
					( attribute "PN" "1"
						( Origin gPackager )
					)
					( objectStatus "C8U4.1" )
				)
				( pin "b"
					( attribute "PN" "2"
						( Origin gPackager )
					)
					( objectStatus "C8U4.2" )
				)
			)
			( gate "@baseboard_fab2_lib.baseboard_fab2(sch_1):page225_i226"
				( attribute "CDS_LIB" "dev_discrete"
					( Origin gPackager )
				)
				( attribute "CDS_LOCATION" "C8T10"
					( Origin gPackager )
				)
				( attribute "CDS_SEC" "1"
					( Origin gPackager )
				)
				( attribute "LOCATION" "C8T10"
					( Origin gFrontEnd )
				)
				( attribute "MATERIAL" "X6S"
					( Origin gFrontEnd )
				)
				( attribute "PACK_TYPE" "0603V"
					( Origin gFrontEnd )
				)
				( attribute "PART_NUMBER" "E15431-004"
					( Origin gFrontEnd )
				)
				( attribute "PHYS_PAGE" "225"
					( Origin gFrontEnd )
				)
				( attribute "ROOM" "PVDDQ_GHJ"
					( Origin gFrontEnd )
				)
				( attribute "ROT" "0"
					( Origin gFrontEnd )
				)
				( attribute "SEC" "1"
					( Origin gFrontEnd )
				)
				( attribute "SEC_TYPE" "0603V"
					( Origin gFrontEnd )
				)
				( attribute "TOLERANCE" "20%"
					( Origin gFrontEnd )
				)
				( attribute "VALUE" "22.0UF"
					( Origin gFrontEnd )
				)
				( attribute "VER" "1"
					( Origin gFrontEnd )
				)
				( attribute "VOLTAGE" "4V"
					( Units "uVoltage" "V" 1.000000)
					( Origin gFrontEnd )
				)
				( attribute "XY" "(1850,-450)"
					( Origin gFrontEnd )
				)
				( attribute "CHIPS_PART_NAME" "CAP_A"
					( Origin gPackager )
				)
				( attribute "CDS_PART_NAME" "CAP_A_0603V-22.0UF,4V,20%,X6S,A"
					( Origin gPackager )
				)
				( objectStatus "C8T10" )
				( pin "a"
					( attribute "PN" "1"
						( Origin gPackager )
					)
					( objectStatus "C8T10.1" )
				)
				( pin "b"
					( attribute "PN" "2"
						( Origin gPackager )
					)
					( objectStatus "C8T10.2" )
				)
			)
			( gate "@baseboard_fab2_lib.baseboard_fab2(sch_1):page225_i227"
				( attribute "CDS_LIB" "dev_discrete"
					( Origin gPackager )
				)
				( attribute "CDS_LOCATION" "C8T9"
					( Origin gPackager )
				)
				( attribute "CDS_SEC" "1"
					( Origin gPackager )
				)
				( attribute "LOCATION" "C8T9"
					( Origin gFrontEnd )
				)
				( attribute "MATERIAL" "X6S"
					( Origin gFrontEnd )
				)
				( attribute "PACK_TYPE" "0603V"
					( Origin gFrontEnd )
				)
				( attribute "PART_NUMBER" "E15431-004"
					( Origin gFrontEnd )
				)
				( attribute "PHYS_PAGE" "225"
					( Origin gFrontEnd )
				)
				( attribute "ROOM" "PVDDQ_GHJ"
					( Origin gFrontEnd )
				)
				( attribute "ROT" "0"
					( Origin gFrontEnd )
				)
				( attribute "SEC" "1"
					( Origin gFrontEnd )
				)
				( attribute "SEC_TYPE" "0603V"
					( Origin gFrontEnd )
				)
				( attribute "TOLERANCE" "20%"
					( Origin gFrontEnd )
				)
				( attribute "VALUE" "22.0UF"
					( Origin gFrontEnd )
				)
				( attribute "VER" "1"
					( Origin gFrontEnd )
				)
				( attribute "VOLTAGE" "4V"
					( Units "uVoltage" "V" 1.000000)
					( Origin gFrontEnd )
				)
				( attribute "XY" "(1550,-450)"
					( Origin gFrontEnd )
				)
				( attribute "CHIPS_PART_NAME" "CAP_A"
					( Origin gPackager )
				)
				( attribute "CDS_PART_NAME" "CAP_A_0603V-22.0UF,4V,20%,X6S,A"
					( Origin gPackager )
				)
				( objectStatus "C8T9" )
				( pin "a"
					( attribute "PN" "1"
						( Origin gPackager )
					)
					( objectStatus "C8T9.1" )
				)
				( pin "b"
					( attribute "PN" "2"
						( Origin gPackager )
					)
					( objectStatus "C8T9.2" )
				)
			)
			( gate "@baseboard_fab2_lib.baseboard_fab2(sch_1):page225_i228"
				( attribute "CDS_LIB" "dev_discrete"
					( Origin gPackager )
				)
				( attribute "CDS_LOCATION" "C8U5"
					( Origin gPackager )
				)
				( attribute "CDS_SEC" "1"
					( Origin gPackager )
				)
				( attribute "LOCATION" "C8U5"
					( Origin gFrontEnd )
				)
				( attribute "MATERIAL" "X6S"
					( Origin gFrontEnd )
				)
				( attribute "PACK_TYPE" "0603V"
					( Origin gFrontEnd )
				)
				( attribute "PART_NUMBER" "E15431-004"
					( Origin gFrontEnd )
				)
				( attribute "PHYS_PAGE" "225"
					( Origin gFrontEnd )
				)
				( attribute "ROOM" "PVDDQ_GHJ"
					( Origin gFrontEnd )
				)
				( attribute "ROT" "0"
					( Origin gFrontEnd )
				)
				( attribute "SEC" "1"
					( Origin gFrontEnd )
				)
				( attribute "SEC_TYPE" "0603V"
					( Origin gFrontEnd )
				)
				( attribute "TOLERANCE" "20%"
					( Origin gFrontEnd )
				)
				( attribute "VALUE" "22.0UF"
					( Origin gFrontEnd )
				)
				( attribute "VER" "1"
					( Origin gFrontEnd )
				)
				( attribute "VOLTAGE" "4V"
					( Units "uVoltage" "V" 1.000000)
					( Origin gFrontEnd )
				)
				( attribute "XY" "(1250,-450)"
					( Origin gFrontEnd )
				)
				( attribute "CHIPS_PART_NAME" "CAP_A"
					( Origin gPackager )
				)
				( attribute "CDS_PART_NAME" "CAP_A_0603V-22.0UF,4V,20%,X6S,A"
					( Origin gPackager )
				)
				( objectStatus "C8U5" )
				( pin "a"
					( attribute "PN" "1"
						( Origin gPackager )
					)
					( objectStatus "C8U5.1" )
				)
				( pin "b"
					( attribute "PN" "2"
						( Origin gPackager )
					)
					( objectStatus "C8U5.2" )
				)
			)
			( gate "@baseboard_fab2_lib.baseboard_fab2(sch_1):page225_i229"
				( attribute "CDS_LIB" "dev_discrete"
					( Origin gPackager )
				)
				( attribute "CDS_LOCATION" "C8T8"
					( Origin gPackager )
				)
				( attribute "CDS_SEC" "1"
					( Origin gPackager )
				)
				( attribute "LOCATION" "C8T8"
					( Origin gFrontEnd )
				)
				( attribute "MATERIAL" "X6S"
					( Origin gFrontEnd )
				)
				( attribute "PACK_TYPE" "0603V"
					( Origin gFrontEnd )
				)
				( attribute "PART_NUMBER" "E15431-004"
					( Origin gFrontEnd )
				)
				( attribute "PHYS_PAGE" "225"
					( Origin gFrontEnd )
				)
				( attribute "ROOM" "PVDDQ_GHJ"
					( Origin gFrontEnd )
				)
				( attribute "ROT" "0"
					( Origin gFrontEnd )
				)
				( attribute "SEC" "1"
					( Origin gFrontEnd )
				)
				( attribute "SEC_TYPE" "0603V"
					( Origin gFrontEnd )
				)
				( attribute "TOLERANCE" "20%"
					( Origin gFrontEnd )
				)
				( attribute "VALUE" "22.0UF"
					( Origin gFrontEnd )
				)
				( attribute "VER" "1"
					( Origin gFrontEnd )
				)
				( attribute "VOLTAGE" "4V"
					( Units "uVoltage" "V" 1.000000)
					( Origin gFrontEnd )
				)
				( attribute "XY" "(975,-450)"
					( Origin gFrontEnd )
				)
				( attribute "CHIPS_PART_NAME" "CAP_A"
					( Origin gPackager )
				)
				( attribute "CDS_PART_NAME" "CAP_A_0603V-22.0UF,4V,20%,X6S,A"
					( Origin gPackager )
				)
				( objectStatus "C8T8" )
				( pin "a"
					( attribute "PN" "1"
						( Origin gPackager )
					)
					( objectStatus "C8T8.1" )
				)
				( pin "b"
					( attribute "PN" "2"
						( Origin gPackager )
					)
					( objectStatus "C8T8.2" )
				)
			)
			( gate "@baseboard_fab2_lib.baseboard_fab2(sch_1):page225_i230"
				( attribute "CDS_LIB" "dev_discrete"
					( Origin gPackager )
				)
				( attribute "CDS_LOCATION" "C8T7"
					( Origin gPackager )
				)
				( attribute "CDS_SEC" "1"
					( Origin gPackager )
				)
				( attribute "LOCATION" "C8T7"
					( Origin gFrontEnd )
				)
				( attribute "MATERIAL" "X6S"
					( Origin gFrontEnd )
				)
				( attribute "PACK_TYPE" "0603V"
					( Origin gFrontEnd )
				)
				( attribute "PART_NUMBER" "E15431-004"
					( Origin gFrontEnd )
				)
				( attribute "PHYS_PAGE" "225"
					( Origin gFrontEnd )
				)
				( attribute "ROOM" "PVDDQ_GHJ"
					( Origin gFrontEnd )
				)
				( attribute "ROT" "0"
					( Origin gFrontEnd )
				)
				( attribute "SEC" "1"
					( Origin gFrontEnd )
				)
				( attribute "SEC_TYPE" "0603V"
					( Origin gFrontEnd )
				)
				( attribute "TOLERANCE" "20%"
					( Origin gFrontEnd )
				)
				( attribute "VALUE" "22.0UF"
					( Origin gFrontEnd )
				)
				( attribute "VER" "1"
					( Origin gFrontEnd )
				)
				( attribute "VOLTAGE" "4V"
					( Units "uVoltage" "V" 1.000000)
					( Origin gFrontEnd )
				)
				( attribute "XY" "(700,-450)"
					( Origin gFrontEnd )
				)
				( attribute "CHIPS_PART_NAME" "CAP_A"
					( Origin gPackager )
				)
				( attribute "CDS_PART_NAME" "CAP_A_0603V-22.0UF,4V,20%,X6S,A"
					( Origin gPackager )
				)
				( objectStatus "C8T7" )
				( pin "a"
					( attribute "PN" "1"
						( Origin gPackager )
					)
					( objectStatus "C8T7.1" )
				)
				( pin "b"
					( attribute "PN" "2"
						( Origin gPackager )
					)
					( objectStatus "C8T7.2" )
				)
			)
			( gate "@baseboard_fab2_lib.baseboard_fab2(sch_1):page225_i231"
				( attribute "CDS_LIB" "dev_discrete"
					( Origin gPackager )
				)
				( attribute "CDS_LOCATION" "C8T6"
					( Origin gPackager )
				)
				( attribute "CDS_SEC" "1"
					( Origin gPackager )
				)
				( attribute "LOCATION" "C8T6"
					( Origin gFrontEnd )
				)
				( attribute "MATERIAL" "X6S"
					( Origin gFrontEnd )
				)
				( attribute "PACK_TYPE" "0603V"
					( Origin gFrontEnd )
				)
				( attribute "PART_NUMBER" "E15431-004"
					( Origin gFrontEnd )
				)
				( attribute "PHYS_PAGE" "225"
					( Origin gFrontEnd )
				)
				( attribute "ROOM" "PVDDQ_GHJ"
					( Origin gFrontEnd )
				)
				( attribute "ROT" "0"
					( Origin gFrontEnd )
				)
				( attribute "SEC" "1"
					( Origin gFrontEnd )
				)
				( attribute "SEC_TYPE" "0603V"
					( Origin gFrontEnd )
				)
				( attribute "TOLERANCE" "20%"
					( Origin gFrontEnd )
				)
				( attribute "VALUE" "22.0UF"
					( Origin gFrontEnd )
				)
				( attribute "VER" "1"
					( Origin gFrontEnd )
				)
				( attribute "VOLTAGE" "4V"
					( Units "uVoltage" "V" 1.000000)
					( Origin gFrontEnd )
				)
				( attribute "XY" "(400,-450)"
					( Origin gFrontEnd )
				)
				( attribute "CHIPS_PART_NAME" "CAP_A"
					( Origin gPackager )
				)
				( attribute "CDS_PART_NAME" "CAP_A_0603V-22.0UF,4V,20%,X6S,A"
					( Origin gPackager )
				)
				( objectStatus "C8T6" )
				( pin "a"
					( attribute "PN" "1"
						( Origin gPackager )
					)
					( objectStatus "C8T6.1" )
				)
				( pin "b"
					( attribute "PN" "2"
						( Origin gPackager )
					)
					( objectStatus "C8T6.2" )
				)
			)
			( gate "@baseboard_fab2_lib.baseboard_fab2(sch_1):page225_i232"
				( attribute "CDS_LIB" "dev_discrete"
					( Origin gPackager )
				)
				( attribute "CDS_LOCATION" "C8U6"
					( Origin gPackager )
				)
				( attribute "CDS_SEC" "1"
					( Origin gPackager )
				)
				( attribute "LOCATION" "C8U6"
					( Origin gFrontEnd )
				)
				( attribute "MATERIAL" "X6S"
					( Origin gFrontEnd )
				)
				( attribute "PACK_TYPE" "0603V"
					( Origin gFrontEnd )
				)
				( attribute "PART_NUMBER" "E15431-004"
					( Origin gFrontEnd )
				)
				( attribute "PHYS_PAGE" "225"
					( Origin gFrontEnd )
				)
				( attribute "ROOM" "PVDDQ_GHJ"
					( Origin gFrontEnd )
				)
				( attribute "ROT" "0"
					( Origin gFrontEnd )
				)
				( attribute "SEC" "1"
					( Origin gFrontEnd )
				)
				( attribute "SEC_TYPE" "0603V"
					( Origin gFrontEnd )
				)
				( attribute "TOLERANCE" "20%"
					( Origin gFrontEnd )
				)
				( attribute "VALUE" "22.0UF"
					( Origin gFrontEnd )
				)
				( attribute "VER" "1"
					( Origin gFrontEnd )
				)
				( attribute "VOLTAGE" "4V"
					( Units "uVoltage" "V" 1.000000)
					( Origin gFrontEnd )
				)
				( attribute "XY" "(100,-450)"
					( Origin gFrontEnd )
				)
				( attribute "CHIPS_PART_NAME" "CAP_A"
					( Origin gPackager )
				)
				( attribute "CDS_PART_NAME" "CAP_A_0603V-22.0UF,4V,20%,X6S,A"
					( Origin gPackager )
				)
				( objectStatus "C8U6" )
				( pin "a"
					( attribute "PN" "1"
						( Origin gPackager )
					)
					( objectStatus "C8U6.1" )
				)
				( pin "b"
					( attribute "PN" "2"
						( Origin gPackager )
					)
					( objectStatus "C8U6.2" )
				)
			)
			( gate "@baseboard_fab2_lib.baseboard_fab2(sch_1):page225_i233"
				( attribute "CDS_LIB" "dev_discrete"
					( Origin gPackager )
				)
				( attribute "CDS_LOCATION" "C8T5"
					( Origin gPackager )
				)
				( attribute "CDS_SEC" "1"
					( Origin gPackager )
				)
				( attribute "LOCATION" "C8T5"
					( Origin gFrontEnd )
				)
				( attribute "MATERIAL" "X6S"
					( Origin gFrontEnd )
				)
				( attribute "PACK_TYPE" "0603V"
					( Origin gFrontEnd )
				)
				( attribute "PART_NUMBER" "E15431-004"
					( Origin gFrontEnd )
				)
				( attribute "PHYS_PAGE" "225"
					( Origin gFrontEnd )
				)
				( attribute "ROOM" "PVDDQ_GHJ"
					( Origin gFrontEnd )
				)
				( attribute "ROT" "0"
					( Origin gFrontEnd )
				)
				( attribute "SEC" "1"
					( Origin gFrontEnd )
				)
				( attribute "SEC_TYPE" "0603V"
					( Origin gFrontEnd )
				)
				( attribute "TOLERANCE" "20%"
					( Origin gFrontEnd )
				)
				( attribute "VALUE" "22.0UF"
					( Origin gFrontEnd )
				)
				( attribute "VER" "1"
					( Origin gFrontEnd )
				)
				( attribute "VOLTAGE" "4V"
					( Units "uVoltage" "V" 1.000000)
					( Origin gFrontEnd )
				)
				( attribute "XY" "(-225,-450)"
					( Origin gFrontEnd )
				)
				( attribute "CHIPS_PART_NAME" "CAP_A"
					( Origin gPackager )
				)
				( attribute "CDS_PART_NAME" "CAP_A_0603V-22.0UF,4V,20%,X6S,A"
					( Origin gPackager )
				)
				( objectStatus "C8T5" )
				( pin "a"
					( attribute "PN" "1"
						( Origin gPackager )
					)
					( objectStatus "C8T5.1" )
				)
				( pin "b"
					( attribute "PN" "2"
						( Origin gPackager )
					)
					( objectStatus "C8T5.2" )
				)
			)
			( gate "@baseboard_fab2_lib.baseboard_fab2(sch_1):page225_i234"
				( attribute "CDS_LIB" "dev_discrete"
					( Origin gPackager )
				)
				( attribute "CDS_LOCATION" "C7T5"
					( Origin gPackager )
				)
				( attribute "CDS_SEC" "1"
					( Origin gPackager )
				)
				( attribute "LOCATION" "C7T5"
					( Origin gFrontEnd )
				)
				( attribute "MATERIAL" "X6S"
					( Origin gFrontEnd )
				)
				( attribute "PACK_TYPE" "0603V"
					( Origin gFrontEnd )
				)
				( attribute "PART_NUMBER" "E15431-004"
					( Origin gFrontEnd )
				)
				( attribute "PHYS_PAGE" "225"
					( Origin gFrontEnd )
				)
				( attribute "ROOM" "PVDDQ_GHJ"
					( Origin gFrontEnd )
				)
				( attribute "ROT" "0"
					( Origin gFrontEnd )
				)
				( attribute "SEC" "1"
					( Origin gFrontEnd )
				)
				( attribute "SEC_TYPE" "0603V"
					( Origin gFrontEnd )
				)
				( attribute "TOLERANCE" "20%"
					( Origin gFrontEnd )
				)
				( attribute "VALUE" "22.0UF"
					( Origin gFrontEnd )
				)
				( attribute "VER" "1"
					( Origin gFrontEnd )
				)
				( attribute "VOLTAGE" "4V"
					( Units "uVoltage" "V" 1.000000)
					( Origin gFrontEnd )
				)
				( attribute "XY" "(-500,-450)"
					( Origin gFrontEnd )
				)
				( attribute "CHIPS_PART_NAME" "CAP_A"
					( Origin gPackager )
				)
				( attribute "CDS_PART_NAME" "CAP_A_0603V-22.0UF,4V,20%,X6S,A"
					( Origin gPackager )
				)
				( objectStatus "C7T5" )
				( pin "a"
					( attribute "PN" "1"
						( Origin gPackager )
					)
					( objectStatus "C7T5.1" )
				)
				( pin "b"
					( attribute "PN" "2"
						( Origin gPackager )
					)
					( objectStatus "C7T5.2" )
				)
			)
			( gate "@baseboard_fab2_lib.baseboard_fab2(sch_1):page225_i235"
				( attribute "CDS_LIB" "dev_discrete"
					( Origin gPackager )
				)
				( attribute "CDS_LOCATION" "C7T4"
					( Origin gPackager )
				)
				( attribute "CDS_SEC" "1"
					( Origin gPackager )
				)
				( attribute "LOCATION" "C7T4"
					( Origin gFrontEnd )
				)
				( attribute "MATERIAL" "X6S"
					( Origin gFrontEnd )
				)
				( attribute "PACK_TYPE" "0603V"
					( Origin gFrontEnd )
				)
				( attribute "PART_NUMBER" "E15431-004"
					( Origin gFrontEnd )
				)
				( attribute "PHYS_PAGE" "225"
					( Origin gFrontEnd )
				)
				( attribute "ROOM" "PVDDQ_GHJ"
					( Origin gFrontEnd )
				)
				( attribute "ROT" "0"
					( Origin gFrontEnd )
				)
				( attribute "SEC" "1"
					( Origin gFrontEnd )
				)
				( attribute "SEC_TYPE" "0603V"
					( Origin gFrontEnd )
				)
				( attribute "TOLERANCE" "20%"
					( Origin gFrontEnd )
				)
				( attribute "VALUE" "22.0UF"
					( Origin gFrontEnd )
				)
				( attribute "VER" "1"
					( Origin gFrontEnd )
				)
				( attribute "VOLTAGE" "4V"
					( Units "uVoltage" "V" 1.000000)
					( Origin gFrontEnd )
				)
				( attribute "XY" "(-800,-450)"
					( Origin gFrontEnd )
				)
				( attribute "CHIPS_PART_NAME" "CAP_A"
					( Origin gPackager )
				)
				( attribute "CDS_PART_NAME" "CAP_A_0603V-22.0UF,4V,20%,X6S,A"
					( Origin gPackager )
				)
				( objectStatus "C7T4" )
				( pin "a"
					( attribute "PN" "1"
						( Origin gPackager )
					)
					( objectStatus "C7T4.1" )
				)
				( pin "b"
					( attribute "PN" "2"
						( Origin gPackager )
					)
					( objectStatus "C7T4.2" )
				)
			)
			( gate "@baseboard_fab2_lib.baseboard_fab2(sch_1):page225_i236"
				( attribute "CDS_LIB" "dev_discrete"
					( Origin gPackager )
				)
				( attribute "CDS_LOCATION" "C8U3"
					( Origin gPackager )
				)
				( attribute "CDS_SEC" "1"
					( Origin gPackager )
				)
				( attribute "LOCATION" "C8U3"
					( Origin gFrontEnd )
				)
				( attribute "MATERIAL" "X6S"
					( Origin gFrontEnd )
				)
				( attribute "PACK_TYPE" "0603V"
					( Origin gFrontEnd )
				)
				( attribute "PART_NUMBER" "E15431-004"
					( Origin gFrontEnd )
				)
				( attribute "PHYS_PAGE" "225"
					( Origin gFrontEnd )
				)
				( attribute "ROOM" "PVDDQ_ABC"
					( Origin gFrontEnd )
				)
				( attribute "ROT" "0"
					( Origin gFrontEnd )
				)
				( attribute "SEC" "1"
					( Origin gFrontEnd )
				)
				( attribute "SEC_TYPE" "0603V"
					( Origin gFrontEnd )
				)
				( attribute "TOLERANCE" "20%"
					( Origin gFrontEnd )
				)
				( attribute "VALUE" "22.0UF"
					( Origin gFrontEnd )
				)
				( attribute "VER" "1"
					( Origin gFrontEnd )
				)
				( attribute "VOLTAGE" "4V"
					( Units "uVoltage" "V" 1.000000)
					( Origin gFrontEnd )
				)
				( attribute "XY" "(-1100,-450)"
					( Origin gFrontEnd )
				)
				( attribute "CHIPS_PART_NAME" "CAP_A"
					( Origin gPackager )
				)
				( attribute "CDS_PART_NAME" "CAP_A_0603V-22.0UF,4V,20%,X6S,A"
					( Origin gPackager )
				)
				( objectStatus "C8U3" )
				( pin "a"
					( attribute "PN" "1"
						( Origin gPackager )
					)
					( objectStatus "C8U3.1" )
				)
				( pin "b"
					( attribute "PN" "2"
						( Origin gPackager )
					)
					( objectStatus "C8U3.2" )
				)
			)
			( gate "@baseboard_fab2_lib.baseboard_fab2(sch_1):page225_i237"
				( attribute "CDS_LIB" "dev_discrete"
					( Origin gPackager )
				)
				( attribute "CDS_LOCATION" "C7U1"
					( Origin gPackager )
				)
				( attribute "CDS_SEC" "1"
					( Origin gPackager )
				)
				( attribute "LOCATION" "C7U1"
					( Origin gFrontEnd )
				)
				( attribute "MATERIAL" "X6S"
					( Origin gFrontEnd )
				)
				( attribute "PACK_TYPE" "0603V"
					( Origin gFrontEnd )
				)
				( attribute "PART_NUMBER" "E15431-004"
					( Origin gFrontEnd )
				)
				( attribute "PHYS_PAGE" "225"
					( Origin gFrontEnd )
				)
				( attribute "ROOM" "PVDDQ_GHJ"
					( Origin gFrontEnd )
				)
				( attribute "ROT" "0"
					( Origin gFrontEnd )
				)
				( attribute "SEC" "1"
					( Origin gFrontEnd )
				)
				( attribute "SEC_TYPE" "0603V"
					( Origin gFrontEnd )
				)
				( attribute "TOLERANCE" "20%"
					( Origin gFrontEnd )
				)
				( attribute "VALUE" "22.0UF"
					( Origin gFrontEnd )
				)
				( attribute "VER" "1"
					( Origin gFrontEnd )
				)
				( attribute "VOLTAGE" "4V"
					( Units "uVoltage" "V" 1.000000)
					( Origin gFrontEnd )
				)
				( attribute "XY" "(-1375,-450)"
					( Origin gFrontEnd )
				)
				( attribute "CHIPS_PART_NAME" "CAP_A"
					( Origin gPackager )
				)
				( attribute "CDS_PART_NAME" "CAP_A_0603V-22.0UF,4V,20%,X6S,A"
					( Origin gPackager )
				)
				( objectStatus "C7U1" )
				( pin "a"
					( attribute "PN" "1"
						( Origin gPackager )
					)
					( objectStatus "C7U1.1" )
				)
				( pin "b"
					( attribute "PN" "2"
						( Origin gPackager )
					)
					( objectStatus "C7U1.2" )
				)
			)
			( gate "@baseboard_fab2_lib.baseboard_fab2(sch_1):page225_i238"
				( attribute "CDS_LIB" "dev_discrete"
					( Origin gPackager )
				)
				( attribute "CDS_LOCATION" "C7U2"
					( Origin gPackager )
				)
				( attribute "CDS_SEC" "1"
					( Origin gPackager )
				)
				( attribute "LOCATION" "C7U2"
					( Origin gFrontEnd )
				)
				( attribute "MATERIAL" "X6S"
					( Origin gFrontEnd )
				)
				( attribute "PACK_TYPE" "0603V"
					( Origin gFrontEnd )
				)
				( attribute "PART_NUMBER" "E15431-004"
					( Origin gFrontEnd )
				)
				( attribute "PHYS_PAGE" "225"
					( Origin gFrontEnd )
				)
				( attribute "ROOM" "PVDDQ_GHJ"
					( Origin gFrontEnd )
				)
				( attribute "ROT" "0"
					( Origin gFrontEnd )
				)
				( attribute "SEC" "1"
					( Origin gFrontEnd )
				)
				( attribute "SEC_TYPE" "0603V"
					( Origin gFrontEnd )
				)
				( attribute "TOLERANCE" "20%"
					( Origin gFrontEnd )
				)
				( attribute "VALUE" "22.0UF"
					( Origin gFrontEnd )
				)
				( attribute "VER" "1"
					( Origin gFrontEnd )
				)
				( attribute "VOLTAGE" "4V"
					( Units "uVoltage" "V" 1.000000)
					( Origin gFrontEnd )
				)
				( attribute "XY" "(-1650,-450)"
					( Origin gFrontEnd )
				)
				( attribute "CHIPS_PART_NAME" "CAP_A"
					( Origin gPackager )
				)
				( attribute "CDS_PART_NAME" "CAP_A_0603V-22.0UF,4V,20%,X6S,A"
					( Origin gPackager )
				)
				( objectStatus "C7U2" )
				( pin "a"
					( attribute "PN" "1"
						( Origin gPackager )
					)
					( objectStatus "C7U2.1" )
				)
				( pin "b"
					( attribute "PN" "2"
						( Origin gPackager )
					)
					( objectStatus "C7U2.2" )
				)
			)
			( gate "@baseboard_fab2_lib.baseboard_fab2(sch_1):page225_i239"
				( attribute "CDS_LIB" "dev_discrete"
					( Origin gPackager )
				)
				( attribute "CDS_LOCATION" "C8U2"
					( Origin gPackager )
				)
				( attribute "CDS_SEC" "1"
					( Origin gPackager )
				)
				( attribute "LOCATION" "C8U2"
					( Origin gFrontEnd )
				)
				( attribute "MATERIAL" "X6S"
					( Origin gFrontEnd )
				)
				( attribute "PACK_TYPE" "0603V"
					( Origin gFrontEnd )
				)
				( attribute "PART_NUMBER" "E15431-004"
					( Origin gFrontEnd )
				)
				( attribute "PHYS_PAGE" "225"
					( Origin gFrontEnd )
				)
				( attribute "ROOM" "PVDDQ_GHJ"
					( Origin gFrontEnd )
				)
				( attribute "ROT" "0"
					( Origin gFrontEnd )
				)
				( attribute "SEC" "1"
					( Origin gFrontEnd )
				)
				( attribute "SEC_TYPE" "0603V"
					( Origin gFrontEnd )
				)
				( attribute "TOLERANCE" "20%"
					( Origin gFrontEnd )
				)
				( attribute "VALUE" "22.0UF"
					( Origin gFrontEnd )
				)
				( attribute "VER" "1"
					( Origin gFrontEnd )
				)
				( attribute "VOLTAGE" "4V"
					( Units "uVoltage" "V" 1.000000)
					( Origin gFrontEnd )
				)
				( attribute "XY" "(-1950,-450)"
					( Origin gFrontEnd )
				)
				( attribute "CHIPS_PART_NAME" "CAP_A"
					( Origin gPackager )
				)
				( attribute "CDS_PART_NAME" "CAP_A_0603V-22.0UF,4V,20%,X6S,A"
					( Origin gPackager )
				)
				( objectStatus "C8U2" )
				( pin "a"
					( attribute "PN" "1"
						( Origin gPackager )
					)
					( objectStatus "C8U2.1" )
				)
				( pin "b"
					( attribute "PN" "2"
						( Origin gPackager )
					)
					( objectStatus "C8U2.2" )
				)
			)
			( gate "@baseboard_fab2_lib.baseboard_fab2(sch_1):page225_i241"
				( attribute "CDS_LIB" "dev_discrete"
					( Origin gPackager )
				)
				( attribute "CDS_LOCATION" "C8U7"
					( Origin gPackager )
				)
				( attribute "CDS_SEC" "1"
					( Origin gPackager )
				)
				( attribute "LOCATION" "C8U7"
					( Origin gFrontEnd )
				)
				( attribute "MATERIAL" "X6S"
					( Origin gFrontEnd )
				)
				( attribute "PACK_TYPE" "0603V"
					( Origin gFrontEnd )
				)
				( attribute "PART_NUMBER" "E15431-004"
					( Origin gFrontEnd )
				)
				( attribute "PHYS_PAGE" "225"
					( Origin gFrontEnd )
				)
				( attribute "ROOM" "PVDDQ_GHJ"
					( Origin gFrontEnd )
				)
				( attribute "ROT" "0"
					( Origin gFrontEnd )
				)
				( attribute "SEC" "1"
					( Origin gFrontEnd )
				)
				( attribute "SEC_TYPE" "0603V"
					( Origin gFrontEnd )
				)
				( attribute "TOLERANCE" "20%"
					( Origin gFrontEnd )
				)
				( attribute "VALUE" "22.0UF"
					( Origin gFrontEnd )
				)
				( attribute "VER" "1"
					( Origin gFrontEnd )
				)
				( attribute "VOLTAGE" "4V"
					( Units "uVoltage" "V" 1.000000)
					( Origin gFrontEnd )
				)
				( attribute "XY" "(-2250,-450)"
					( Origin gFrontEnd )
				)
				( attribute "CHIPS_PART_NAME" "CAP_A"
					( Origin gPackager )
				)
				( attribute "CDS_PART_NAME" "CAP_A_0603V-22.0UF,4V,20%,X6S,A"
					( Origin gPackager )
				)
				( objectStatus "C8U7" )
				( pin "a"
					( attribute "PN" "1"
						( Origin gPackager )
					)
					( objectStatus "C8U7.1" )
				)
				( pin "b"
					( attribute "PN" "2"
						( Origin gPackager )
					)
					( objectStatus "C8U7.2" )
				)
			)
			( gate "@baseboard_fab2_lib.baseboard_fab2(sch_1):page225_i243"
				( attribute "CDS_LIB" "mstr_misc"
					( Origin gPackager )
				)
				( attribute "CDS_LOCATION" "SH7U1"
					( Origin gPackager )
				)
				( attribute "CDS_SEC" "1"
					( Origin gPackager )
				)
				( attribute "LOCATION" "SH7U1"
					( Origin gFrontEnd )
				)
				( attribute "MATERIAL" "EMPTY"
					( Origin gFrontEnd )
				)
				( attribute "PACK_TYPE" "SH0201"
					( Origin gFrontEnd )
				)
				( attribute "PART_NUMBER" "N_A"
					( Origin gFrontEnd )
				)
				( attribute "PHYS_PAGE" "225"
					( Origin gFrontEnd )
				)
				( attribute "PIN_SHORT" "A:B"
					( Origin gFrontEnd )
				)
				( attribute "ROT" "0"
					( Origin gFrontEnd )
				)
				( attribute "SEC" "1"
					( Origin gFrontEnd )
				)
				( attribute "SEC_TYPE" "SH0201"
					( Origin gFrontEnd )
				)
				( attribute "VER" "1"
					( Origin gFrontEnd )
				)
				( attribute "XY" "(-250,2325)"
					( Origin gFrontEnd )
				)
				( attribute "CHIPS_PART_NAME" "SHUNT"
					( Origin gPackager )
				)
				( attribute "CDS_PART_NAME" "SHUNT_SH0201-EMPTY,N_A"
					( Origin gPackager )
				)
				( objectStatus "SH7U1" )
				( pin "a"
					( attribute "PN" "1"
						( Origin gPackager )
					)
					( objectStatus "SH7U1.1" )
				)
				( pin "b"
					( attribute "PN" "2"
						( Origin gPackager )
					)
					( objectStatus "SH7U1.2" )
				)
			)
			( gate "@baseboard_fab2_lib.baseboard_fab2(sch_1):page225_i244"
				( attribute "CDS_LIB" "mstr_misc"
					( Origin gPackager )
				)
				( attribute "CDS_LOCATION" "SH7U2"
					( Origin gPackager )
				)
				( attribute "CDS_SEC" "1"
					( Origin gPackager )
				)
				( attribute "LOCATION" "SH7U2"
					( Origin gFrontEnd )
				)
				( attribute "MATERIAL" "EMPTY"
					( Origin gFrontEnd )
				)
				( attribute "PACK_TYPE" "SH0201"
					( Origin gFrontEnd )
				)
				( attribute "PART_NUMBER" "N_A"
					( Origin gFrontEnd )
				)
				( attribute "PHYS_PAGE" "225"
					( Origin gFrontEnd )
				)
				( attribute "PIN_SHORT" "A:B"
					( Origin gFrontEnd )
				)
				( attribute "ROT" "0"
					( Origin gFrontEnd )
				)
				( attribute "SEC" "1"
					( Origin gFrontEnd )
				)
				( attribute "SEC_TYPE" "SH0201"
					( Origin gFrontEnd )
				)
				( attribute "VER" "1"
					( Origin gFrontEnd )
				)
				( attribute "XY" "(-275,1875)"
					( Origin gFrontEnd )
				)
				( attribute "CHIPS_PART_NAME" "SHUNT"
					( Origin gPackager )
				)
				( attribute "CDS_PART_NAME" "SHUNT_SH0201-EMPTY,N_A"
					( Origin gPackager )
				)
				( objectStatus "SH7U2" )
				( pin "a"
					( attribute "PN" "1"
						( Origin gPackager )
					)
					( objectStatus "SH7U2.1" )
				)
				( pin "b"
					( attribute "PN" "2"
						( Origin gPackager )
					)
					( objectStatus "SH7U2.2" )
				)
			)
			( gate "@baseboard_fab2_lib.baseboard_fab2(sch_1):page226_i8"
				( attribute "CDS_LIB" "mstr_discrete"
					( Origin gPackager )
				)
				( attribute "CDS_LOCATION" "R9M7"
					( Origin gPackager )
				)
				( attribute "CDS_SEC" "1"
					( Origin gPackager )
				)
				( attribute "LOCATION" "R9M7"
					( Origin gFrontEnd )
				)
				( attribute "MATERIAL" "EMPTY"
					( Origin gFrontEnd )
				)
				( attribute "PACK_TYPE" "0402"
					( Origin gFrontEnd )
				)
				( attribute "PART_NUMBER" "G21796-017"
					( Origin gFrontEnd )
				)
				( attribute "PHYS_PAGE" "226"
					( Origin gFrontEnd )
				)
				( attribute "ROOM" "VDDQ_KLM_PWR_VR"
					( Origin gFrontEnd )
				)
				( attribute "ROT" "0"
					( Origin gFrontEnd )
				)
				( attribute "SEC" "1"
					( Origin gFrontEnd )
				)
				( attribute "SEC_TYPE" "0402"
					( Origin gFrontEnd )
				)
				( attribute "TOLERANCE" "1%"
					( Origin gFrontEnd )
				)
				( attribute "VALUE" "100.0"
					( Origin gFrontEnd )
				)
				( attribute "VER" "2"
					( Origin gFrontEnd )
				)
				( attribute "WATTAGE" "1/16W"
					( Origin gFrontEnd )
				)
				( attribute "XY" "(3800,2775)"
					( Origin gFrontEnd )
				)
				( attribute "CHIPS_PART_NAME" "RES"
					( Origin gPackager )
				)
				( attribute "CDS_PART_NAME" "RES_0402-100.0,1%,1/16W,EMPTY,A"
					( Origin gPackager )
				)
				( objectStatus "R9M7" )
				( pin "a"
					( attribute "PN" "1"
						( Origin gPackager )
					)
					( objectStatus "R9M7.1" )
				)
				( pin "b"
					( attribute "PN" "2"
						( Origin gPackager )
					)
					( objectStatus "R9M7.2" )
				)
			)
			( gate "@baseboard_fab2_lib.baseboard_fab2(sch_1):page226_i13"
				( attribute "CDS_LIB" "mstr_discrete"
					( Origin gPackager )
				)
				( attribute "CDS_LOCATION" "R1B13"
					( Origin gPackager )
				)
				( attribute "CDS_SEC" "1"
					( Origin gPackager )
				)
				( attribute "LOCATION" "R1B13"
					( Origin gFrontEnd )
				)
				( attribute "MATERIAL" "EMPTY"
					( Origin gFrontEnd )
				)
				( attribute "PACK_TYPE" "0402"
					( Origin gFrontEnd )
				)
				( attribute "PART_NUMBER" "G21796-311"
					( Origin gFrontEnd )
				)
				( attribute "PHYS_PAGE" "226"
					( Origin gFrontEnd )
				)
				( attribute "ROOM" "VDDQ_KLM_PWR_VR"
					( Origin gFrontEnd )
				)
				( attribute "ROT" "0"
					( Origin gFrontEnd )
				)
				( attribute "SEC" "1"
					( Origin gFrontEnd )
				)
				( attribute "SEC_TYPE" "0402"
					( Origin gFrontEnd )
				)
				( attribute "TOLERANCE" "1.0%"
					( Origin gFrontEnd )
				)
				( attribute "VALUE" "2.26K"
					( Origin gFrontEnd )
				)
				( attribute "VER" "2"
					( Origin gFrontEnd )
				)
				( attribute "WATTAGE" "1/16W"
					( Origin gFrontEnd )
				)
				( attribute "XY" "(2750,3050)"
					( Origin gFrontEnd )
				)
				( attribute "CHIPS_PART_NAME" "RES"
					( Origin gPackager )
				)
				( attribute "CDS_PART_NAME" "RES_0402-2.26K,1.0%,1/16W,EMPTA"
					( Origin gPackager )
				)
				( objectStatus "R1B13" )
				( pin "a"
					( attribute "PN" "1"
						( Origin gPackager )
					)
					( objectStatus "R1B13.1" )
				)
				( pin "b"
					( attribute "PN" "2"
						( Origin gPackager )
					)
					( objectStatus "R1B13.2" )
				)
			)
			( gate "@baseboard_fab2_lib.baseboard_fab2(sch_1):page226_i14"
				( attribute "CDS_LIB" "mstr_discrete"
					( Origin gPackager )
				)
				( attribute "CDS_LOCATION" "R1B5"
					( Origin gPackager )
				)
				( attribute "CDS_SEC" "1"
					( Origin gPackager )
				)
				( attribute "LOCATION" "R1B5"
					( Origin gFrontEnd )
				)
				( attribute "MATERIAL" "CHIP"
					( Origin gFrontEnd )
				)
				( attribute "PACK_TYPE" "0402"
					( Origin gFrontEnd )
				)
				( attribute "PART_NUMBER" "G21796-250"
					( Origin gFrontEnd )
				)
				( attribute "PHYS_PAGE" "226"
					( Origin gFrontEnd )
				)
				( attribute "ROOM" "VDDQ_KLM_PWR_VR"
					( Origin gFrontEnd )
				)
				( attribute "ROT" "0"
					( Origin gFrontEnd )
				)
				( attribute "SEC" "1"
					( Origin gFrontEnd )
				)
				( attribute "SEC_TYPE" "0402"
					( Origin gFrontEnd )
				)
				( attribute "TOLERANCE" "1.0%"
					( Origin gFrontEnd )
				)
				( attribute "VALUE" "22.1"
					( Origin gFrontEnd )
				)
				( attribute "VER" "1"
					( Origin gFrontEnd )
				)
				( attribute "WATTAGE" "1/16W"
					( Origin gFrontEnd )
				)
				( attribute "XY" "(3375,2525)"
					( Origin gFrontEnd )
				)
				( attribute "CHIPS_PART_NAME" "RES"
					( Origin gPackager )
				)
				( attribute "CDS_PART_NAME" "RES_0402-22.1,1.0%,1/16W,CHIP,A"
					( Origin gPackager )
				)
				( objectStatus "R1B5" )
				( pin "a"
					( attribute "PN" "1"
						( Origin gPackager )
					)
					( objectStatus "R1B5.1" )
				)
				( pin "b"
					( attribute "PN" "2"
						( Origin gPackager )
					)
					( objectStatus "R1B5.2" )
				)
			)
			( gate "@baseboard_fab2_lib.baseboard_fab2(sch_1):page226_i16"
				( attribute "CDS_LIB" "mstr_discrete"
					( Origin gPackager )
				)
				( attribute "CDS_LOCATION" "R1B11"
					( Origin gPackager )
				)
				( attribute "CDS_SEC" "1"
					( Origin gPackager )
				)
				( attribute "LOCATION" "R1B11"
					( Origin gFrontEnd )
				)
				( attribute "MATERIAL" "CHIP"
					( Origin gFrontEnd )
				)
				( attribute "PACK_TYPE" "0402"
					( Origin gFrontEnd )
				)
				( attribute "PART_NUMBER" "G21497-005"
					( Origin gFrontEnd )
				)
				( attribute "PHYS_PAGE" "226"
					( Origin gFrontEnd )
				)
				( attribute "ROOM" "VDDQ_KLM_PWR_VR"
					( Origin gFrontEnd )
				)
				( attribute "ROT" "0"
					( Origin gFrontEnd )
				)
				( attribute "SEC" "1"
					( Origin gFrontEnd )
				)
				( attribute "SEC_TYPE" "0402"
					( Origin gFrontEnd )
				)
				( attribute "TOLERANCE" "5%"
					( Origin gFrontEnd )
				)
				( attribute "VALUE" "0.0"
					( Origin gFrontEnd )
				)
				( attribute "VER" "1"
					( Origin gFrontEnd )
				)
				( attribute "WATTAGE" "1/16W"
					( Origin gFrontEnd )
				)
				( attribute "XY" "(2575,2375)"
					( Origin gFrontEnd )
				)
				( attribute "CHIPS_PART_NAME" "RES"
					( Origin gPackager )
				)
				( attribute "CDS_PART_NAME" "RES_0402-0.0,5%,1/16W,CHIP,G21A"
					( Origin gPackager )
				)
				( objectStatus "R1B11" )
				( pin "a"
					( attribute "PN" "1"
						( Origin gPackager )
					)
					( objectStatus "R1B11.1" )
				)
				( pin "b"
					( attribute "PN" "2"
						( Origin gPackager )
					)
					( objectStatus "R1B11.2" )
				)
			)
			( gate "@baseboard_fab2_lib.baseboard_fab2(sch_1):page226_i17"
				( attribute "CDS_LIB" "mstr_discrete"
					( Origin gPackager )
				)
				( attribute "CDS_LOCATION" "R1B2"
					( Origin gPackager )
				)
				( attribute "CDS_SEC" "1"
					( Origin gPackager )
				)
				( attribute "LOCATION" "R1B2"
					( Origin gFrontEnd )
				)
				( attribute "MATERIAL" "CHIP"
					( Origin gFrontEnd )
				)
				( attribute "PACK_TYPE" "0402"
					( Origin gFrontEnd )
				)
				( attribute "PART_NUMBER" "G21796-026"
					( Origin gFrontEnd )
				)
				( attribute "PHYS_PAGE" "226"
					( Origin gFrontEnd )
				)
				( attribute "ROOM" "VDDQ_KLM_PWR_VR"
					( Origin gFrontEnd )
				)
				( attribute "ROT" "0"
					( Origin gFrontEnd )
				)
				( attribute "SEC" "1"
					( Origin gFrontEnd )
				)
				( attribute "SEC_TYPE" "0402"
					( Origin gFrontEnd )
				)
				( attribute "TOLERANCE" "1%"
					( Origin gFrontEnd )
				)
				( attribute "VALUE" "1.00K"
					( Origin gFrontEnd )
				)
				( attribute "VER" "2"
					( Origin gFrontEnd )
				)
				( attribute "WATTAGE" "1/16W"
					( Origin gFrontEnd )
				)
				( attribute "XY" "(2350,3025)"
					( Origin gFrontEnd )
				)
				( attribute "CHIPS_PART_NAME" "RES"
					( Origin gPackager )
				)
				( attribute "CDS_PART_NAME" "RES_0402-1.00K,1%,1/16W,CHIP,GA"
					( Origin gPackager )
				)
				( objectStatus "R1B2" )
				( pin "a"
					( attribute "PN" "1"
						( Origin gPackager )
					)
					( objectStatus "R1B2.1" )
				)
				( pin "b"
					( attribute "PN" "2"
						( Origin gPackager )
					)
					( objectStatus "R1B2.2" )
				)
			)
			( gate "@baseboard_fab2_lib.baseboard_fab2(sch_1):page226_i21"
				( attribute "CDS_LIB" "mstr_discrete"
					( Origin gPackager )
				)
				( attribute "CDS_LOCATION" "R1B6"
					( Origin gPackager )
				)
				( attribute "CDS_SEC" "1"
					( Origin gPackager )
				)
				( attribute "LOCATION" "R1B6"
					( Origin gFrontEnd )
				)
				( attribute "MATERIAL" "CHIP"
					( Origin gFrontEnd )
				)
				( attribute "PACK_TYPE" "0402"
					( Origin gFrontEnd )
				)
				( attribute "PART_NUMBER" "G21796-173"
					( Origin gFrontEnd )
				)
				( attribute "PHYS_PAGE" "226"
					( Origin gFrontEnd )
				)
				( attribute "ROOM" "VDDQ_KLM_PWR_VR"
					( Origin gFrontEnd )
				)
				( attribute "ROT" "0"
					( Origin gFrontEnd )
				)
				( attribute "SEC" "1"
					( Origin gPackager )
				)
				( attribute "TOLERANCE" "1%"
					( Origin gFrontEnd )
				)
				( attribute "VALUE" "20.0"
					( Origin gFrontEnd )
				)
				( attribute "VER" "1"
					( Origin gFrontEnd )
				)
				( attribute "WATTAGE" "1/16W"
					( Origin gFrontEnd )
				)
				( attribute "XY" "(3100,2025)"
					( Origin gFrontEnd )
				)
				( attribute "CHIPS_PART_NAME" "RES"
					( Origin gPackager )
				)
				( attribute "CDS_PART_NAME" "RES_0402-20.0,1%,1/16W,CHIP,G2A"
					( Origin gPackager )
				)
				( objectStatus "R1B6" )
				( pin "a"
					( attribute "PN" "1"
						( Origin gPackager )
					)
					( objectStatus "R1B6.1" )
				)
				( pin "b"
					( attribute "PN" "2"
						( Origin gPackager )
					)
					( objectStatus "R1B6.2" )
				)
			)
			( gate "@baseboard_fab2_lib.baseboard_fab2(sch_1):page226_i22"
				( attribute "CDS_LIB" "mstr_discrete"
					( Origin gPackager )
				)
				( attribute "CDS_LOCATION" "R1B7"
					( Origin gPackager )
				)
				( attribute "CDS_SEC" "1"
					( Origin gPackager )
				)
				( attribute "LOCATION" "R1B7"
					( Origin gFrontEnd )
				)
				( attribute "MATERIAL" "CHIP"
					( Origin gFrontEnd )
				)
				( attribute "PACK_TYPE" "0402"
					( Origin gFrontEnd )
				)
				( attribute "PART_NUMBER" "G21796-173"
					( Origin gFrontEnd )
				)
				( attribute "PHYS_PAGE" "226"
					( Origin gFrontEnd )
				)
				( attribute "ROOM" "VDDQ_KLM_PWR_VR"
					( Origin gFrontEnd )
				)
				( attribute "ROT" "0"
					( Origin gFrontEnd )
				)
				( attribute "SEC" "1"
					( Origin gPackager )
				)
				( attribute "TOLERANCE" "1%"
					( Origin gFrontEnd )
				)
				( attribute "VALUE" "20.0"
					( Origin gFrontEnd )
				)
				( attribute "VER" "1"
					( Origin gFrontEnd )
				)
				( attribute "WATTAGE" "1/16W"
					( Origin gFrontEnd )
				)
				( attribute "XY" "(2775,1975)"
					( Origin gFrontEnd )
				)
				( attribute "CHIPS_PART_NAME" "RES"
					( Origin gPackager )
				)
				( attribute "CDS_PART_NAME" "RES_0402-20.0,1%,1/16W,CHIP,G2A"
					( Origin gPackager )
				)
				( objectStatus "R1B7" )
				( pin "a"
					( attribute "PN" "1"
						( Origin gPackager )
					)
					( objectStatus "R1B7.1" )
				)
				( pin "b"
					( attribute "PN" "2"
						( Origin gPackager )
					)
					( objectStatus "R1B7.2" )
				)
			)
			( gate "@baseboard_fab2_lib.baseboard_fab2(sch_1):page226_i23"
				( attribute "CDS_LIB" "mstr_discrete"
					( Origin gPackager )
				)
				( attribute "CDS_LOCATION" "R1B10"
					( Origin gPackager )
				)
				( attribute "CDS_SEC" "1"
					( Origin gPackager )
				)
				( attribute "LOCATION" "R1B10"
					( Origin gFrontEnd )
				)
				( attribute "MATERIAL" "CHIP"
					( Origin gFrontEnd )
				)
				( attribute "PACK_TYPE" "0402"
					( Origin gFrontEnd )
				)
				( attribute "PART_NUMBER" "G21497-005"
					( Origin gFrontEnd )
				)
				( attribute "PHYS_PAGE" "226"
					( Origin gFrontEnd )
				)
				( attribute "ROOM" "VDDQ_KLM_PWR_VR"
					( Origin gFrontEnd )
				)
				( attribute "ROT" "0"
					( Origin gFrontEnd )
				)
				( attribute "SEC" "1"
					( Origin gFrontEnd )
				)
				( attribute "SEC_TYPE" "0402"
					( Origin gFrontEnd )
				)
				( attribute "TOLERANCE" "5%"
					( Origin gFrontEnd )
				)
				( attribute "VALUE" "0.0"
					( Origin gFrontEnd )
				)
				( attribute "VER" "1"
					( Origin gFrontEnd )
				)
				( attribute "WATTAGE" "1/16W"
					( Origin gFrontEnd )
				)
				( attribute "XY" "(2775,1675)"
					( Origin gFrontEnd )
				)
				( attribute "CHIPS_PART_NAME" "RES"
					( Origin gPackager )
				)
				( attribute "CDS_PART_NAME" "RES_0402-0.0,5%,1/16W,CHIP,G21A"
					( Origin gPackager )
				)
				( objectStatus "R1B10" )
				( pin "a"
					( attribute "PN" "1"
						( Origin gPackager )
					)
					( objectStatus "R1B10.1" )
				)
				( pin "b"
					( attribute "PN" "2"
						( Origin gPackager )
					)
					( objectStatus "R1B10.2" )
				)
			)
			( gate "@baseboard_fab2_lib.baseboard_fab2(sch_1):page226_i25"
				( attribute "CDS_LIB" "dev_discrete"
					( Origin gPackager )
				)
				( attribute "CDS_LOCATION" "C1B6"
					( Origin gPackager )
				)
				( attribute "CDS_SEC" "1"
					( Origin gPackager )
				)
				( attribute "LOCATION" "C1B6"
					( Origin gFrontEnd )
				)
				( attribute "MATERIAL" "X6S"
					( Origin gFrontEnd )
				)
				( attribute "PACK_TYPE" "0402V"
					( Origin gFrontEnd )
				)
				( attribute "PART_NUMBER" "D97712-004"
					( Origin gFrontEnd )
				)
				( attribute "PHYS_PAGE" "226"
					( Origin gFrontEnd )
				)
				( attribute "ROOM" "VDDQ_KLM_PWR_VR"
					( Origin gFrontEnd )
				)
				( attribute "ROT" "0"
					( Origin gFrontEnd )
				)
				( attribute "SEC" "1"
					( Origin gPackager )
				)
				( attribute "TOLERANCE" "10%"
					( Origin gFrontEnd )
				)
				( attribute "VALUE" "1.0UF"
					( Origin gFrontEnd )
				)
				( attribute "VER" "1"
					( Origin gFrontEnd )
				)
				( attribute "VOLTAGE" "6.3V"
					( Units "uVoltage" "V" 1.000000)
					( Origin gFrontEnd )
				)
				( attribute "XY" "(1525,3075)"
					( Origin gFrontEnd )
				)
				( attribute "CHIPS_PART_NAME" "CAP_A"
					( Origin gPackager )
				)
				( attribute "CDS_PART_NAME" "CAP_A_0402V-1.0UF,6.3V,10%,X6SA"
					( Origin gPackager )
				)
				( objectStatus "C1B6" )
				( pin "a"
					( attribute "PN" "1"
						( Origin gPackager )
					)
					( objectStatus "C1B6.1" )
				)
				( pin "b"
					( attribute "PN" "2"
						( Origin gPackager )
					)
					( objectStatus "C1B6.2" )
				)
			)
			( gate "@baseboard_fab2_lib.baseboard_fab2(sch_1):page226_i27"
				( attribute "CDS_LIB" "dev_discrete"
					( Origin gPackager )
				)
				( attribute "CDS_LOCATION" "C1B5"
					( Origin gPackager )
				)
				( attribute "CDS_SEC" "1"
					( Origin gPackager )
				)
				( attribute "LOCATION" "C1B5"
					( Origin gFrontEnd )
				)
				( attribute "MATERIAL" "X7R"
					( Origin gFrontEnd )
				)
				( attribute "PACK_TYPE" "0402V"
					( Origin gFrontEnd )
				)
				( attribute "PART_NUMBER" "A36096-030"
					( Origin gFrontEnd )
				)
				( attribute "PHYS_PAGE" "226"
					( Origin gFrontEnd )
				)
				( attribute "ROOM" "VDDQ_KLM_PWR_VR"
					( Origin gFrontEnd )
				)
				( attribute "ROT" "0"
					( Origin gFrontEnd )
				)
				( attribute "SEC" "1"
					( Origin gFrontEnd )
				)
				( attribute "SEC_TYPE" "0402V"
					( Origin gFrontEnd )
				)
				( attribute "TOLERANCE" "10%"
					( Origin gFrontEnd )
				)
				( attribute "VALUE" "0.1UF"
					( Origin gFrontEnd )
				)
				( attribute "VER" "1"
					( Origin gFrontEnd )
				)
				( attribute "VOLTAGE" "16V"
					( Units "uVoltage" "V" 1.000000)
					( Origin gFrontEnd )
				)
				( attribute "XY" "(1125,3075)"
					( Origin gFrontEnd )
				)
				( attribute "CHIPS_PART_NAME" "CAP_A"
					( Origin gPackager )
				)
				( attribute "CDS_PART_NAME" "CAP_A_0402V-0.1UF,16V,10%,X7R,A"
					( Origin gPackager )
				)
				( objectStatus "C1B5" )
				( pin "a"
					( attribute "PN" "1"
						( Origin gPackager )
					)
					( objectStatus "C1B5.1" )
				)
				( pin "b"
					( attribute "PN" "2"
						( Origin gPackager )
					)
					( objectStatus "C1B5.2" )
				)
			)
			( gate "@baseboard_fab2_lib.baseboard_fab2(sch_1):page226_i30"
				( attribute "CDS_LIB" "mstr_discrete"
					( Origin gPackager )
				)
				( attribute "CDS_LOCATION" "R9M3"
					( Origin gPackager )
				)
				( attribute "CDS_SEC" "1"
					( Origin gPackager )
				)
				( attribute "LOCATION" "R9M3"
					( Origin gFrontEnd )
				)
				( attribute "MATERIAL" "CHIP"
					( Origin gFrontEnd )
				)
				( attribute "PACK_TYPE" "0402"
					( Origin gFrontEnd )
				)
				( attribute "PART_NUMBER" "G21497-005"
					( Origin gFrontEnd )
				)
				( attribute "PHYS_PAGE" "226"
					( Origin gFrontEnd )
				)
				( attribute "ROOM" "VDDQ_KLM_PWR_VR"
					( Origin gFrontEnd )
				)
				( attribute "ROT" "0"
					( Origin gFrontEnd )
				)
				( attribute "SEC" "1"
					( Origin gFrontEnd )
				)
				( attribute "SEC_TYPE" "0402"
					( Origin gFrontEnd )
				)
				( attribute "TOLERANCE" "5%"
					( Origin gFrontEnd )
				)
				( attribute "VALUE" "0.0"
					( Origin gFrontEnd )
				)
				( attribute "VER" "2"
					( Origin gFrontEnd )
				)
				( attribute "WATTAGE" "1/16W"
					( Origin gFrontEnd )
				)
				( attribute "XY" "(825,3525)"
					( Origin gFrontEnd )
				)
				( attribute "CHIPS_PART_NAME" "RES"
					( Origin gPackager )
				)
				( attribute "CDS_PART_NAME" "RES_0402-0.0,5%,1/16W,CHIP,G21A"
					( Origin gPackager )
				)
				( objectStatus "R9M3" )
				( pin "a"
					( attribute "PN" "1"
						( Origin gPackager )
					)
					( objectStatus "R9M3.1" )
				)
				( pin "b"
					( attribute "PN" "2"
						( Origin gPackager )
					)
					( objectStatus "R9M3.2" )
				)
			)
			( gate "@baseboard_fab2_lib.baseboard_fab2(sch_1):page226_i32"
				( attribute "CDS_LIB" "mstr_discrete"
					( Origin gPackager )
				)
				( attribute "CDS_LOCATION" "R1B16"
					( Origin gPackager )
				)
				( attribute "CDS_SEC" "1"
					( Origin gPackager )
				)
				( attribute "LOCATION" "R1B16"
					( Origin gFrontEnd )
				)
				( attribute "MATERIAL" "CHIP"
					( Origin gFrontEnd )
				)
				( attribute "NO_XNET_CONNECTION" "1"
					( Origin gFrontEnd )
				)
				( attribute "PACK_TYPE" "0402"
					( Origin gFrontEnd )
				)
				( attribute "PART_NUMBER" "G21796-066"
					( Origin gFrontEnd )
				)
				( attribute "PHYS_PAGE" "226"
					( Origin gFrontEnd )
				)
				( attribute "ROOM" "VDDQ_KLM_PWR_VR"
					( Origin gFrontEnd )
				)
				( attribute "ROT" "0"
					( Origin gFrontEnd )
				)
				( attribute "SEC" "1"
					( Origin gFrontEnd )
				)
				( attribute "SEC_TYPE" "0402"
					( Origin gFrontEnd )
				)
				( attribute "TOLERANCE" "1%"
					( Origin gFrontEnd )
				)
				( attribute "VALUE" "10.0"
					( Origin gFrontEnd )
				)
				( attribute "VER" "1"
					( Origin gFrontEnd )
				)
				( attribute "WATTAGE" "1/16W"
					( Origin gFrontEnd )
				)
				( attribute "XY" "(-1675,1175)"
					( Origin gFrontEnd )
				)
				( attribute "CHIPS_PART_NAME" "RES"
					( Origin gPackager )
				)
				( attribute "CDS_PART_NAME" "RES_0402-10.0,1%,1/16W,CHIP,G2A"
					( Origin gPackager )
				)
				( objectStatus "R1B16" )
				( pin "a"
					( attribute "PN" "1"
						( Origin gPackager )
					)
					( objectStatus "R1B16.1" )
				)
				( pin "b"
					( attribute "PN" "2"
						( Origin gPackager )
					)
					( objectStatus "R1B16.2" )
				)
			)
			( gate "@baseboard_fab2_lib.baseboard_fab2(sch_1):page226_i36"
				( attribute "CDS_LIB" "mstr_discrete"
					( Origin gPackager )
				)
				( attribute "CDS_LOCATION" "C1B11"
					( Origin gPackager )
				)
				( attribute "CDS_SEC" "1"
					( Origin gPackager )
				)
				( attribute "LOCATION" "C1B11"
					( Origin gFrontEnd )
				)
				( attribute "MATERIAL" "X7R"
					( Origin gFrontEnd )
				)
				( attribute "PACK_TYPE" "0402LF"
					( Origin gFrontEnd )
				)
				( attribute "PART_NUMBER" "A36096-050"
					( Origin gFrontEnd )
				)
				( attribute "PHYS_PAGE" "226"
					( Origin gFrontEnd )
				)
				( attribute "ROOM" "VDDQ_KLM_PWR_VR"
					( Origin gFrontEnd )
				)
				( attribute "ROT" "2"
					( Origin gFrontEnd )
				)
				( attribute "SEC" "1"
					( Origin gFrontEnd )
				)
				( attribute "SEC_TYPE" "0402LF"
					( Origin gFrontEnd )
				)
				( attribute "TOLERANCE" "10%"
					( Origin gFrontEnd )
				)
				( attribute "VALUE" "220PF"
					( Origin gFrontEnd )
				)
				( attribute "VER" "1"
					( Origin gFrontEnd )
				)
				( attribute "VOLTAGE" "50V"
					( Units "uVoltage" "V" 1.000000)
					( Origin gFrontEnd )
				)
				( attribute "XY" "(25,725)"
					( Origin gFrontEnd )
				)
				( attribute "CHIPS_PART_NAME" "CAP"
					( Origin gPackager )
				)
				( attribute "CDS_PART_NAME" "CAP_0402LF-220PF,50V,10%,X7R,AA"
					( Origin gPackager )
				)
				( objectStatus "C1B11" )
				( pin "a"
					( attribute "PN" "1"
						( Origin gPackager )
					)
					( objectStatus "C1B11.1" )
				)
				( pin "b"
					( attribute "PN" "2"
						( Origin gPackager )
					)
					( objectStatus "C1B11.2" )
				)
			)
			( gate "@baseboard_fab2_lib.baseboard_fab2(sch_1):page226_i39"
				( attribute "CDS_LIB" "mstr_discrete"
					( Origin gPackager )
				)
				( attribute "CDS_LOCATION" "C1B12"
					( Origin gPackager )
				)
				( attribute "CDS_SEC" "1"
					( Origin gPackager )
				)
				( attribute "LOCATION" "C1B12"
					( Origin gFrontEnd )
				)
				( attribute "MATERIAL" "X7R"
					( Origin gFrontEnd )
				)
				( attribute "NO_XNET_CONNECTION" "1"
					( Origin gFrontEnd )
				)
				( attribute "PACK_TYPE" "0402LF"
					( Origin gFrontEnd )
				)
				( attribute "PART_NUMBER" "A36096-050"
					( Origin gFrontEnd )
				)
				( attribute "PHYS_PAGE" "226"
					( Origin gFrontEnd )
				)
				( attribute "ROOM" "VDDQ_KLM_PWR_VR"
					( Origin gFrontEnd )
				)
				( attribute "ROT" "0"
					( Origin gFrontEnd )
				)
				( attribute "SEC" "1"
					( Origin gFrontEnd )
				)
				( attribute "SEC_TYPE" "0402LF"
					( Origin gFrontEnd )
				)
				( attribute "TOLERANCE" "10%"
					( Origin gFrontEnd )
				)
				( attribute "VALUE" "220PF"
					( Origin gFrontEnd )
				)
				( attribute "VER" "1"
					( Origin gFrontEnd )
				)
				( attribute "VOLTAGE" "50V"
					( Units "uVoltage" "V" 1.000000)
					( Origin gFrontEnd )
				)
				( attribute "XY" "(-1500,1025)"
					( Origin gFrontEnd )
				)
				( attribute "CHIPS_PART_NAME" "CAP"
					( Origin gPackager )
				)
				( attribute "CDS_PART_NAME" "CAP_0402LF-220PF,50V,10%,X7R,AA"
					( Origin gPackager )
				)
				( objectStatus "C1B12" )
				( pin "a"
					( attribute "PN" "1"
						( Origin gPackager )
					)
					( objectStatus "C1B12.1" )
				)
				( pin "b"
					( attribute "PN" "2"
						( Origin gPackager )
					)
					( objectStatus "C1B12.2" )
				)
			)
			( gate "@baseboard_fab2_lib.baseboard_fab2(sch_1):page226_i41"
				( attribute "CDS_LIB" "dev_discrete"
					( Origin gPackager )
				)
				( attribute "CDS_LOCATION" "C1B3"
					( Origin gPackager )
				)
				( attribute "CDS_SEC" "1"
					( Origin gPackager )
				)
				( attribute "LOCATION" "C1B3"
					( Origin gFrontEnd )
				)
				( attribute "MATERIAL" "X6S"
					( Origin gFrontEnd )
				)
				( attribute "PACK_TYPE" "0402V"
					( Origin gFrontEnd )
				)
				( attribute "PART_NUMBER" "D97712-004"
					( Origin gFrontEnd )
				)
				( attribute "PHYS_PAGE" "226"
					( Origin gFrontEnd )
				)
				( attribute "ROOM" "VDDQ_KLM_PWR_VR"
					( Origin gFrontEnd )
				)
				( attribute "ROT" "0"
					( Origin gFrontEnd )
				)
				( attribute "SEC" "1"
					( Origin gFrontEnd )
				)
				( attribute "SEC_TYPE" "0402V"
					( Origin gFrontEnd )
				)
				( attribute "TOLERANCE" "10%"
					( Origin gFrontEnd )
				)
				( attribute "VALUE" "1.0UF"
					( Origin gFrontEnd )
				)
				( attribute "VER" "1"
					( Origin gFrontEnd )
				)
				( attribute "VOLTAGE" "6.3V"
					( Units "uVoltage" "V" 1.000000)
					( Origin gFrontEnd )
				)
				( attribute "XY" "(3750,150)"
					( Origin gFrontEnd )
				)
				( attribute "CHIPS_PART_NAME" "CAP_A"
					( Origin gPackager )
				)
				( attribute "CDS_PART_NAME" "CAP_A_0402V-1.0UF,6.3V,10%,X6SA"
					( Origin gPackager )
				)
				( objectStatus "C1B3" )
				( pin "a"
					( attribute "PN" "1"
						( Origin gPackager )
					)
					( objectStatus "C1B3.1" )
				)
				( pin "b"
					( attribute "PN" "2"
						( Origin gPackager )
					)
					( objectStatus "C1B3.2" )
				)
			)
			( gate "@baseboard_fab2_lib.baseboard_fab2(sch_1):page226_i44"
				( attribute "CDS_LIB" "dev_discrete"
					( Origin gPackager )
				)
				( attribute "CDS_LOCATION" "C1B2"
					( Origin gPackager )
				)
				( attribute "CDS_SEC" "1"
					( Origin gPackager )
				)
				( attribute "LOCATION" "C1B2"
					( Origin gFrontEnd )
				)
				( attribute "MATERIAL" "X7R"
					( Origin gFrontEnd )
				)
				( attribute "PACK_TYPE" "0402V"
					( Origin gFrontEnd )
				)
				( attribute "PART_NUMBER" "A36096-030"
					( Origin gFrontEnd )
				)
				( attribute "PHYS_PAGE" "226"
					( Origin gFrontEnd )
				)
				( attribute "ROOM" "VDDQ_KLM_PWR_VR"
					( Origin gFrontEnd )
				)
				( attribute "ROT" "0"
					( Origin gFrontEnd )
				)
				( attribute "SEC" "1"
					( Origin gFrontEnd )
				)
				( attribute "SEC_TYPE" "0402V"
					( Origin gFrontEnd )
				)
				( attribute "TOLERANCE" "10%"
					( Origin gFrontEnd )
				)
				( attribute "VALUE" "0.1UF"
					( Origin gFrontEnd )
				)
				( attribute "VER" "1"
					( Origin gFrontEnd )
				)
				( attribute "VOLTAGE" "16V"
					( Units "uVoltage" "V" 1.000000)
					( Origin gFrontEnd )
				)
				( attribute "XY" "(3350,175)"
					( Origin gFrontEnd )
				)
				( attribute "CHIPS_PART_NAME" "CAP_A"
					( Origin gPackager )
				)
				( attribute "CDS_PART_NAME" "CAP_A_0402V-0.1UF,16V,10%,X7R,A"
					( Origin gPackager )
				)
				( objectStatus "C1B2" )
				( pin "a"
					( attribute "PN" "1"
						( Origin gPackager )
					)
					( objectStatus "C1B2.1" )
				)
				( pin "b"
					( attribute "PN" "2"
						( Origin gPackager )
					)
					( objectStatus "C1B2.2" )
				)
			)
			( gate "@baseboard_fab2_lib.baseboard_fab2(sch_1):page226_i50"
				( attribute "CDS_LIB" "mstr_discrete"
					( Origin gPackager )
				)
				( attribute "CDS_LOCATION" "R9M6"
					( Origin gPackager )
				)
				( attribute "CDS_SEC" "1"
					( Origin gPackager )
				)
				( attribute "LOCATION" "R9M6"
					( Origin gFrontEnd )
				)
				( attribute "MATERIAL" "CHIP"
					( Origin gFrontEnd )
				)
				( attribute "PACK_TYPE" "0402"
					( Origin gFrontEnd )
				)
				( attribute "PART_NUMBER" "G21796-047"
					( Origin gFrontEnd )
				)
				( attribute "PHYS_PAGE" "226"
					( Origin gFrontEnd )
				)
				( attribute "ROOM" "VDDQ_KLM_PWR_VR"
					( Origin gFrontEnd )
				)
				( attribute "ROT" "0"
					( Origin gFrontEnd )
				)
				( attribute "SEC" "1"
					( Origin gFrontEnd )
				)
				( attribute "SEC_TYPE" "0402"
					( Origin gFrontEnd )
				)
				( attribute "TOLERANCE" "1%"
					( Origin gFrontEnd )
				)
				( attribute "VALUE" "49.9"
					( Origin gFrontEnd )
				)
				( attribute "VER" "2"
					( Origin gFrontEnd )
				)
				( attribute "WATTAGE" "1/16W"
					( Origin gFrontEnd )
				)
				( attribute "XY" "(-675,3550)"
					( Origin gFrontEnd )
				)
				( attribute "CHIPS_PART_NAME" "RES"
					( Origin gPackager )
				)
				( attribute "CDS_PART_NAME" "RES_0402-49.9,1%,1/16W,CHIP,G2A"
					( Origin gPackager )
				)
				( objectStatus "R9M6" )
				( pin "a"
					( attribute "PN" "1"
						( Origin gPackager )
					)
					( objectStatus "R9M6.1" )
				)
				( pin "b"
					( attribute "PN" "2"
						( Origin gPackager )
					)
					( objectStatus "R9M6.2" )
				)
			)
			( gate "@baseboard_fab2_lib.baseboard_fab2(sch_1):page226_i53"
				( attribute "CDS_LIB" "mstr_discrete"
					( Origin gPackager )
				)
				( attribute "CDS_LOCATION" "R1B8"
					( Origin gPackager )
				)
				( attribute "CDS_SEC" "1"
					( Origin gPackager )
				)
				( attribute "LOCATION" "R1B8"
					( Origin gFrontEnd )
				)
				( attribute "MATERIAL" "CHIP"
					( Origin gFrontEnd )
				)
				( attribute "PACK_TYPE" "0402"
					( Origin gFrontEnd )
				)
				( attribute "PART_NUMBER" "G21796-009"
					( Origin gFrontEnd )
				)
				( attribute "PHYS_PAGE" "226"
					( Origin gFrontEnd )
				)
				( attribute "ROOM" "VDDQ_KLM_PWR_VR"
					( Origin gFrontEnd )
				)
				( attribute "ROT" "0"
					( Origin gFrontEnd )
				)
				( attribute "SEC" "1"
					( Origin gFrontEnd )
				)
				( attribute "SEC_TYPE" "0402"
					( Origin gFrontEnd )
				)
				( attribute "TOLERANCE" "1%"
					( Origin gFrontEnd )
				)
				( attribute "VALUE" "150.0"
					( Origin gFrontEnd )
				)
				( attribute "VER" "1"
					( Origin gFrontEnd )
				)
				( attribute "WATTAGE" "1/16W"
					( Origin gFrontEnd )
				)
				( attribute "XY" "(-300,3050)"
					( Origin gFrontEnd )
				)
				( attribute "CHIPS_PART_NAME" "RES"
					( Origin gPackager )
				)
				( attribute "CDS_PART_NAME" "RES_0402-150.0,1%,1/16W,CHIP,GA"
					( Origin gPackager )
				)
				( objectStatus "R1B8" )
				( pin "a"
					( attribute "PN" "1"
						( Origin gPackager )
					)
					( objectStatus "R1B8.1" )
				)
				( pin "b"
					( attribute "PN" "2"
						( Origin gPackager )
					)
					( objectStatus "R1B8.2" )
				)
			)
			( gate "@baseboard_fab2_lib.baseboard_fab2(sch_1):page226_i57"
				( attribute "CDS_LIB" "mstr_discrete"
					( Origin gPackager )
				)
				( attribute "CDS_LOCATION" "R9M8"
					( Origin gPackager )
				)
				( attribute "CDS_SEC" "1"
					( Origin gPackager )
				)
				( attribute "LOCATION" "R9M8"
					( Origin gFrontEnd )
				)
				( attribute "MATERIAL" "CHIP"
					( Origin gFrontEnd )
				)
				( attribute "PACK_TYPE" "0402"
					( Origin gFrontEnd )
				)
				( attribute "PART_NUMBER" "G21796-160"
					( Origin gFrontEnd )
				)
				( attribute "PHYS_PAGE" "226"
					( Origin gFrontEnd )
				)
				( attribute "ROOM" "VDDQ_KLM_PWR_VR"
					( Origin gFrontEnd )
				)
				( attribute "ROT" "0"
					( Origin gFrontEnd )
				)
				( attribute "SEC" "1"
					( Origin gFrontEnd )
				)
				( attribute "SEC_TYPE" "0402"
					( Origin gFrontEnd )
				)
				( attribute "TOLERANCE" "1%"
					( Origin gFrontEnd )
				)
				( attribute "VALUE" "100.0K"
					( Origin gFrontEnd )
				)
				( attribute "VER" "2"
					( Origin gFrontEnd )
				)
				( attribute "WATTAGE" "1/16W"
					( Origin gFrontEnd )
				)
				( attribute "XY" "(-1250,3725)"
					( Origin gFrontEnd )
				)
				( attribute "CHIPS_PART_NAME" "RES"
					( Origin gPackager )
				)
				( attribute "CDS_PART_NAME" "RES_0402-100.0K,1%,1/16W,CHIP,B"
					( Origin gPackager )
				)
				( objectStatus "R9M8" )
				( pin "a"
					( attribute "PN" "1"
						( Origin gPackager )
					)
					( objectStatus "R9M8.1" )
				)
				( pin "b"
					( attribute "PN" "2"
						( Origin gPackager )
					)
					( objectStatus "R9M8.2" )
				)
			)
			( gate "@baseboard_fab2_lib.baseboard_fab2(sch_1):page226_i58"
				( attribute "CDS_LIB" "mstr_discrete"
					( Origin gPackager )
				)
				( attribute "CDS_LOCATION" "R1B9"
					( Origin gPackager )
				)
				( attribute "CDS_SEC" "1"
					( Origin gPackager )
				)
				( attribute "LOCATION" "R1B9"
					( Origin gFrontEnd )
				)
				( attribute "MATERIAL" "CHIP"
					( Origin gFrontEnd )
				)
				( attribute "PACK_TYPE" "0402"
					( Origin gFrontEnd )
				)
				( attribute "PART_NUMBER" "G21796-003"
					( Origin gFrontEnd )
				)
				( attribute "PHYS_PAGE" "226"
					( Origin gFrontEnd )
				)
				( attribute "ROOM" "VDDQ_KLM_PWR_VR"
					( Origin gFrontEnd )
				)
				( attribute "ROT" "0"
					( Origin gFrontEnd )
				)
				( attribute "SEC" "1"
					( Origin gFrontEnd )
				)
				( attribute "SEC_TYPE" "0402"
					( Origin gFrontEnd )
				)
				( attribute "TOLERANCE" "1%"
					( Origin gFrontEnd )
				)
				( attribute "VALUE" "1.5K"
					( Origin gFrontEnd )
				)
				( attribute "VER" "2"
					( Origin gFrontEnd )
				)
				( attribute "WATTAGE" "1/16W"
					( Origin gFrontEnd )
				)
				( attribute "XY" "(-1250,3325)"
					( Origin gFrontEnd )
				)
				( attribute "CHIPS_PART_NAME" "RES"
					( Origin gPackager )
				)
				( attribute "CDS_PART_NAME" "RES_0402-1.5K,1%,1/16W,CHIP,G2A"
					( Origin gPackager )
				)
				( objectStatus "R1B9" )
				( pin "a"
					( attribute "PN" "1"
						( Origin gPackager )
					)
					( objectStatus "R1B9.1" )
				)
				( pin "b"
					( attribute "PN" "2"
						( Origin gPackager )
					)
					( objectStatus "R1B9.2" )
				)
			)
			( gate "@baseboard_fab2_lib.baseboard_fab2(sch_1):page226_i59"
				( attribute "CDS_LIB" "mstr_discrete"
					( Origin gPackager )
				)
				( attribute "CDS_LOCATION" "C1B8"
					( Origin gPackager )
				)
				( attribute "CDS_SEC" "1"
					( Origin gPackager )
				)
				( attribute "LOCATION" "C1B8"
					( Origin gFrontEnd )
				)
				( attribute "MATERIAL" "X7R"
					( Origin gFrontEnd )
				)
				( attribute "PACK_TYPE" "0402LF"
					( Origin gFrontEnd )
				)
				( attribute "PART_NUMBER" "A36096-046"
					( Origin gFrontEnd )
				)
				( attribute "PHYS_PAGE" "226"
					( Origin gFrontEnd )
				)
				( attribute "ROOM" "VDDQ_KLM_PWR_VR"
					( Origin gFrontEnd )
				)
				( attribute "ROT" "2"
					( Origin gFrontEnd )
				)
				( attribute "SEC" "1"
					( Origin gFrontEnd )
				)
				( attribute "SEC_TYPE" "0402LF"
					( Origin gFrontEnd )
				)
				( attribute "TOLERANCE" "10%"
					( Origin gFrontEnd )
				)
				( attribute "VALUE" "1000PF"
					( Origin gFrontEnd )
				)
				( attribute "VER" "1"
					( Origin gFrontEnd )
				)
				( attribute "VOLTAGE" "50V"
					( Units "uVoltage" "V" 1.000000)
					( Origin gFrontEnd )
				)
				( attribute "XY" "(-1475,3375)"
					( Origin gFrontEnd )
				)
				( attribute "CHIPS_PART_NAME" "CAP"
					( Origin gPackager )
				)
				( attribute "CDS_PART_NAME" "CAP_0402LF-1000PF,50V,10%,X7R,A"
					( Origin gPackager )
				)
				( objectStatus "C1B8" )
				( pin "a"
					( attribute "PN" "1"
						( Origin gPackager )
					)
					( objectStatus "C1B8.1" )
				)
				( pin "b"
					( attribute "PN" "2"
						( Origin gPackager )
					)
					( objectStatus "C1B8.2" )
				)
			)
			( gate "@baseboard_fab2_lib.baseboard_fab2(sch_1):page226_i77"
				( attribute "CDS_LIB" "mstr_discrete"
					( Origin gPackager )
				)
				( attribute "CDS_LOCATION" "R1B15"
					( Origin gPackager )
				)
				( attribute "CDS_SEC" "1"
					( Origin gPackager )
				)
				( attribute "LOCATION" "R1B15"
					( Origin gFrontEnd )
				)
				( attribute "MATERIAL" "CHIP"
					( Origin gFrontEnd )
				)
				( attribute "PACK_TYPE" "0402"
					( Origin gFrontEnd )
				)
				( attribute "PART_NUMBER" "G21796-297"
					( Origin gFrontEnd )
				)
				( attribute "PHYS_PAGE" "226"
					( Origin gFrontEnd )
				)
				( attribute "ROOM" "VDDQ_KLM_PWR_VR"
					( Origin gFrontEnd )
				)
				( attribute "ROT" "0"
					( Origin gFrontEnd )
				)
				( attribute "SEC" "1"
					( Origin gPackager )
				)
				( attribute "TOLERANCE" "1.0%"
					( Origin gFrontEnd )
				)
				( attribute "VALUE" "5.36K"
					( Origin gFrontEnd )
				)
				( attribute "VER" "2"
					( Origin gFrontEnd )
				)
				( attribute "WATTAGE" "1/16W"
					( Origin gFrontEnd )
				)
				( attribute "XY" "(575,275)"
					( Origin gFrontEnd )
				)
				( attribute "CHIPS_PART_NAME" "RES"
					( Origin gPackager )
				)
				( attribute "CDS_PART_NAME" "RES_0402-5.36K,1.0%,1/16W,CHIPA"
					( Origin gPackager )
				)
				( objectStatus "R1B15" )
				( pin "a"
					( attribute "PN" "1"
						( Origin gPackager )
					)
					( objectStatus "R1B15.1" )
				)
				( pin "b"
					( attribute "PN" "2"
						( Origin gPackager )
					)
					( objectStatus "R1B15.2" )
				)
			)
			( gate "@baseboard_fab2_lib.baseboard_fab2(sch_1):page226_i78"
				( attribute "CDS_LIB" "mstr_discrete"
					( Origin gPackager )
				)
				( attribute "CDS_LOCATION" "R1B12"
					( Origin gPackager )
				)
				( attribute "CDS_SEC" "1"
					( Origin gPackager )
				)
				( attribute "LOCATION" "R1B12"
					( Origin gFrontEnd )
				)
				( attribute "MATERIAL" "CHIP"
					( Origin gFrontEnd )
				)
				( attribute "PACK_TYPE" "0402"
					( Origin gFrontEnd )
				)
				( attribute "PART_NUMBER" "G21796-043"
					( Origin gFrontEnd )
				)
				( attribute "PHYS_PAGE" "226"
					( Origin gFrontEnd )
				)
				( attribute "ROOM" "VDDQ_KLM_PWR_VR"
					( Origin gFrontEnd )
				)
				( attribute "ROT" "0"
					( Origin gFrontEnd )
				)
				( attribute "SEC" "1"
					( Origin gPackager )
				)
				( attribute "TOLERANCE" "1%"
					( Origin gFrontEnd )
				)
				( attribute "VALUE" "3.16K"
					( Origin gFrontEnd )
				)
				( attribute "VER" "2"
					( Origin gFrontEnd )
				)
				( attribute "WATTAGE" "1/16W"
					( Origin gFrontEnd )
				)
				( attribute "XY" "(200,275)"
					( Origin gFrontEnd )
				)
				( attribute "CHIPS_PART_NAME" "RES"
					( Origin gPackager )
				)
				( attribute "CDS_PART_NAME" "RES_0402-3.16K,1%,1/16W,CHIP,GA"
					( Origin gPackager )
				)
				( objectStatus "R1B12" )
				( pin "a"
					( attribute "PN" "1"
						( Origin gPackager )
					)
					( objectStatus "R1B12.1" )
				)
				( pin "b"
					( attribute "PN" "2"
						( Origin gPackager )
					)
					( objectStatus "R1B12.2" )
				)
			)
			( gate "@baseboard_fab2_lib.baseboard_fab2(sch_1):page226_i79"
				( attribute "CDS_LIB" "mstr_discrete"
					( Origin gPackager )
				)
				( attribute "CDS_LOCATION" "R1B1"
					( Origin gPackager )
				)
				( attribute "CDS_SEC" "1"
					( Origin gPackager )
				)
				( attribute "LOCATION" "R1B1"
					( Origin gFrontEnd )
				)
				( attribute "MATERIAL" "CHIP"
					( Origin gFrontEnd )
				)
				( attribute "PACK_TYPE" "0402"
					( Origin gFrontEnd )
				)
				( attribute "PART_NUMBER" "G21796-026"
					( Origin gFrontEnd )
				)
				( attribute "PHYS_PAGE" "226"
					( Origin gFrontEnd )
				)
				( attribute "ROOM" "RQ_PVDDQ_KLM_VRHOT_LVT3_N"
					( Origin gFrontEnd )
				)
				( attribute "ROT" "0"
					( Origin gFrontEnd )
				)
				( attribute "SEC" "1"
					( Origin gFrontEnd )
				)
				( attribute "SEC_TYPE" "0402"
					( Origin gFrontEnd )
				)
				( attribute "TOLERANCE" "1%"
					( Origin gFrontEnd )
				)
				( attribute "VALUE" "1.00K"
					( Origin gFrontEnd )
				)
				( attribute "VER" "2"
					( Origin gFrontEnd )
				)
				( attribute "WATTAGE" "1/16W"
					( Origin gFrontEnd )
				)
				( attribute "XY" "(2075,3025)"
					( Origin gFrontEnd )
				)
				( attribute "CHIPS_PART_NAME" "RES"
					( Origin gPackager )
				)
				( attribute "CDS_PART_NAME" "RES_0402-1.00K,1%,1/16W,CHIP,GA"
					( Origin gPackager )
				)
				( objectStatus "R1B1" )
				( pin "a"
					( attribute "PN" "1"
						( Origin gPackager )
					)
					( objectStatus "R1B1.1" )
				)
				( pin "b"
					( attribute "PN" "2"
						( Origin gPackager )
					)
					( objectStatus "R1B1.2" )
				)
			)
			( gate "@baseboard_fab2_lib.baseboard_fab2(sch_1):page226_i80"
				( attribute "CDS_LIB" "mstr_discrete"
					( Origin gPackager )
				)
				( attribute "CDS_LOCATION" "C1B4"
					( Origin gPackager )
				)
				( attribute "CDS_SEC" "1"
					( Origin gPackager )
				)
				( attribute "LOCATION" "C1B4"
					( Origin gFrontEnd )
				)
				( attribute "MATERIAL" "X7R"
					( Origin gFrontEnd )
				)
				( attribute "PACK_TYPE" "0402LF"
					( Origin gFrontEnd )
				)
				( attribute "PART_NUMBER" "A36096-046"
					( Origin gFrontEnd )
				)
				( attribute "PHYS_PAGE" "226"
					( Origin gFrontEnd )
				)
				( attribute "ROOM" "VDDQ_KLM_PWR_VR"
					( Origin gFrontEnd )
				)
				( attribute "ROT" "0"
					( Origin gFrontEnd )
				)
				( attribute "SEC" "1"
					( Origin gFrontEnd )
				)
				( attribute "SEC_TYPE" "0402LF"
					( Origin gFrontEnd )
				)
				( attribute "TOLERANCE" "10%"
					( Origin gFrontEnd )
				)
				( attribute "VALUE" "1000PF"
					( Origin gFrontEnd )
				)
				( attribute "VER" "1"
					( Origin gFrontEnd )
				)
				( attribute "VOLTAGE" "50V"
					( Units "uVoltage" "V" 1.000000)
					( Origin gFrontEnd )
				)
				( attribute "XY" "(2900,975)"
					( Origin gFrontEnd )
				)
				( attribute "CHIPS_PART_NAME" "CAP"
					( Origin gPackager )
				)
				( attribute "CDS_PART_NAME" "CAP_0402LF-1000PF,50V,10%,X7R,A"
					( Origin gPackager )
				)
				( objectStatus "C1B4" )
				( pin "a"
					( attribute "PN" "1"
						( Origin gPackager )
					)
					( objectStatus "C1B4.1" )
				)
				( pin "b"
					( attribute "PN" "2"
						( Origin gPackager )
					)
					( objectStatus "C1B4.2" )
				)
			)
			( gate "@baseboard_fab2_lib.baseboard_fab2(sch_1):page226_i82"
				( attribute "CDS_LIB" "mstr_discrete"
					( Origin gPackager )
				)
				( attribute "CDS_LOCATION" "R1B4"
					( Origin gPackager )
				)
				( attribute "CDS_SEC" "1"
					( Origin gPackager )
				)
				( attribute "LOCATION" "R1B4"
					( Origin gFrontEnd )
				)
				( attribute "MATERIAL" "CHIP"
					( Origin gFrontEnd )
				)
				( attribute "PACK_TYPE" "0402"
					( Origin gFrontEnd )
				)
				( attribute "PART_NUMBER" "G21796-074"
					( Origin gFrontEnd )
				)
				( attribute "PHYS_PAGE" "226"
					( Origin gFrontEnd )
				)
				( attribute "ROT" "0"
					( Origin gFrontEnd )
				)
				( attribute "SEC" "1"
					( Origin gFrontEnd )
				)
				( attribute "SEC_TYPE" "0402"
					( Origin gFrontEnd )
				)
				( attribute "TOLERANCE" "1%"
					( Origin gFrontEnd )
				)
				( attribute "VALUE" "33.2"
					( Origin gFrontEnd )
				)
				( attribute "VER" "1"
					( Origin gFrontEnd )
				)
				( attribute "WATTAGE" "1/16W"
					( Origin gFrontEnd )
				)
				( attribute "XY" "(3275,2425)"
					( Origin gFrontEnd )
				)
				( attribute "CHIPS_PART_NAME" "RES"
					( Origin gPackager )
				)
				( attribute "CDS_PART_NAME" "RES_0402-33.2,1%,1/16W,CHIP,G2A"
					( Origin gPackager )
				)
				( objectStatus "R1B4" )
				( pin "a"
					( attribute "PN" "1"
						( Origin gPackager )
					)
					( objectStatus "R1B4.1" )
				)
				( pin "b"
					( attribute "PN" "2"
						( Origin gPackager )
					)
					( objectStatus "R1B4.2" )
				)
			)
			( gate "@baseboard_fab2_lib.baseboard_fab2(sch_1):page226_i84"
				( attribute "CDS_LIB" "mstr_discrete"
					( Origin gPackager )
				)
				( attribute "CDS_LOCATION" "R9M9"
					( Origin gPackager )
				)
				( attribute "CDS_SEC" "1"
					( Origin gPackager )
				)
				( attribute "LOCATION" "R9M9"
					( Origin gFrontEnd )
				)
				( attribute "MATERIAL" "CHIP"
					( Origin gFrontEnd )
				)
				( attribute "PACK_TYPE" "0402"
					( Origin gFrontEnd )
				)
				( attribute "PART_NUMBER" "G21497-005"
					( Origin gFrontEnd )
				)
				( attribute "PHYS_PAGE" "226"
					( Origin gFrontEnd )
				)
				( attribute "ROOM" "PVCCIN_CPU0_VR"
					( Origin gFrontEnd )
				)
				( attribute "ROT" "0"
					( Origin gFrontEnd )
				)
				( attribute "SEC" "1"
					( Origin gPackager )
				)
				( attribute "TOLERANCE" "5%"
					( Origin gFrontEnd )
				)
				( attribute "VALUE" "0.0"
					( Origin gFrontEnd )
				)
				( attribute "VER" "1"
					( Origin gFrontEnd )
				)
				( attribute "WATTAGE" "1/16W"
					( Origin gFrontEnd )
				)
				( attribute "XY" "(-1550,1475)"
					( Origin gFrontEnd )
				)
				( attribute "CHIPS_PART_NAME" "RES"
					( Origin gPackager )
				)
				( attribute "CDS_PART_NAME" "RES_0402-0.0,5%,1/16W,CHIP,G21A"
					( Origin gPackager )
				)
				( objectStatus "R9M9" )
				( pin "a"
					( attribute "PN" "1"
						( Origin gPackager )
					)
					( objectStatus "R9M9.1" )
				)
				( pin "b"
					( attribute "PN" "2"
						( Origin gPackager )
					)
					( objectStatus "R9M9.2" )
				)
			)
			( gate "@baseboard_fab2_lib.baseboard_fab2(sch_1):page226_i85"
				( attribute "BOM_COST" "SM_CONTROLLER"
					( Origin gFrontEnd )
				)
				( attribute "CDS_LIB" "mstr_discrete"
					( Origin gPackager )
				)
				( attribute "CDS_LOCATION" "R9M5"
					( Origin gPackager )
				)
				( attribute "CDS_SEC" "1"
					( Origin gPackager )
				)
				( attribute "LOCATION" "R9M5"
					( Origin gFrontEnd )
				)
				( attribute "MATERIAL" "EMPTY"
					( Origin gFrontEnd )
				)
				( attribute "PACK_TYPE" "0402"
					( Origin gFrontEnd )
				)
				( attribute "PART_NUMBER" "G21796-010"
					( Origin gFrontEnd )
				)
				( attribute "PHYS_PAGE" "226"
					( Origin gFrontEnd )
				)
				( attribute "ROOM" "BMC"
					( Origin gFrontEnd )
				)
				( attribute "ROT" "0"
					( Origin gFrontEnd )
				)
				( attribute "SEC" "1"
					( Origin gFrontEnd )
				)
				( attribute "SEC_TYPE" "0402"
					( Origin gFrontEnd )
				)
				( attribute "TOLERANCE" "1%"
					( Origin gFrontEnd )
				)
				( attribute "VALUE" "100.0K"
					( Origin gFrontEnd )
				)
				( attribute "VER" "2"
					( Origin gFrontEnd )
				)
				( attribute "WATTAGE" "1/16W"
					( Origin gFrontEnd )
				)
				( attribute "XY" "(75,3550)"
					( Origin gFrontEnd )
				)
				( attribute "CHIPS_PART_NAME" "RES"
					( Origin gPackager )
				)
				( attribute "CDS_PART_NAME" "RES_0402-100.0K,1%,1/16W,EMPTYA"
					( Origin gPackager )
				)
				( objectStatus "R9M5" )
				( pin "a"
					( attribute "PN" "1"
						( Origin gPackager )
					)
					( objectStatus "R9M5.1" )
				)
				( pin "b"
					( attribute "PN" "2"
						( Origin gPackager )
					)
					( objectStatus "R9M5.2" )
				)
			)
			( gate "@baseboard_fab2_lib.baseboard_fab2(sch_1):page226_i87"
				( attribute "CDS_LIB" "mstr_discrete"
					( Origin gPackager )
				)
				( attribute "CDS_LOCATION" "R9M11"
					( Origin gPackager )
				)
				( attribute "CDS_SEC" "1"
					( Origin gPackager )
				)
				( attribute "LOCATION" "R9M11"
					( Origin gFrontEnd )
				)
				( attribute "MATERIAL" "CHIP"
					( Origin gFrontEnd )
				)
				( attribute "PACK_TYPE" "0402"
					( Origin gFrontEnd )
				)
				( attribute "PART_NUMBER" "G21497-005"
					( Origin gFrontEnd )
				)
				( attribute "PHYS_PAGE" "226"
					( Origin gFrontEnd )
				)
				( attribute "ROOM" "PVCCIN_CPU0_VR"
					( Origin gFrontEnd )
				)
				( attribute "ROT" "0"
					( Origin gFrontEnd )
				)
				( attribute "SEC" "1"
					( Origin gPackager )
				)
				( attribute "TOLERANCE" "5%"
					( Origin gFrontEnd )
				)
				( attribute "VALUE" "0.0"
					( Origin gFrontEnd )
				)
				( attribute "VER" "1"
					( Origin gFrontEnd )
				)
				( attribute "WATTAGE" "1/16W"
					( Origin gFrontEnd )
				)
				( attribute "XY" "(-1625,2725)"
					( Origin gFrontEnd )
				)
				( attribute "CHIPS_PART_NAME" "RES"
					( Origin gPackager )
				)
				( attribute "CDS_PART_NAME" "RES_0402-0.0,5%,1/16W,CHIP,G21A"
					( Origin gPackager )
				)
				( objectStatus "R9M11" )
				( pin "a"
					( attribute "PN" "1"
						( Origin gPackager )
					)
					( objectStatus "R9M11.1" )
				)
				( pin "b"
					( attribute "PN" "2"
						( Origin gPackager )
					)
					( objectStatus "R9M11.2" )
				)
			)
			( gate "@baseboard_fab2_lib.baseboard_fab2(sch_1):page226_i88"
				( attribute "CDS_LIB" "mstr_discrete"
					( Origin gPackager )
				)
				( attribute "CDS_LOCATION" "R9M10"
					( Origin gPackager )
				)
				( attribute "CDS_SEC" "1"
					( Origin gPackager )
				)
				( attribute "LOCATION" "R9M10"
					( Origin gFrontEnd )
				)
				( attribute "MATERIAL" "CHIP"
					( Origin gFrontEnd )
				)
				( attribute "PACK_TYPE" "0402"
					( Origin gFrontEnd )
				)
				( attribute "PART_NUMBER" "G21497-005"
					( Origin gFrontEnd )
				)
				( attribute "PHYS_PAGE" "226"
					( Origin gFrontEnd )
				)
				( attribute "ROOM" "PVCCIN_CPU0_VR"
					( Origin gFrontEnd )
				)
				( attribute "ROT" "0"
					( Origin gFrontEnd )
				)
				( attribute "SEC" "1"
					( Origin gPackager )
				)
				( attribute "TOLERANCE" "5%"
					( Origin gFrontEnd )
				)
				( attribute "VALUE" "0.0"
					( Origin gFrontEnd )
				)
				( attribute "VER" "1"
					( Origin gFrontEnd )
				)
				( attribute "WATTAGE" "1/16W"
					( Origin gFrontEnd )
				)
				( attribute "XY" "(-825,2875)"
					( Origin gFrontEnd )
				)
				( attribute "CHIPS_PART_NAME" "RES"
					( Origin gPackager )
				)
				( attribute "CDS_PART_NAME" "RES_0402-0.0,5%,1/16W,CHIP,G21A"
					( Origin gPackager )
				)
				( objectStatus "R9M10" )
				( pin "a"
					( attribute "PN" "1"
						( Origin gPackager )
					)
					( objectStatus "R9M10.1" )
				)
				( pin "b"
					( attribute "PN" "2"
						( Origin gPackager )
					)
					( objectStatus "R9M10.2" )
				)
			)
			( gate "@baseboard_fab2_lib.baseboard_fab2(sch_1):page226_i90"
				( attribute "CDS_LIB" "mstr_controller"
					( Origin gPackager )
				)
				( attribute "CDS_LMAN_SYM_OUTLINE" "-400,900,400,-900"
					( Origin gPackager )
				)
				( attribute "CDS_LOCATION" "EU1B1"
					( Origin gPackager )
				)
				( attribute "CDS_SEC" "1"
					( Origin gPackager )
				)
				( attribute "LOCATION" "EU1B1"
					( Origin gFrontEnd )
				)
				( attribute "MATERIAL" "IC"
					( Origin gFrontEnd )
				)
				( attribute "PACK_TYPE" "QFN"
					( Origin gFrontEnd )
				)
				( attribute "PART_NUMBER" "H89186-001"
					( Origin gFrontEnd )
				)
				( attribute "PHYS_PAGE" "226"
					( Origin gFrontEnd )
				)
				( attribute "ROT" "0"
					( Origin gFrontEnd )
				)
				( attribute "SEC" "1"
					( Origin gFrontEnd )
				)
				( attribute "SEC_TYPE" "QFN"
					( Origin gFrontEnd )
				)
				( attribute "VER" "2"
					( Origin gFrontEnd )
				)
				( attribute "XY" "(1425,1775)"
					( Origin gFrontEnd )
				)
				( attribute "CHIPS_PART_NAME" "PXM1310B"
					( Origin gPackager )
				)
				( attribute "CDS_PART_NAME" "PXM1310B_QFN-IC,H89186-001"
					( Origin gPackager )
				)
				( objectStatus "EU1B1" )
				( pin "airef1"
					( attribute "PN" "21"
						( Origin gPackager )
					)
					( objectStatus "EU1B1.21" )
				)
				( pin "airef2"
					( attribute "PN" "23"
						( Origin gPackager )
					)
					( objectStatus "EU1B1.23" )
				)
				( pin "airef3"
					( attribute "PN" "25"
						( Origin gPackager )
					)
					( objectStatus "EU1B1.25" )
				)
				( pin "aisen1"
					( attribute "PN" "22"
						( Origin gPackager )
					)
					( objectStatus "EU1B1.22" )
				)
				( pin "aisen2"
					( attribute "PN" "24"
						( Origin gPackager )
					)
					( objectStatus "EU1B1.24" )
				)
				( pin "aisen3"
					( attribute "PN" "26"
						( Origin gPackager )
					)
					( objectStatus "EU1B1.26" )
				)
				( pin "apwm1"
					( attribute "PN" "5"
						( Origin gPackager )
					)
					( objectStatus "EU1B1.5" )
				)
				( pin "apwm2"
					( attribute "PN" "4"
						( Origin gPackager )
					)
					( objectStatus "EU1B1.4" )
				)
				( pin "apwm3"
					( attribute "PN" "3"
						( Origin gPackager )
					)
					( objectStatus "EU1B1.3" )
				)
				( pin "atsen"
					( attribute "PN" "35"
						( Origin gPackager )
					)
					( objectStatus "EU1B1.35" )
				)
				( pin "avref"
					( attribute "PN" "20"
						( Origin gPackager )
					)
					( objectStatus "EU1B1.20" )
				)
				( pin "avren"
					( attribute "PN" "10"
						( Origin gPackager )
					)
					( objectStatus "EU1B1.10" )
				)
				( pin "avrrdy"
					( attribute "PN" "9"
						( Origin gPackager )
					)
					( objectStatus "EU1B1.9" )
				)
				( pin "avsen"
					( attribute "PN" "19"
						( Origin gPackager )
					)
					( objectStatus "EU1B1.19" )
				)
				( pin "biref1"
					( attribute "PN" "31"
						( Origin gPackager )
					)
					( objectStatus "EU1B1.31" )
				)
				( pin "bisen1"
					( attribute "PN" "32"
						( Origin gPackager )
					)
					( objectStatus "EU1B1.32" )
				)
				( pin "bpwm1"
					( attribute "PN" "1"
						( Origin gPackager )
					)
					( objectStatus "EU1B1.1" )
				)
				( pin "btsen"
					( attribute "PN" "34"
						( Origin gPackager )
					)
					( objectStatus "EU1B1.34" )
				)
				( pin "bvref"
					( attribute "PN" "30"
						( Origin gPackager )
					)
					( objectStatus "EU1B1.30" )
				)
				( pin "bvsen"
					( attribute "PN" "29"
						( Origin gPackager )
					)
					( objectStatus "EU1B1.29" )
				)
				( pin "dnc(0)"
					( attribute "PN" "2"
						( Origin gPackager )
					)
					( objectStatus "EU1B1.2" )
				)
				( pin "dnc(1)"
					( attribute "PN" "28"
						( Origin gPackager )
					)
					( objectStatus "EU1B1.28" )
				)
				( pin "gnd"
					( attribute "PN" "27"
						( Origin gPackager )
					)
					( objectStatus "EU1B1.27" )
				)
				( pin "iinsen"
					( attribute "PN" "38"
						( Origin gPackager )
					)
					( objectStatus "EU1B1.38" )
				)
				( pin "mp0"
					( attribute "PN" "13"
						( Origin gPackager )
					)
					( objectStatus "EU1B1.13" )
				)
				( pin "mp1"
					( attribute "PN" "14"
						( Origin gPackager )
					)
					( objectStatus "EU1B1.14" )
				)
				( pin "mp2"
					( attribute "PN" "18"
						( Origin gPackager )
					)
					( objectStatus "EU1B1.18" )
				)
				( pin "pinalrt_n"
					( attribute "PN" "12"
						( Origin gPackager )
					)
					( objectStatus "EU1B1.12" )
				)
				( pin "reset_n"
					( attribute "PN" "8"
						( Origin gPackager )
					)
					( objectStatus "EU1B1.8" )
				)
				( pin "scl"
					( attribute "PN" "7"
						( Origin gPackager )
					)
					( objectStatus "EU1B1.7" )
				)
				( pin "sda"
					( attribute "PN" "6"
						( Origin gPackager )
					)
					( objectStatus "EU1B1.6" )
				)
				( pin "thpad"
					( attribute "PN" "41"
						( Origin gPackager )
					)
					( objectStatus "EU1B1.41" )
				)
				( pin "valrt_n"
					( attribute "PN" "17"
						( Origin gPackager )
					)
					( objectStatus "EU1B1.17" )
				)
				( pin "vclk"
					( attribute "PN" "15"
						( Origin gPackager )
					)
					( objectStatus "EU1B1.15" )
				)
				( pin "vd12"
					( attribute "PN" "40"
						( Origin gPackager )
					)
					( objectStatus "EU1B1.40" )
				)
				( pin "vdd"
					( attribute "PN" "39"
						( Origin gPackager )
					)
					( objectStatus "EU1B1.39" )
				)
				( pin "vdio"
					( attribute "PN" "16"
						( Origin gPackager )
					)
					( objectStatus "EU1B1.16" )
				)
				( pin "vinsen"
					( attribute "PN" "37"
						( Origin gPackager )
					)
					( objectStatus "EU1B1.37" )
				)
				( pin "vrhot_n"
					( attribute "PN" "11"
						( Origin gPackager )
					)
					( objectStatus "EU1B1.11" )
				)
				( pin "xaddr1"
					( attribute "PN" "36"
						( Origin gPackager )
					)
					( objectStatus "EU1B1.36" )
				)
				( pin "xaddr2"
					( attribute "PN" "33"
						( Origin gPackager )
					)
					( objectStatus "EU1B1.33" )
				)
			)
			( gate "@baseboard_fab2_lib.baseboard_fab2(sch_1):page226_i92"
				( attribute "CDS_LIB" "dev_discrete"
					( Origin gPackager )
				)
				( attribute "CDS_LOCATION" "C9M11"
					( Origin gPackager )
				)
				( attribute "CDS_SEC" "1"
					( Origin gPackager )
				)
				( attribute "LOCATION" "C9M11"
					( Origin gFrontEnd )
				)
				( attribute "MATERIAL" "X7R"
					( Origin gFrontEnd )
				)
				( attribute "PACK_TYPE" "0402V"
					( Origin gFrontEnd )
				)
				( attribute "PART_NUMBER" "A36096-030"
					( Origin gFrontEnd )
				)
				( attribute "PHYS_PAGE" "226"
					( Origin gFrontEnd )
				)
				( attribute "ROOM" "VDDQ_KLM_PWR_VR"
					( Origin gFrontEnd )
				)
				( attribute "ROT" "2"
					( Origin gFrontEnd )
				)
				( attribute "SEC" "1"
					( Origin gFrontEnd )
				)
				( attribute "SEC_TYPE" "0402V"
					( Origin gFrontEnd )
				)
				( attribute "TOLERANCE" "10%"
					( Origin gFrontEnd )
				)
				( attribute "VALUE" "0.1UF"
					( Origin gFrontEnd )
				)
				( attribute "VER" "1"
					( Origin gFrontEnd )
				)
				( attribute "VOLTAGE" "16V"
					( Units "uVoltage" "V" 1.000000)
					( Origin gFrontEnd )
				)
				( attribute "XY" "(-425,425)"
					( Origin gFrontEnd )
				)
				( attribute "CHIPS_PART_NAME" "CAP_A"
					( Origin gPackager )
				)
				( attribute "CDS_PART_NAME" "CAP_A_0402V-0.1UF,16V,10%,X7R,A"
					( Origin gPackager )
				)
				( objectStatus "C9M11" )
				( pin "a"
					( attribute "PN" "1"
						( Origin gPackager )
					)
					( objectStatus "C9M11.1" )
				)
				( pin "b"
					( attribute "PN" "2"
						( Origin gPackager )
					)
					( objectStatus "C9M11.2" )
				)
			)
			( gate "@baseboard_fab2_lib.baseboard_fab2(sch_1):page227_i6"
				( attribute "BOM_COST" "VDDQ_KLM_PWR_VR"
					( Origin gFrontEnd )
				)
				( attribute "CDS_LIB" "mstr_discrete"
					( Origin gPackager )
				)
				( attribute "CDS_LOCATION" "C1A12"
					( Origin gPackager )
				)
				( attribute "CDS_SEC" "1"
					( Origin gPackager )
				)
				( attribute "LOCATION" "C1A12"
					( Origin gFrontEnd )
				)
				( attribute "MATERIAL" "X6S"
					( Origin gFrontEnd )
				)
				( attribute "PACK_TYPE" "0805LF"
					( Origin gFrontEnd )
				)
				( attribute "PART_NUMBER" "C95333-002"
					( Origin gFrontEnd )
				)
				( attribute "PHYS_PAGE" "227"
					( Origin gFrontEnd )
				)
				( attribute "ROOM" "VDDQ_KLM_PWR_VR"
					( Origin gFrontEnd )
				)
				( attribute "ROT" "0"
					( Origin gFrontEnd )
				)
				( attribute "SEC" "1"
					( Origin gFrontEnd )
				)
				( attribute "SEC_TYPE" "0805LF"
					( Origin gFrontEnd )
				)
				( attribute "TOLERANCE" "20%"
					( Origin gFrontEnd )
				)
				( attribute "VALUE" "22UF"
					( Origin gFrontEnd )
				)
				( attribute "VER" "1"
					( Origin gFrontEnd )
				)
				( attribute "VOLTAGE" "4V"
					( Units "uVoltage" "V" 1.000000)
					( Origin gFrontEnd )
				)
				( attribute "XY" "(4025,1650)"
					( Origin gFrontEnd )
				)
				( attribute "CHIPS_PART_NAME" "CAP"
					( Origin gPackager )
				)
				( attribute "CDS_PART_NAME" "CAP_0805LF-22UF,4V,20%,X6S,C95A"
					( Origin gPackager )
				)
				( objectStatus "C1A12" )
				( pin "a"
					( attribute "PN" "1"
						( Origin gPackager )
					)
					( objectStatus "C1A12.1" )
				)
				( pin "b"
					( attribute "PN" "2"
						( Origin gPackager )
					)
					( objectStatus "C1A12.2" )
				)
			)
			( gate "@baseboard_fab2_lib.baseboard_fab2(sch_1):page227_i44"
				( attribute "CDS_LIB" "mstr_discrete"
					( Origin gPackager )
				)
				( attribute "CDS_LOCATION" "C1A18"
					( Origin gPackager )
				)
				( attribute "CDS_SEC" "1"
					( Origin gPackager )
				)
				( attribute "LOCATION" "C1A18"
					( Origin gFrontEnd )
				)
				( attribute "MATERIAL" "X7R"
					( Origin gFrontEnd )
				)
				( attribute "PACK_TYPE" "0402"
					( Origin gFrontEnd )
				)
				( attribute "PART_NUMBER" "A36096-104"
					( Origin gFrontEnd )
				)
				( attribute "PHYS_PAGE" "227"
					( Origin gFrontEnd )
				)
				( attribute "ROOM" "VDDQ_KLM_PWR_VR"
					( Origin gFrontEnd )
				)
				( attribute "ROT" "2"
					( Origin gFrontEnd )
				)
				( attribute "SEC" "1"
					( Origin gFrontEnd )
				)
				( attribute "SEC_TYPE" "0402"
					( Origin gFrontEnd )
				)
				( attribute "SPOF" "TRUE"
					( Origin gFrontEnd )
				)
				( attribute "TOLERANCE" "10%"
					( Origin gFrontEnd )
				)
				( attribute "VALUE" "0.220UF"
					( Origin gFrontEnd )
				)
				( attribute "VER" "1"
					( Origin gFrontEnd )
				)
				( attribute "VOLTAGE" "16V"
					( Units "uVoltage" "V" 1.000000)
					( Origin gFrontEnd )
				)
				( attribute "XY" "(-950,1850)"
					( Origin gFrontEnd )
				)
				( attribute "CHIPS_PART_NAME" "CAP"
					( Origin gPackager )
				)
				( attribute "CDS_PART_NAME" "CAP_0402-0.220UF,16V,10%,X7R,AA"
					( Origin gPackager )
				)
				( objectStatus "C1A18" )
				( pin "a"
					( attribute "PN" "1"
						( Origin gPackager )
					)
					( objectStatus "C1A18.1" )
				)
				( pin "b"
					( attribute "PN" "2"
						( Origin gPackager )
					)
					( objectStatus "C1A18.2" )
				)
			)
			( gate "@baseboard_fab2_lib.baseboard_fab2(sch_1):page227_i45"
				( attribute "CDS_LIB" "mstr_discrete"
					( Origin gPackager )
				)
				( attribute "CDS_LOCATION" "C9L11"
					( Origin gPackager )
				)
				( attribute "CDS_SEC" "1"
					( Origin gPackager )
				)
				( attribute "LOCATION" "C9L11"
					( Origin gFrontEnd )
				)
				( attribute "MATERIAL" "X6S"
					( Origin gFrontEnd )
				)
				( attribute "PACK_TYPE" "0805"
					( Origin gFrontEnd )
				)
				( attribute "PART_NUMBER" "C95333-007"
					( Origin gFrontEnd )
				)
				( attribute "PHYS_PAGE" "227"
					( Origin gFrontEnd )
				)
				( attribute "ROOM" "VDDQ_KLM_PWR_VR"
					( Origin gFrontEnd )
				)
				( attribute "ROT" "0"
					( Origin gFrontEnd )
				)
				( attribute "SEC" "1"
					( Origin gFrontEnd )
				)
				( attribute "SEC_TYPE" "0805"
					( Origin gFrontEnd )
				)
				( attribute "TOLERANCE" "10%"
					( Origin gFrontEnd )
				)
				( attribute "VALUE" "10UF"
					( Origin gFrontEnd )
				)
				( attribute "VER" "1"
					( Origin gFrontEnd )
				)
				( attribute "VOLTAGE" "16V"
					( Units "uVoltage" "V" 1.000000)
					( Origin gFrontEnd )
				)
				( attribute "XY" "(-2650,2450)"
					( Origin gFrontEnd )
				)
				( attribute "CHIPS_PART_NAME" "CAP"
					( Origin gPackager )
				)
				( attribute "CDS_PART_NAME" "CAP_0805-10UF,16V,10%,X6S,C953A"
					( Origin gPackager )
				)
				( objectStatus "C9L11" )
				( pin "a"
					( attribute "PN" "1"
						( Origin gPackager )
					)
					( objectStatus "C9L11.1" )
				)
				( pin "b"
					( attribute "PN" "2"
						( Origin gPackager )
					)
					( objectStatus "C9L11.2" )
				)
			)
			( gate "@baseboard_fab2_lib.baseboard_fab2(sch_1):page227_i46"
				( attribute "CDS_LIB" "mstr_discrete"
					( Origin gPackager )
				)
				( attribute "CDS_LOCATION" "C9L10"
					( Origin gPackager )
				)
				( attribute "CDS_SEC" "1"
					( Origin gPackager )
				)
				( attribute "LOCATION" "C9L10"
					( Origin gFrontEnd )
				)
				( attribute "MATERIAL" "X6S"
					( Origin gFrontEnd )
				)
				( attribute "PACK_TYPE" "0805"
					( Origin gFrontEnd )
				)
				( attribute "PART_NUMBER" "C95333-007"
					( Origin gFrontEnd )
				)
				( attribute "PHYS_PAGE" "227"
					( Origin gFrontEnd )
				)
				( attribute "ROOM" "VDDQ_KLM_PWR_VR"
					( Origin gFrontEnd )
				)
				( attribute "ROT" "0"
					( Origin gFrontEnd )
				)
				( attribute "SEC" "1"
					( Origin gFrontEnd )
				)
				( attribute "SEC_TYPE" "0805"
					( Origin gFrontEnd )
				)
				( attribute "TOLERANCE" "10%"
					( Origin gFrontEnd )
				)
				( attribute "VALUE" "10UF"
					( Origin gFrontEnd )
				)
				( attribute "VER" "1"
					( Origin gFrontEnd )
				)
				( attribute "VOLTAGE" "16V"
					( Units "uVoltage" "V" 1.000000)
					( Origin gFrontEnd )
				)
				( attribute "XY" "(-2400,2400)"
					( Origin gFrontEnd )
				)
				( attribute "CHIPS_PART_NAME" "CAP"
					( Origin gPackager )
				)
				( attribute "CDS_PART_NAME" "CAP_0805-10UF,16V,10%,X6S,C953A"
					( Origin gPackager )
				)
				( objectStatus "C9L10" )
				( pin "a"
					( attribute "PN" "1"
						( Origin gPackager )
					)
					( objectStatus "C9L10.1" )
				)
				( pin "b"
					( attribute "PN" "2"
						( Origin gPackager )
					)
					( objectStatus "C9L10.2" )
				)
			)
			( gate "@baseboard_fab2_lib.baseboard_fab2(sch_1):page227_i47"
				( attribute "CDS_LIB" "mstr_discrete"
					( Origin gPackager )
				)
				( attribute "CDS_LOCATION" "C9L6"
					( Origin gPackager )
				)
				( attribute "CDS_SEC" "1"
					( Origin gPackager )
				)
				( attribute "LOCATION" "C9L6"
					( Origin gFrontEnd )
				)
				( attribute "MATERIAL" "X6S"
					( Origin gFrontEnd )
				)
				( attribute "PACK_TYPE" "0805"
					( Origin gFrontEnd )
				)
				( attribute "PART_NUMBER" "C95333-007"
					( Origin gFrontEnd )
				)
				( attribute "PHYS_PAGE" "227"
					( Origin gFrontEnd )
				)
				( attribute "ROOM" "VDDQ_KLM_PWR_VR"
					( Origin gFrontEnd )
				)
				( attribute "ROT" "0"
					( Origin gFrontEnd )
				)
				( attribute "SEC" "1"
					( Origin gFrontEnd )
				)
				( attribute "SEC_TYPE" "0805"
					( Origin gFrontEnd )
				)
				( attribute "TOLERANCE" "10%"
					( Origin gFrontEnd )
				)
				( attribute "VALUE" "10UF"
					( Origin gFrontEnd )
				)
				( attribute "VER" "1"
					( Origin gFrontEnd )
				)
				( attribute "VOLTAGE" "16V"
					( Units "uVoltage" "V" 1.000000)
					( Origin gFrontEnd )
				)
				( attribute "XY" "(-2175,2425)"
					( Origin gFrontEnd )
				)
				( attribute "CHIPS_PART_NAME" "CAP"
					( Origin gPackager )
				)
				( attribute "CDS_PART_NAME" "CAP_0805-10UF,16V,10%,X6S,C953A"
					( Origin gPackager )
				)
				( objectStatus "C9L6" )
				( pin "a"
					( attribute "PN" "1"
						( Origin gPackager )
					)
					( objectStatus "C9L6.1" )
				)
				( pin "b"
					( attribute "PN" "2"
						( Origin gPackager )
					)
					( objectStatus "C9L6.2" )
				)
			)
			( gate "@baseboard_fab2_lib.baseboard_fab2(sch_1):page227_i48"
				( attribute "CDS_LIB" "mstr_discrete"
					( Origin gPackager )
				)
				( attribute "CDS_LOCATION" "C1A19"
					( Origin gPackager )
				)
				( attribute "CDS_SEC" "1"
					( Origin gPackager )
				)
				( attribute "LOCATION" "C1A19"
					( Origin gFrontEnd )
				)
				( attribute "MATERIAL" "X6S"
					( Origin gFrontEnd )
				)
				( attribute "PACK_TYPE" "0402"
					( Origin gFrontEnd )
				)
				( attribute "PART_NUMBER" "D97712-011"
					( Origin gFrontEnd )
				)
				( attribute "PHYS_PAGE" "227"
					( Origin gFrontEnd )
				)
				( attribute "ROOM" "VDDQ_KLM_PWR_VR"
					( Origin gFrontEnd )
				)
				( attribute "ROT" "0"
					( Origin gFrontEnd )
				)
				( attribute "SEC" "1"
					( Origin gFrontEnd )
				)
				( attribute "SEC_TYPE" "0402"
					( Origin gFrontEnd )
				)
				( attribute "TOLERANCE" "10%"
					( Origin gFrontEnd )
				)
				( attribute "VALUE" "1.0UF"
					( Origin gFrontEnd )
				)
				( attribute "VER" "1"
					( Origin gFrontEnd )
				)
				( attribute "VOLTAGE" "16V"
					( Units "uVoltage" "V" 1.000000)
					( Origin gFrontEnd )
				)
				( attribute "XY" "(-1900,2425)"
					( Origin gFrontEnd )
				)
				( attribute "CHIPS_PART_NAME" "CAP"
					( Origin gPackager )
				)
				( attribute "CDS_PART_NAME" "CAP_0402-1.0UF,16V,10%,X6S,D97A"
					( Origin gPackager )
				)
				( objectStatus "C1A19" )
				( pin "a"
					( attribute "PN" "1"
						( Origin gPackager )
					)
					( objectStatus "C1A19.1" )
				)
				( pin "b"
					( attribute "PN" "2"
						( Origin gPackager )
					)
					( objectStatus "C1A19.2" )
				)
			)
			( gate "@baseboard_fab2_lib.baseboard_fab2(sch_1):page227_i50"
				( attribute "CDS_LIB" "mstr_discrete"
					( Origin gPackager )
				)
				( attribute "CDS_LOCATION" "C1B20"
					( Origin gPackager )
				)
				( attribute "CDS_SEC" "1"
					( Origin gPackager )
				)
				( attribute "LOCATION" "C1B20"
					( Origin gFrontEnd )
				)
				( attribute "MATERIAL" "X6S"
					( Origin gFrontEnd )
				)
				( attribute "PACK_TYPE" "0402"
					( Origin gFrontEnd )
				)
				( attribute "PART_NUMBER" "D97712-011"
					( Origin gFrontEnd )
				)
				( attribute "PHYS_PAGE" "227"
					( Origin gFrontEnd )
				)
				( attribute "ROOM" "VDDQ_KLM_PWR_VR"
					( Origin gFrontEnd )
				)
				( attribute "ROT" "0"
					( Origin gFrontEnd )
				)
				( attribute "SEC" "1"
					( Origin gFrontEnd )
				)
				( attribute "SEC_TYPE" "0402"
					( Origin gFrontEnd )
				)
				( attribute "TOLERANCE" "10%"
					( Origin gFrontEnd )
				)
				( attribute "VALUE" "1.0UF"
					( Origin gFrontEnd )
				)
				( attribute "VER" "1"
					( Origin gFrontEnd )
				)
				( attribute "VOLTAGE" "16V"
					( Units "uVoltage" "V" 1.000000)
					( Origin gFrontEnd )
				)
				( attribute "XY" "(-1350,2425)"
					( Origin gFrontEnd )
				)
				( attribute "CHIPS_PART_NAME" "CAP"
					( Origin gPackager )
				)
				( attribute "CDS_PART_NAME" "CAP_0402-1.0UF,16V,10%,X6S,D97A"
					( Origin gPackager )
				)
				( objectStatus "C1B20" )
				( pin "a"
					( attribute "PN" "1"
						( Origin gPackager )
					)
					( objectStatus "C1B20.1" )
				)
				( pin "b"
					( attribute "PN" "2"
						( Origin gPackager )
					)
					( objectStatus "C1B20.2" )
				)
			)
			( gate "@baseboard_fab2_lib.baseboard_fab2(sch_1):page227_i51"
				( attribute "CDS_LIB" "dev_discrete"
					( Origin gPackager )
				)
				( attribute "CDS_LOCATION" "C1A10"
					( Origin gPackager )
				)
				( attribute "CDS_SEC" "1"
					( Origin gPackager )
				)
				( attribute "LOCATION" "C1A10"
					( Origin gFrontEnd )
				)
				( attribute "MATERIAL" "X7R"
					( Origin gFrontEnd )
				)
				( attribute "PACK_TYPE" "0402V"
					( Origin gFrontEnd )
				)
				( attribute "PART_NUMBER" "A36096-030"
					( Origin gFrontEnd )
				)
				( attribute "PHYS_PAGE" "227"
					( Origin gFrontEnd )
				)
				( attribute "ROOM" "VDDQ_KLM_PWR_VR"
					( Origin gFrontEnd )
				)
				( attribute "ROT" "0"
					( Origin gFrontEnd )
				)
				( attribute "SEC" "1"
					( Origin gFrontEnd )
				)
				( attribute "SEC_TYPE" "0402V"
					( Origin gFrontEnd )
				)
				( attribute "TOLERANCE" "10%"
					( Origin gFrontEnd )
				)
				( attribute "VALUE" "0.1UF"
					( Origin gFrontEnd )
				)
				( attribute "VER" "1"
					( Origin gFrontEnd )
				)
				( attribute "VOLTAGE" "16V"
					( Units "uVoltage" "V" 1.000000)
					( Origin gFrontEnd )
				)
				( attribute "XY" "(-1675,2375)"
					( Origin gFrontEnd )
				)
				( attribute "CHIPS_PART_NAME" "CAP_A"
					( Origin gPackager )
				)
				( attribute "CDS_PART_NAME" "CAP_A_0402V-0.1UF,16V,10%,X7R,A"
					( Origin gPackager )
				)
				( objectStatus "C1A10" )
				( pin "a"
					( attribute "PN" "1"
						( Origin gPackager )
					)
					( objectStatus "C1A10.1" )
				)
				( pin "b"
					( attribute "PN" "2"
						( Origin gPackager )
					)
					( objectStatus "C1A10.2" )
				)
			)
			( gate "@baseboard_fab2_lib.baseboard_fab2(sch_1):page227_i52"
				( attribute "CDS_LIB" "mstr_discrete"
					( Origin gPackager )
				)
				( attribute "CDS_LOCATION" "R9L9"
					( Origin gPackager )
				)
				( attribute "CDS_SEC" "1"
					( Origin gPackager )
				)
				( attribute "LOCATION" "R9L9"
					( Origin gFrontEnd )
				)
				( attribute "MATERIAL" "CHIP"
					( Origin gFrontEnd )
				)
				( attribute "PACK_TYPE" "0402"
					( Origin gFrontEnd )
				)
				( attribute "PART_NUMBER" "G21796-090"
					( Origin gFrontEnd )
				)
				( attribute "PHYS_PAGE" "227"
					( Origin gFrontEnd )
				)
				( attribute "ROOM" "VDDQ_KLM_PWR_VR"
					( Origin gFrontEnd )
				)
				( attribute "ROT" "0"
					( Origin gFrontEnd )
				)
				( attribute "SEC" "1"
					( Origin gFrontEnd )
				)
				( attribute "SEC_TYPE" "0402"
					( Origin gFrontEnd )
				)
				( attribute "TOLERANCE" "1%"
					( Origin gFrontEnd )
				)
				( attribute "VALUE" "1.0"
					( Origin gFrontEnd )
				)
				( attribute "VER" "1"
					( Origin gFrontEnd )
				)
				( attribute "WATTAGE" "1/16W"
					( Origin gFrontEnd )
				)
				( attribute "XY" "(-1100,3025)"
					( Origin gFrontEnd )
				)
				( attribute "CHIPS_PART_NAME" "RES"
					( Origin gPackager )
				)
				( attribute "CDS_PART_NAME" "RES_0402-1.0,1%,1/16W,CHIP,G21A"
					( Origin gPackager )
				)
				( objectStatus "R9L9" )
				( pin "a"
					( attribute "PN" "1"
						( Origin gPackager )
					)
					( objectStatus "R9L9.1" )
				)
				( pin "b"
					( attribute "PN" "2"
						( Origin gPackager )
					)
					( objectStatus "R9L9.2" )
				)
			)
			( gate "@baseboard_fab2_lib.baseboard_fab2(sch_1):page227_i53"
				( attribute "CDS_LIB" "dev_discrete"
					( Origin gPackager )
				)
				( attribute "CDS_LOCATION" "C1A2"
					( Origin gPackager )
				)
				( attribute "CDS_SEC" "1"
					( Origin gPackager )
				)
				( attribute "LOCATION" "C1A2"
					( Origin gFrontEnd )
				)
				( attribute "MATERIAL" "X6S"
					( Origin gFrontEnd )
				)
				( attribute "PACK_TYPE" "0402V"
					( Origin gFrontEnd )
				)
				( attribute "PART_NUMBER" "D97712-004"
					( Origin gFrontEnd )
				)
				( attribute "PHYS_PAGE" "227"
					( Origin gFrontEnd )
				)
				( attribute "ROOM" "VDDQ_KLM_PWR_VR"
					( Origin gFrontEnd )
				)
				( attribute "ROT" "2"
					( Origin gFrontEnd )
				)
				( attribute "SEC" "1"
					( Origin gFrontEnd )
				)
				( attribute "SEC_TYPE" "0402V"
					( Origin gFrontEnd )
				)
				( attribute "TOLERANCE" "10%"
					( Origin gFrontEnd )
				)
				( attribute "VALUE" "1.0UF"
					( Origin gFrontEnd )
				)
				( attribute "VER" "1"
					( Origin gFrontEnd )
				)
				( attribute "VOLTAGE" "6.3V"
					( Units "uVoltage" "V" 1.000000)
					( Origin gFrontEnd )
				)
				( attribute "XY" "(-675,2425)"
					( Origin gFrontEnd )
				)
				( attribute "CHIPS_PART_NAME" "CAP_A"
					( Origin gPackager )
				)
				( attribute "CDS_PART_NAME" "CAP_A_0402V-1.0UF,6.3V,10%,X6SA"
					( Origin gPackager )
				)
				( objectStatus "C1A2" )
				( pin "a"
					( attribute "PN" "1"
						( Origin gPackager )
					)
					( objectStatus "C1A2.1" )
				)
				( pin "b"
					( attribute "PN" "2"
						( Origin gPackager )
					)
					( objectStatus "C1A2.2" )
				)
			)
			( gate "@baseboard_fab2_lib.baseboard_fab2(sch_1):page227_i54"
				( attribute "CDS_LIB" "mstr_discrete"
					( Origin gPackager )
				)
				( attribute "CDS_LOCATION" "C1B21"
					( Origin gPackager )
				)
				( attribute "CDS_SEC" "1"
					( Origin gPackager )
				)
				( attribute "LOCATION" "C1B21"
					( Origin gFrontEnd )
				)
				( attribute "MATERIAL" "X7R"
					( Origin gFrontEnd )
				)
				( attribute "PACK_TYPE" "0402"
					( Origin gFrontEnd )
				)
				( attribute "PART_NUMBER" "A36096-155"
					( Origin gFrontEnd )
				)
				( attribute "PHYS_PAGE" "227"
					( Origin gFrontEnd )
				)
				( attribute "ROOM" "VDDQ_KLM_PWR_VR"
					( Origin gFrontEnd )
				)
				( attribute "ROT" "0"
					( Origin gFrontEnd )
				)
				( attribute "SEC" "1"
					( Origin gFrontEnd )
				)
				( attribute "SEC_TYPE" "0402"
					( Origin gFrontEnd )
				)
				( attribute "TOLERANCE" "10%"
					( Origin gFrontEnd )
				)
				( attribute "VALUE" "0.22UF"
					( Origin gFrontEnd )
				)
				( attribute "VER" "1"
					( Origin gFrontEnd )
				)
				( attribute "VOLTAGE" "16V"
					( Units "uVoltage" "V" 1.000000)
					( Origin gFrontEnd )
				)
				( attribute "XY" "(-575,2425)"
					( Origin gFrontEnd )
				)
				( attribute "CHIPS_PART_NAME" "CAP"
					( Origin gPackager )
				)
				( attribute "CDS_PART_NAME" "CAP_0402-0.22UF,16V,10%,X7R,A3A"
					( Origin gPackager )
				)
				( objectStatus "C1B21" )
				( pin "a"
					( attribute "PN" "1"
						( Origin gPackager )
					)
					( objectStatus "C1B21.1" )
				)
				( pin "b"
					( attribute "PN" "2"
						( Origin gPackager )
					)
					( objectStatus "C1B21.2" )
				)
			)
			( gate "@baseboard_fab2_lib.baseboard_fab2(sch_1):page227_i55"
				( attribute "CDS_LIB" "mstr_discrete"
					( Origin gPackager )
				)
				( attribute "CDS_LOCATION" "L1A2"
					( Origin gPackager )
				)
				( attribute "CDS_SEC" "1"
					( Origin gPackager )
				)
				( attribute "LOCATION" "L1A2"
					( Origin gFrontEnd )
				)
				( attribute "MATERIAL" "IND"
					( Origin gFrontEnd )
				)
				( attribute "PACK_TYPE" "SM"
					( Origin gFrontEnd )
				)
				( attribute "PART_NUMBER" "D92183-034"
					( Origin gFrontEnd )
				)
				( attribute "PHYS_PAGE" "227"
					( Origin gFrontEnd )
				)
				( attribute "ROOM" "VDDQ_KLM_PWR_VR"
					( Origin gFrontEnd )
				)
				( attribute "ROT" "0"
					( Origin gFrontEnd )
				)
				( attribute "SEC" "1"
					( Origin gFrontEnd )
				)
				( attribute "SEC_TYPE" "SM"
					( Origin gFrontEnd )
				)
				( attribute "VALUE" "0.12UH"
					( Origin gFrontEnd )
				)
				( attribute "VER" "1"
					( Origin gFrontEnd )
				)
				( attribute "XY" "(3075,1850)"
					( Origin gFrontEnd )
				)
				( attribute "CHIPS_PART_NAME" "INDUCTOR"
					( Origin gPackager )
				)
				( attribute "CDS_PART_NAME" "INDUCTOR_SM-0.12UH,IND,D92183-A"
					( Origin gPackager )
				)
				( objectStatus "L1A2" )
				( pin "ina"
					( attribute "PN" "1"
						( Origin gPackager )
					)
					( objectStatus "L1A2.1" )
				)
				( pin "inb"
					( attribute "PN" "2"
						( Origin gPackager )
					)
					( objectStatus "L1A2.2" )
				)
			)
			( gate "@baseboard_fab2_lib.baseboard_fab2(sch_1):page227_i65"
				( attribute "CDS_LIB" "mstr_discrete"
					( Origin gPackager )
				)
				( attribute "CDS_LOCATION" "L1A1"
					( Origin gPackager )
				)
				( attribute "CDS_SEC" "1"
					( Origin gPackager )
				)
				( attribute "LOCATION" "L1A1"
					( Origin gFrontEnd )
				)
				( attribute "MATERIAL" "IND"
					( Origin gFrontEnd )
				)
				( attribute "PACK_TYPE" "SM"
					( Origin gFrontEnd )
				)
				( attribute "PART_NUMBER" "D92183-034"
					( Origin gFrontEnd )
				)
				( attribute "PHYS_PAGE" "227"
					( Origin gFrontEnd )
				)
				( attribute "ROOM" "VDDQ_KLM_PWR_VR"
					( Origin gFrontEnd )
				)
				( attribute "ROT" "0"
					( Origin gFrontEnd )
				)
				( attribute "SEC" "1"
					( Origin gFrontEnd )
				)
				( attribute "SEC_TYPE" "SM"
					( Origin gFrontEnd )
				)
				( attribute "VALUE" "0.12UH"
					( Origin gFrontEnd )
				)
				( attribute "VER" "1"
					( Origin gFrontEnd )
				)
				( attribute "XY" "(3150,-300)"
					( Origin gFrontEnd )
				)
				( attribute "CHIPS_PART_NAME" "INDUCTOR"
					( Origin gPackager )
				)
				( attribute "CDS_PART_NAME" "INDUCTOR_SM-0.12UH,IND,D92183-A"
					( Origin gPackager )
				)
				( objectStatus "L1A1" )
				( pin "ina"
					( attribute "PN" "1"
						( Origin gPackager )
					)
					( objectStatus "L1A1.1" )
				)
				( pin "inb"
					( attribute "PN" "2"
						( Origin gPackager )
					)
					( objectStatus "L1A1.2" )
				)
			)
			( gate "@baseboard_fab2_lib.baseboard_fab2(sch_1):page227_i68"
				( attribute "BOM_COST" "VDDQ_KLM_PWR_VR"
					( Origin gFrontEnd )
				)
				( attribute "CDS_LIB" "mstr_discrete"
					( Origin gPackager )
				)
				( attribute "CDS_LOCATION" "C1A1"
					( Origin gPackager )
				)
				( attribute "CDS_SEC" "1"
					( Origin gPackager )
				)
				( attribute "LOCATION" "C1A1"
					( Origin gFrontEnd )
				)
				( attribute "MATERIAL" "X6S"
					( Origin gFrontEnd )
				)
				( attribute "PACK_TYPE" "0805LF"
					( Origin gFrontEnd )
				)
				( attribute "PART_NUMBER" "C95333-002"
					( Origin gFrontEnd )
				)
				( attribute "PHYS_PAGE" "227"
					( Origin gFrontEnd )
				)
				( attribute "ROOM" "VDDQ_KLM_PWR_VR"
					( Origin gFrontEnd )
				)
				( attribute "ROT" "0"
					( Origin gFrontEnd )
				)
				( attribute "SEC" "1"
					( Origin gFrontEnd )
				)
				( attribute "SEC_TYPE" "0805LF"
					( Origin gFrontEnd )
				)
				( attribute "TOLERANCE" "20%"
					( Origin gFrontEnd )
				)
				( attribute "VALUE" "22UF"
					( Origin gFrontEnd )
				)
				( attribute "VER" "1"
					( Origin gFrontEnd )
				)
				( attribute "VOLTAGE" "4V"
					( Units "uVoltage" "V" 1.000000)
					( Origin gFrontEnd )
				)
				( attribute "XY" "(4025,-500)"
					( Origin gFrontEnd )
				)
				( attribute "CHIPS_PART_NAME" "CAP"
					( Origin gPackager )
				)
				( attribute "CDS_PART_NAME" "CAP_0805LF-22UF,4V,20%,X6S,C95A"
					( Origin gPackager )
				)
				( objectStatus "C1A1" )
				( pin "a"
					( attribute "PN" "1"
						( Origin gPackager )
					)
					( objectStatus "C1A1.1" )
				)
				( pin "b"
					( attribute "PN" "2"
						( Origin gPackager )
					)
					( objectStatus "C1A1.2" )
				)
			)
			( gate "@baseboard_fab2_lib.baseboard_fab2(sch_1):page227_i72"
				( attribute "CDS_LIB" "mstr_discrete"
					( Origin gPackager )
				)
				( attribute "CDS_LOCATION" "C1A13"
					( Origin gPackager )
				)
				( attribute "CDS_SEC" "1"
					( Origin gPackager )
				)
				( attribute "LOCATION" "C1A13"
					( Origin gFrontEnd )
				)
				( attribute "MATERIAL" "X7R"
					( Origin gFrontEnd )
				)
				( attribute "PACK_TYPE" "0402"
					( Origin gFrontEnd )
				)
				( attribute "PART_NUMBER" "A36096-155"
					( Origin gFrontEnd )
				)
				( attribute "PHYS_PAGE" "227"
					( Origin gFrontEnd )
				)
				( attribute "ROOM" "VDDQ_KLM_PWR_VR"
					( Origin gFrontEnd )
				)
				( attribute "ROT" "0"
					( Origin gFrontEnd )
				)
				( attribute "SEC" "1"
					( Origin gFrontEnd )
				)
				( attribute "SEC_TYPE" "0402"
					( Origin gFrontEnd )
				)
				( attribute "TOLERANCE" "10%"
					( Origin gFrontEnd )
				)
				( attribute "VALUE" "0.22UF"
					( Origin gFrontEnd )
				)
				( attribute "VER" "1"
					( Origin gFrontEnd )
				)
				( attribute "VOLTAGE" "16V"
					( Units "uVoltage" "V" 1.000000)
					( Origin gFrontEnd )
				)
				( attribute "XY" "(-650,275)"
					( Origin gFrontEnd )
				)
				( attribute "CHIPS_PART_NAME" "CAP"
					( Origin gPackager )
				)
				( attribute "CDS_PART_NAME" "CAP_0402-0.22UF,16V,10%,X7R,A3A"
					( Origin gPackager )
				)
				( objectStatus "C1A13" )
				( pin "a"
					( attribute "PN" "1"
						( Origin gPackager )
					)
					( objectStatus "C1A13.1" )
				)
				( pin "b"
					( attribute "PN" "2"
						( Origin gPackager )
					)
					( objectStatus "C1A13.2" )
				)
			)
			( gate "@baseboard_fab2_lib.baseboard_fab2(sch_1):page227_i73"
				( attribute "CDS_LIB" "dev_discrete"
					( Origin gPackager )
				)
				( attribute "CDS_LOCATION" "C1A11"
					( Origin gPackager )
				)
				( attribute "CDS_SEC" "1"
					( Origin gPackager )
				)
				( attribute "LOCATION" "C1A11"
					( Origin gFrontEnd )
				)
				( attribute "MATERIAL" "X6S"
					( Origin gFrontEnd )
				)
				( attribute "PACK_TYPE" "0402V"
					( Origin gFrontEnd )
				)
				( attribute "PART_NUMBER" "D97712-004"
					( Origin gFrontEnd )
				)
				( attribute "PHYS_PAGE" "227"
					( Origin gFrontEnd )
				)
				( attribute "ROOM" "VDDQ_KLM_PWR_VR"
					( Origin gFrontEnd )
				)
				( attribute "ROT" "2"
					( Origin gFrontEnd )
				)
				( attribute "SEC" "1"
					( Origin gFrontEnd )
				)
				( attribute "SEC_TYPE" "0402V"
					( Origin gFrontEnd )
				)
				( attribute "TOLERANCE" "10%"
					( Origin gFrontEnd )
				)
				( attribute "VALUE" "1.0UF"
					( Origin gFrontEnd )
				)
				( attribute "VER" "1"
					( Origin gFrontEnd )
				)
				( attribute "VOLTAGE" "6.3V"
					( Units "uVoltage" "V" 1.000000)
					( Origin gFrontEnd )
				)
				( attribute "XY" "(-750,275)"
					( Origin gFrontEnd )
				)
				( attribute "CHIPS_PART_NAME" "CAP_A"
					( Origin gPackager )
				)
				( attribute "CDS_PART_NAME" "CAP_A_0402V-1.0UF,6.3V,10%,X6SA"
					( Origin gPackager )
				)
				( objectStatus "C1A11" )
				( pin "a"
					( attribute "PN" "1"
						( Origin gPackager )
					)
					( objectStatus "C1A11.1" )
				)
				( pin "b"
					( attribute "PN" "2"
						( Origin gPackager )
					)
					( objectStatus "C1A11.2" )
				)
			)
			( gate "@baseboard_fab2_lib.baseboard_fab2(sch_1):page227_i75"
				( attribute "CDS_LIB" "mstr_discrete"
					( Origin gPackager )
				)
				( attribute "CDS_LOCATION" "C1A8"
					( Origin gPackager )
				)
				( attribute "CDS_SEC" "1"
					( Origin gPackager )
				)
				( attribute "LOCATION" "C1A8"
					( Origin gFrontEnd )
				)
				( attribute "MATERIAL" "X7R"
					( Origin gFrontEnd )
				)
				( attribute "PACK_TYPE" "0402"
					( Origin gFrontEnd )
				)
				( attribute "PART_NUMBER" "A36096-104"
					( Origin gFrontEnd )
				)
				( attribute "PHYS_PAGE" "227"
					( Origin gFrontEnd )
				)
				( attribute "ROOM" "VDDQ_KLM_PWR_VR"
					( Origin gFrontEnd )
				)
				( attribute "ROT" "2"
					( Origin gFrontEnd )
				)
				( attribute "SEC" "1"
					( Origin gFrontEnd )
				)
				( attribute "SEC_TYPE" "0402"
					( Origin gFrontEnd )
				)
				( attribute "SPOF" "TRUE"
					( Origin gFrontEnd )
				)
				( attribute "TOLERANCE" "10%"
					( Origin gFrontEnd )
				)
				( attribute "VALUE" "0.220UF"
					( Origin gFrontEnd )
				)
				( attribute "VER" "1"
					( Origin gFrontEnd )
				)
				( attribute "VOLTAGE" "16V"
					( Units "uVoltage" "V" 1.000000)
					( Origin gFrontEnd )
				)
				( attribute "XY" "(-950,-325)"
					( Origin gFrontEnd )
				)
				( attribute "CHIPS_PART_NAME" "CAP"
					( Origin gPackager )
				)
				( attribute "CDS_PART_NAME" "CAP_0402-0.220UF,16V,10%,X7R,AA"
					( Origin gPackager )
				)
				( objectStatus "C1A8" )
				( pin "a"
					( attribute "PN" "1"
						( Origin gPackager )
					)
					( objectStatus "C1A8.1" )
				)
				( pin "b"
					( attribute "PN" "2"
						( Origin gPackager )
					)
					( objectStatus "C1A8.2" )
				)
			)
			( gate "@baseboard_fab2_lib.baseboard_fab2(sch_1):page227_i76"
				( attribute "CDS_LIB" "mstr_discrete"
					( Origin gPackager )
				)
				( attribute "CDS_LOCATION" "R9L4"
					( Origin gPackager )
				)
				( attribute "CDS_SEC" "1"
					( Origin gPackager )
				)
				( attribute "LOCATION" "R9L4"
					( Origin gFrontEnd )
				)
				( attribute "MATERIAL" "CHIP"
					( Origin gFrontEnd )
				)
				( attribute "PACK_TYPE" "0402"
					( Origin gFrontEnd )
				)
				( attribute "PART_NUMBER" "G21796-090"
					( Origin gFrontEnd )
				)
				( attribute "PHYS_PAGE" "227"
					( Origin gFrontEnd )
				)
				( attribute "ROOM" "VDDQ_KLM_PWR_VR"
					( Origin gFrontEnd )
				)
				( attribute "ROT" "0"
					( Origin gFrontEnd )
				)
				( attribute "SEC" "1"
					( Origin gFrontEnd )
				)
				( attribute "SEC_TYPE" "0402"
					( Origin gFrontEnd )
				)
				( attribute "TOLERANCE" "1%"
					( Origin gFrontEnd )
				)
				( attribute "VALUE" "1.0"
					( Origin gFrontEnd )
				)
				( attribute "VER" "1"
					( Origin gFrontEnd )
				)
				( attribute "WATTAGE" "1/16W"
					( Origin gFrontEnd )
				)
				( attribute "XY" "(-1050,825)"
					( Origin gFrontEnd )
				)
				( attribute "CHIPS_PART_NAME" "RES"
					( Origin gPackager )
				)
				( attribute "CDS_PART_NAME" "RES_0402-1.0,1%,1/16W,CHIP,G21A"
					( Origin gPackager )
				)
				( objectStatus "R9L4" )
				( pin "a"
					( attribute "PN" "1"
						( Origin gPackager )
					)
					( objectStatus "R9L4.1" )
				)
				( pin "b"
					( attribute "PN" "2"
						( Origin gPackager )
					)
					( objectStatus "R9L4.2" )
				)
			)
			( gate "@baseboard_fab2_lib.baseboard_fab2(sch_1):page227_i77"
				( attribute "CDS_LIB" "mstr_discrete"
					( Origin gPackager )
				)
				( attribute "CDS_LOCATION" "C1A6"
					( Origin gPackager )
				)
				( attribute "CDS_SEC" "1"
					( Origin gPackager )
				)
				( attribute "LOCATION" "C1A6"
					( Origin gFrontEnd )
				)
				( attribute "MATERIAL" "X6S"
					( Origin gFrontEnd )
				)
				( attribute "PACK_TYPE" "0402"
					( Origin gFrontEnd )
				)
				( attribute "PART_NUMBER" "D97712-011"
					( Origin gFrontEnd )
				)
				( attribute "PHYS_PAGE" "227"
					( Origin gFrontEnd )
				)
				( attribute "ROOM" "VDDQ_KLM_PWR_VR"
					( Origin gFrontEnd )
				)
				( attribute "ROT" "0"
					( Origin gFrontEnd )
				)
				( attribute "SEC" "1"
					( Origin gFrontEnd )
				)
				( attribute "SEC_TYPE" "0402"
					( Origin gFrontEnd )
				)
				( attribute "TOLERANCE" "10%"
					( Origin gFrontEnd )
				)
				( attribute "VALUE" "1.0UF"
					( Origin gFrontEnd )
				)
				( attribute "VER" "1"
					( Origin gFrontEnd )
				)
				( attribute "VOLTAGE" "16V"
					( Units "uVoltage" "V" 1.000000)
					( Origin gFrontEnd )
				)
				( attribute "XY" "(-1275,300)"
					( Origin gFrontEnd )
				)
				( attribute "CHIPS_PART_NAME" "CAP"
					( Origin gPackager )
				)
				( attribute "CDS_PART_NAME" "CAP_0402-1.0UF,16V,10%,X6S,D97A"
					( Origin gPackager )
				)
				( objectStatus "C1A6" )
				( pin "a"
					( attribute "PN" "1"
						( Origin gPackager )
					)
					( objectStatus "C1A6.1" )
				)
				( pin "b"
					( attribute "PN" "2"
						( Origin gPackager )
					)
					( objectStatus "C1A6.2" )
				)
			)
			( gate "@baseboard_fab2_lib.baseboard_fab2(sch_1):page227_i78"
				( attribute "CDS_LIB" "dev_discrete"
					( Origin gPackager )
				)
				( attribute "CDS_LOCATION" "C1A20"
					( Origin gPackager )
				)
				( attribute "CDS_SEC" "1"
					( Origin gPackager )
				)
				( attribute "LOCATION" "C1A20"
					( Origin gFrontEnd )
				)
				( attribute "MATERIAL" "X7R"
					( Origin gFrontEnd )
				)
				( attribute "PACK_TYPE" "0402V"
					( Origin gFrontEnd )
				)
				( attribute "PART_NUMBER" "A36096-030"
					( Origin gFrontEnd )
				)
				( attribute "PHYS_PAGE" "227"
					( Origin gFrontEnd )
				)
				( attribute "ROOM" "VDDQ_KLM_PWR_VR"
					( Origin gFrontEnd )
				)
				( attribute "ROT" "0"
					( Origin gFrontEnd )
				)
				( attribute "SEC" "1"
					( Origin gFrontEnd )
				)
				( attribute "SEC_TYPE" "0402V"
					( Origin gFrontEnd )
				)
				( attribute "TOLERANCE" "10%"
					( Origin gFrontEnd )
				)
				( attribute "VALUE" "0.1UF"
					( Origin gFrontEnd )
				)
				( attribute "VER" "1"
					( Origin gFrontEnd )
				)
				( attribute "VOLTAGE" "16V"
					( Units "uVoltage" "V" 1.000000)
					( Origin gFrontEnd )
				)
				( attribute "XY" "(-1750,275)"
					( Origin gFrontEnd )
				)
				( attribute "CHIPS_PART_NAME" "CAP_A"
					( Origin gPackager )
				)
				( attribute "CDS_PART_NAME" "CAP_A_0402V-0.1UF,16V,10%,X7R,A"
					( Origin gPackager )
				)
				( objectStatus "C1A20" )
				( pin "a"
					( attribute "PN" "1"
						( Origin gPackager )
					)
					( objectStatus "C1A20.1" )
				)
				( pin "b"
					( attribute "PN" "2"
						( Origin gPackager )
					)
					( objectStatus "C1A20.2" )
				)
			)
			( gate "@baseboard_fab2_lib.baseboard_fab2(sch_1):page227_i79"
				( attribute "CDS_LIB" "mstr_discrete"
					( Origin gPackager )
				)
				( attribute "CDS_LOCATION" "C1A9"
					( Origin gPackager )
				)
				( attribute "CDS_SEC" "1"
					( Origin gPackager )
				)
				( attribute "LOCATION" "C1A9"
					( Origin gFrontEnd )
				)
				( attribute "MATERIAL" "X6S"
					( Origin gFrontEnd )
				)
				( attribute "PACK_TYPE" "0402"
					( Origin gFrontEnd )
				)
				( attribute "PART_NUMBER" "D97712-011"
					( Origin gFrontEnd )
				)
				( attribute "PHYS_PAGE" "227"
					( Origin gFrontEnd )
				)
				( attribute "ROOM" "VDDQ_KLM_PWR_VR"
					( Origin gFrontEnd )
				)
				( attribute "ROT" "0"
					( Origin gFrontEnd )
				)
				( attribute "SEC" "1"
					( Origin gFrontEnd )
				)
				( attribute "SEC_TYPE" "0402"
					( Origin gFrontEnd )
				)
				( attribute "TOLERANCE" "10%"
					( Origin gFrontEnd )
				)
				( attribute "VALUE" "1.0UF"
					( Origin gFrontEnd )
				)
				( attribute "VER" "1"
					( Origin gFrontEnd )
				)
				( attribute "VOLTAGE" "16V"
					( Units "uVoltage" "V" 1.000000)
					( Origin gFrontEnd )
				)
				( attribute "XY" "(-1975,275)"
					( Origin gFrontEnd )
				)
				( attribute "CHIPS_PART_NAME" "CAP"
					( Origin gPackager )
				)
				( attribute "CDS_PART_NAME" "CAP_0402-1.0UF,16V,10%,X6S,D97A"
					( Origin gPackager )
				)
				( objectStatus "C1A9" )
				( pin "a"
					( attribute "PN" "1"
						( Origin gPackager )
					)
					( objectStatus "C1A9.1" )
				)
				( pin "b"
					( attribute "PN" "2"
						( Origin gPackager )
					)
					( objectStatus "C1A9.2" )
				)
			)
			( gate "@baseboard_fab2_lib.baseboard_fab2(sch_1):page227_i80"
				( attribute "CDS_LIB" "mstr_discrete"
					( Origin gPackager )
				)
				( attribute "CDS_LOCATION" "C9L5"
					( Origin gPackager )
				)
				( attribute "CDS_SEC" "1"
					( Origin gPackager )
				)
				( attribute "LOCATION" "C9L5"
					( Origin gFrontEnd )
				)
				( attribute "MATERIAL" "X6S"
					( Origin gFrontEnd )
				)
				( attribute "PACK_TYPE" "0805"
					( Origin gFrontEnd )
				)
				( attribute "PART_NUMBER" "C95333-007"
					( Origin gFrontEnd )
				)
				( attribute "PHYS_PAGE" "227"
					( Origin gFrontEnd )
				)
				( attribute "ROOM" "VDDQ_KLM_PWR_VR"
					( Origin gFrontEnd )
				)
				( attribute "ROT" "0"
					( Origin gFrontEnd )
				)
				( attribute "SEC" "1"
					( Origin gFrontEnd )
				)
				( attribute "SEC_TYPE" "0805"
					( Origin gFrontEnd )
				)
				( attribute "TOLERANCE" "10%"
					( Origin gFrontEnd )
				)
				( attribute "VALUE" "10UF"
					( Origin gFrontEnd )
				)
				( attribute "VER" "1"
					( Origin gFrontEnd )
				)
				( attribute "VOLTAGE" "16V"
					( Units "uVoltage" "V" 1.000000)
					( Origin gFrontEnd )
				)
				( attribute "XY" "(-2225,275)"
					( Origin gFrontEnd )
				)
				( attribute "CHIPS_PART_NAME" "CAP"
					( Origin gPackager )
				)
				( attribute "CDS_PART_NAME" "CAP_0805-10UF,16V,10%,X6S,C953A"
					( Origin gPackager )
				)
				( objectStatus "C9L5" )
				( pin "a"
					( attribute "PN" "1"
						( Origin gPackager )
					)
					( objectStatus "C9L5.1" )
				)
				( pin "b"
					( attribute "PN" "2"
						( Origin gPackager )
					)
					( objectStatus "C9L5.2" )
				)
			)
			( gate "@baseboard_fab2_lib.baseboard_fab2(sch_1):page227_i81"
				( attribute "CDS_LIB" "mstr_discrete"
					( Origin gPackager )
				)
				( attribute "CDS_LOCATION" "C9L13"
					( Origin gPackager )
				)
				( attribute "CDS_SEC" "1"
					( Origin gPackager )
				)
				( attribute "LOCATION" "C9L13"
					( Origin gFrontEnd )
				)
				( attribute "MATERIAL" "X6S"
					( Origin gFrontEnd )
				)
				( attribute "PACK_TYPE" "0805"
					( Origin gFrontEnd )
				)
				( attribute "PART_NUMBER" "C95333-007"
					( Origin gFrontEnd )
				)
				( attribute "PHYS_PAGE" "227"
					( Origin gFrontEnd )
				)
				( attribute "ROOM" "VDDQ_KLM_PWR_VR"
					( Origin gFrontEnd )
				)
				( attribute "ROT" "0"
					( Origin gFrontEnd )
				)
				( attribute "SEC" "1"
					( Origin gFrontEnd )
				)
				( attribute "SEC_TYPE" "0805"
					( Origin gFrontEnd )
				)
				( attribute "TOLERANCE" "10%"
					( Origin gFrontEnd )
				)
				( attribute "VALUE" "10UF"
					( Origin gFrontEnd )
				)
				( attribute "VER" "1"
					( Origin gFrontEnd )
				)
				( attribute "VOLTAGE" "16V"
					( Units "uVoltage" "V" 1.000000)
					( Origin gFrontEnd )
				)
				( attribute "XY" "(-2475,225)"
					( Origin gFrontEnd )
				)
				( attribute "CHIPS_PART_NAME" "CAP"
					( Origin gPackager )
				)
				( attribute "CDS_PART_NAME" "CAP_0805-10UF,16V,10%,X6S,C953A"
					( Origin gPackager )
				)
				( objectStatus "C9L13" )
				( pin "a"
					( attribute "PN" "1"
						( Origin gPackager )
					)
					( objectStatus "C9L13.1" )
				)
				( pin "b"
					( attribute "PN" "2"
						( Origin gPackager )
					)
					( objectStatus "C9L13.2" )
				)
			)
			( gate "@baseboard_fab2_lib.baseboard_fab2(sch_1):page227_i84"
				( attribute "CDS_LIB" "mstr_discrete"
					( Origin gPackager )
				)
				( attribute "CDS_LOCATION" "C9L14"
					( Origin gPackager )
				)
				( attribute "CDS_SEC" "1"
					( Origin gPackager )
				)
				( attribute "LOCATION" "C9L14"
					( Origin gFrontEnd )
				)
				( attribute "MATERIAL" "X6S"
					( Origin gFrontEnd )
				)
				( attribute "PACK_TYPE" "0805"
					( Origin gFrontEnd )
				)
				( attribute "PART_NUMBER" "C95333-007"
					( Origin gFrontEnd )
				)
				( attribute "PHYS_PAGE" "227"
					( Origin gFrontEnd )
				)
				( attribute "ROOM" "VDDQ_KLM_PWR_VR"
					( Origin gFrontEnd )
				)
				( attribute "ROT" "0"
					( Origin gFrontEnd )
				)
				( attribute "SEC" "1"
					( Origin gFrontEnd )
				)
				( attribute "SEC_TYPE" "0805"
					( Origin gFrontEnd )
				)
				( attribute "TOLERANCE" "10%"
					( Origin gFrontEnd )
				)
				( attribute "VALUE" "10UF"
					( Origin gFrontEnd )
				)
				( attribute "VER" "1"
					( Origin gFrontEnd )
				)
				( attribute "VOLTAGE" "16V"
					( Units "uVoltage" "V" 1.000000)
					( Origin gFrontEnd )
				)
				( attribute "XY" "(-2725,275)"
					( Origin gFrontEnd )
				)
				( attribute "CHIPS_PART_NAME" "CAP"
					( Origin gPackager )
				)
				( attribute "CDS_PART_NAME" "CAP_0805-10UF,16V,10%,X6S,C953A"
					( Origin gPackager )
				)
				( objectStatus "C9L14" )
				( pin "a"
					( attribute "PN" "1"
						( Origin gPackager )
					)
					( objectStatus "C9L14.1" )
				)
				( pin "b"
					( attribute "PN" "2"
						( Origin gPackager )
					)
					( objectStatus "C9L14.2" )
				)
			)
			( gate "@baseboard_fab2_lib.baseboard_fab2(sch_1):page227_i101"
				( attribute "CDS_LIB" "mstr_discrete"
					( Origin gPackager )
				)
				( attribute "CDS_LOCATION" "EU1A2"
					( Origin gPackager )
				)
				( attribute "CDS_SEC" "1"
					( Origin gPackager )
				)
				( attribute "LOCATION" "EU1A2"
					( Origin gFrontEnd )
				)
				( attribute "MATERIAL" "IC"
					( Origin gFrontEnd )
				)
				( attribute "NO_XNET_CONNECTION" "1"
					( Origin gFrontEnd )
				)
				( attribute "PACK_TYPE" "SM"
					( Origin gFrontEnd )
				)
				( attribute "PART_NUMBER" "H73688-001"
					( Origin gFrontEnd )
				)
				( attribute "PHYS_PAGE" "227"
					( Origin gFrontEnd )
				)
				( attribute "ROT" "0"
					( Origin gFrontEnd )
				)
				( attribute "SEC" "1"
					( Origin gFrontEnd )
				)
				( attribute "SEC_TYPE" "SM"
					( Origin gFrontEnd )
				)
				( attribute "VALUE" "IR35411"
					( Origin gFrontEnd )
				)
				( attribute "VER" "1"
					( Origin gFrontEnd )
				)
				( attribute "XY" "(1500,2150)"
					( Origin gFrontEnd )
				)
				( attribute "CHIPS_PART_NAME" "IR354XX"
					( Origin gPackager )
				)
				( attribute "CDS_PART_NAME" "IR354XX_SM-IR35411,IC,H73688-0A"
					( Origin gPackager )
				)
				( objectStatus "EU1A2" )
				( pin "boost"
					( attribute "PN" "33"
						( Origin gPackager )
					)
					( objectStatus "EU1A2.33" )
				)
				( pin "en"
					( attribute "PN" "35"
						( Origin gPackager )
					)
					( objectStatus "EU1A2.35" )
				)
				( pin "gl(0)"
					( attribute "PN" "6"
						( Origin gPackager )
					)
					( objectStatus "EU1A2.6" )
				)
				( pin "gl(1)"
					( attribute "PN" "41"
						( Origin gPackager )
					)
					( objectStatus "EU1A2.41" )
				)
				( pin "iout"
					( attribute "PN" "38"
						( Origin gPackager )
					)
					( objectStatus "EU1A2.38" )
				)
				( pin "lgnd"
					( attribute "PN" "2"
						( Origin gPackager )
					)
					( objectStatus "EU1A2.2" )
				)
				( pin "nc"
					( attribute "PN" "31"
						( Origin gPackager )
					)
					( objectStatus "EU1A2.31" )
				)
				( pin "ocset"
					( attribute "PN" "37"
						( Origin gPackager )
					)
					( objectStatus "EU1A2.37" )
				)
				( pin "pgnd(0)"
					( attribute "PN" "5"
						( Origin gPackager )
					)
					( objectStatus "EU1A2.5" )
				)
				( pin "pgnd(1)"
					( attribute "PN" "7"
						( Origin gPackager )
					)
					( objectStatus "EU1A2.7" )
				)
				( pin "pgnd(2)"
					( attribute "PN" "40"
						( Origin gPackager )
					)
					( objectStatus "EU1A2.40" )
				)
				( pin "phase"
					( attribute "PN" "32"
						( Origin gPackager )
					)
					( objectStatus "EU1A2.32" )
				)
				( pin "pwm"
					( attribute "PN" "34"
						( Origin gPackager )
					)
					( objectStatus "EU1A2.34" )
				)
				( pin "refin"
					( attribute "PN" "39"
						( Origin gPackager )
					)
					( objectStatus "EU1A2.39" )
				)
				( pin "sw"
					( attribute "PN" "10"
						( Origin gPackager )
					)
					( objectStatus "EU1A2.10" )
				)
				( pin "tout_flt"
					( attribute "PN" "36"
						( Origin gPackager )
					)
					( objectStatus "EU1A2.36" )
				)
				( pin "vcc"
					( attribute "PN" "3"
						( Origin gPackager )
					)
					( objectStatus "EU1A2.3" )
				)
				( pin "vdrv"
					( attribute "PN" "4"
						( Origin gPackager )
					)
					( objectStatus "EU1A2.4" )
				)
				( pin "vin(0)"
					( attribute "PN" "25"
						( Origin gPackager )
					)
					( objectStatus "EU1A2.25" )
				)
				( pin "vin(1)"
					( attribute "PN" "30"
						( Origin gPackager )
					)
					( objectStatus "EU1A2.30" )
				)
				( pin "vos"
					( attribute "PN" "1"
						( Origin gPackager )
					)
					( objectStatus "EU1A2.1" )
				)
			)
			( gate "@baseboard_fab2_lib.baseboard_fab2(sch_1):page227_i102"
				( attribute "CDS_LIB" "mstr_discrete"
					( Origin gPackager )
				)
				( attribute "CDS_LOCATION" "EU1A1"
					( Origin gPackager )
				)
				( attribute "CDS_SEC" "1"
					( Origin gPackager )
				)
				( attribute "LOCATION" "EU1A1"
					( Origin gFrontEnd )
				)
				( attribute "MATERIAL" "IC"
					( Origin gFrontEnd )
				)
				( attribute "NO_XNET_CONNECTION" "1"
					( Origin gFrontEnd )
				)
				( attribute "PACK_TYPE" "SM"
					( Origin gFrontEnd )
				)
				( attribute "PART_NUMBER" "H73688-001"
					( Origin gFrontEnd )
				)
				( attribute "PHYS_PAGE" "227"
					( Origin gFrontEnd )
				)
				( attribute "ROT" "0"
					( Origin gFrontEnd )
				)
				( attribute "SEC" "1"
					( Origin gFrontEnd )
				)
				( attribute "SEC_TYPE" "SM"
					( Origin gFrontEnd )
				)
				( attribute "VALUE" "IR35411"
					( Origin gFrontEnd )
				)
				( attribute "VER" "1"
					( Origin gFrontEnd )
				)
				( attribute "XY" "(1475,0)"
					( Origin gFrontEnd )
				)
				( attribute "CHIPS_PART_NAME" "IR354XX"
					( Origin gPackager )
				)
				( attribute "CDS_PART_NAME" "IR354XX_SM-IR35411,IC,H73688-0A"
					( Origin gPackager )
				)
				( objectStatus "EU1A1" )
				( pin "boost"
					( attribute "PN" "33"
						( Origin gPackager )
					)
					( objectStatus "EU1A1.33" )
				)
				( pin "en"
					( attribute "PN" "35"
						( Origin gPackager )
					)
					( objectStatus "EU1A1.35" )
				)
				( pin "gl(0)"
					( attribute "PN" "6"
						( Origin gPackager )
					)
					( objectStatus "EU1A1.6" )
				)
				( pin "gl(1)"
					( attribute "PN" "41"
						( Origin gPackager )
					)
					( objectStatus "EU1A1.41" )
				)
				( pin "iout"
					( attribute "PN" "38"
						( Origin gPackager )
					)
					( objectStatus "EU1A1.38" )
				)
				( pin "lgnd"
					( attribute "PN" "2"
						( Origin gPackager )
					)
					( objectStatus "EU1A1.2" )
				)
				( pin "nc"
					( attribute "PN" "31"
						( Origin gPackager )
					)
					( objectStatus "EU1A1.31" )
				)
				( pin "ocset"
					( attribute "PN" "37"
						( Origin gPackager )
					)
					( objectStatus "EU1A1.37" )
				)
				( pin "pgnd(0)"
					( attribute "PN" "5"
						( Origin gPackager )
					)
					( objectStatus "EU1A1.5" )
				)
				( pin "pgnd(1)"
					( attribute "PN" "7"
						( Origin gPackager )
					)
					( objectStatus "EU1A1.7" )
				)
				( pin "pgnd(2)"
					( attribute "PN" "40"
						( Origin gPackager )
					)
					( objectStatus "EU1A1.40" )
				)
				( pin "phase"
					( attribute "PN" "32"
						( Origin gPackager )
					)
					( objectStatus "EU1A1.32" )
				)
				( pin "pwm"
					( attribute "PN" "34"
						( Origin gPackager )
					)
					( objectStatus "EU1A1.34" )
				)
				( pin "refin"
					( attribute "PN" "39"
						( Origin gPackager )
					)
					( objectStatus "EU1A1.39" )
				)
				( pin "sw"
					( attribute "PN" "10"
						( Origin gPackager )
					)
					( objectStatus "EU1A1.10" )
				)
				( pin "tout_flt"
					( attribute "PN" "36"
						( Origin gPackager )
					)
					( objectStatus "EU1A1.36" )
				)
				( pin "vcc"
					( attribute "PN" "3"
						( Origin gPackager )
					)
					( objectStatus "EU1A1.3" )
				)
				( pin "vdrv"
					( attribute "PN" "4"
						( Origin gPackager )
					)
					( objectStatus "EU1A1.4" )
				)
				( pin "vin(0)"
					( attribute "PN" "25"
						( Origin gPackager )
					)
					( objectStatus "EU1A1.25" )
				)
				( pin "vin(1)"
					( attribute "PN" "30"
						( Origin gPackager )
					)
					( objectStatus "EU1A1.30" )
				)
				( pin "vos"
					( attribute "PN" "1"
						( Origin gPackager )
					)
					( objectStatus "EU1A1.1" )
				)
			)
			( gate "@baseboard_fab2_lib.baseboard_fab2(sch_1):page227_i103"
				( attribute "CDS_LIB" "mstr_discrete"
					( Origin gPackager )
				)
				( attribute "CDS_LOCATION" "R1A3"
					( Origin gPackager )
				)
				( attribute "CDS_SEC" "1"
					( Origin gPackager )
				)
				( attribute "LOCATION" "R1A3"
					( Origin gFrontEnd )
				)
				( attribute "MATERIAL" "EMPTY"
					( Origin gFrontEnd )
				)
				( attribute "PACK_TYPE" "0402"
					( Origin gFrontEnd )
				)
				( attribute "PART_NUMBER" "G21796-187"
					( Origin gFrontEnd )
				)
				( attribute "PHYS_PAGE" "227"
					( Origin gFrontEnd )
				)
				( attribute "ROT" "0"
					( Origin gFrontEnd )
				)
				( attribute "SEC" "1"
					( Origin gFrontEnd )
				)
				( attribute "SEC_TYPE" "0402"
					( Origin gFrontEnd )
				)
				( attribute "TOLERANCE" "1%"
					( Origin gFrontEnd )
				)
				( attribute "VALUE" "68.1K"
					( Origin gFrontEnd )
				)
				( attribute "VER" "2"
					( Origin gFrontEnd )
				)
				( attribute "WATTAGE" "1/16W"
					( Origin gFrontEnd )
				)
				( attribute "XY" "(4325,2325)"
					( Origin gFrontEnd )
				)
				( attribute "CHIPS_PART_NAME" "RES"
					( Origin gPackager )
				)
				( attribute "CDS_PART_NAME" "RES_0402-68.1K,1%,1/16W,EMPTY,A"
					( Origin gPackager )
				)
				( objectStatus "R1A3" )
				( pin "a"
					( attribute "PN" "1"
						( Origin gPackager )
					)
					( objectStatus "R1A3.1" )
				)
				( pin "b"
					( attribute "PN" "2"
						( Origin gPackager )
					)
					( objectStatus "R1A3.2" )
				)
			)
			( gate "@baseboard_fab2_lib.baseboard_fab2(sch_1):page227_i105"
				( attribute "CDS_LIB" "mstr_discrete"
					( Origin gPackager )
				)
				( attribute "CDS_LOCATION" "R1A2"
					( Origin gPackager )
				)
				( attribute "CDS_SEC" "1"
					( Origin gPackager )
				)
				( attribute "LOCATION" "R1A2"
					( Origin gFrontEnd )
				)
				( attribute "MATERIAL" "EMPTY"
					( Origin gFrontEnd )
				)
				( attribute "PACK_TYPE" "0402"
					( Origin gFrontEnd )
				)
				( attribute "PART_NUMBER" "G21796-187"
					( Origin gFrontEnd )
				)
				( attribute "PHYS_PAGE" "227"
					( Origin gFrontEnd )
				)
				( attribute "ROT" "0"
					( Origin gFrontEnd )
				)
				( attribute "SEC" "1"
					( Origin gFrontEnd )
				)
				( attribute "SEC_TYPE" "0402"
					( Origin gFrontEnd )
				)
				( attribute "TOLERANCE" "1%"
					( Origin gFrontEnd )
				)
				( attribute "VALUE" "68.1K"
					( Origin gFrontEnd )
				)
				( attribute "VER" "2"
					( Origin gFrontEnd )
				)
				( attribute "WATTAGE" "1/16W"
					( Origin gFrontEnd )
				)
				( attribute "XY" "(4300,175)"
					( Origin gFrontEnd )
				)
				( attribute "CHIPS_PART_NAME" "RES"
					( Origin gPackager )
				)
				( attribute "CDS_PART_NAME" "RES_0402-68.1K,1%,1/16W,EMPTY,A"
					( Origin gPackager )
				)
				( objectStatus "R1A2" )
				( pin "a"
					( attribute "PN" "1"
						( Origin gPackager )
					)
					( objectStatus "R1A2.1" )
				)
				( pin "b"
					( attribute "PN" "2"
						( Origin gPackager )
					)
					( objectStatus "R1A2.2" )
				)
			)
			( gate "@baseboard_fab2_lib.baseboard_fab2(sch_1):page228_i58"
				( attribute "BOM_COST" "MEM_VRD_PVPP_AB"
					( Origin gFrontEnd )
				)
				( attribute "CDS_LIB" "mstr_discrete"
					( Origin gPackager )
				)
				( attribute "CDS_LOCATION" "R1A1"
					( Origin gPackager )
				)
				( attribute "CDS_SEC" "1"
					( Origin gPackager )
				)
				( attribute "LOCATION" "R1A1"
					( Origin gFrontEnd )
				)
				( attribute "MATERIAL" "CHIP"
					( Origin gFrontEnd )
				)
				( attribute "PACK_TYPE" "0603"
					( Origin gFrontEnd )
				)
				( attribute "PART_NUMBER" "G22026-003"
					( Origin gFrontEnd )
				)
				( attribute "PHYS_PAGE" "228"
					( Origin gFrontEnd )
				)
				( attribute "ROOM" "VDDQ_KLM_PWR_VR"
					( Origin gFrontEnd )
				)
				( attribute "ROT" "0"
					( Origin gFrontEnd )
				)
				( attribute "SEC" "1"
					( Origin gPackager )
				)
				( attribute "TOLERANCE" "1%"
					( Origin gFrontEnd )
				)
				( attribute "VALUE" "120.0"
					( Origin gFrontEnd )
				)
				( attribute "VER" "2"
					( Origin gFrontEnd )
				)
				( attribute "WATTAGE" "1/10W"
					( Origin gFrontEnd )
				)
				( attribute "XY" "(4525,-500)"
					( Origin gFrontEnd )
				)
				( attribute "CHIPS_PART_NAME" "RES"
					( Origin gPackager )
				)
				( attribute "CDS_PART_NAME" "RES_0603-120.0,1%,1/10W,CHIP,GA"
					( Origin gPackager )
				)
				( objectStatus "R1A1" )
				( pin "a"
					( attribute "PN" "1"
						( Origin gPackager )
					)
					( objectStatus "R1A1.1" )
				)
				( pin "b"
					( attribute "PN" "2"
						( Origin gPackager )
					)
					( objectStatus "R1A1.2" )
				)
			)
			( gate "@baseboard_fab2_lib.baseboard_fab2(sch_1):page228_i74"
				( attribute "CDS_LIB" "mstr_discrete"
					( Origin gPackager )
				)
				( attribute "CDS_LOCATION" "R7L2"
					( Origin gPackager )
				)
				( attribute "CDS_SEC" "1"
					( Origin gPackager )
				)
				( attribute "LOCATION" "R7L2"
					( Origin gFrontEnd )
				)
				( attribute "MATERIAL" "EMPTY"
					( Origin gFrontEnd )
				)
				( attribute "PACK_TYPE" "0402"
					( Origin gFrontEnd )
				)
				( attribute "PART_NUMBER" "G21796-017"
					( Origin gFrontEnd )
				)
				( attribute "PHYS_PAGE" "228"
					( Origin gFrontEnd )
				)
				( attribute "ROOM" "VDDQ_KLM_PWR_VR"
					( Origin gFrontEnd )
				)
				( attribute "ROT" "0"
					( Origin gFrontEnd )
				)
				( attribute "SEC" "1"
					( Origin gFrontEnd )
				)
				( attribute "SEC_TYPE" "0402"
					( Origin gFrontEnd )
				)
				( attribute "TOLERANCE" "1%"
					( Origin gFrontEnd )
				)
				( attribute "VALUE" "100.0"
					( Origin gFrontEnd )
				)
				( attribute "VER" "2"
					( Origin gFrontEnd )
				)
				( attribute "WATTAGE" "1/16W"
					( Origin gFrontEnd )
				)
				( attribute "XY" "(-375,1925)"
					( Origin gFrontEnd )
				)
				( attribute "CHIPS_PART_NAME" "RES"
					( Origin gPackager )
				)
				( attribute "CDS_PART_NAME" "RES_0402-100.0,1%,1/16W,EMPTY,A"
					( Origin gPackager )
				)
				( objectStatus "R7L2" )
				( pin "a"
					( attribute "PN" "1"
						( Origin gPackager )
					)
					( objectStatus "R7L2.1" )
				)
				( pin "b"
					( attribute "PN" "2"
						( Origin gPackager )
					)
					( objectStatus "R7L2.2" )
				)
			)
			( gate "@baseboard_fab2_lib.baseboard_fab2(sch_1):page228_i75"
				( attribute "CDS_LIB" "mstr_discrete"
					( Origin gPackager )
				)
				( attribute "CDS_LOCATION" "C9L9"
					( Origin gPackager )
				)
				( attribute "CDS_SEC" "1"
					( Origin gPackager )
				)
				( attribute "LOCATION" "C9L9"
					( Origin gFrontEnd )
				)
				( attribute "MATERIAL" "ALUM"
					( Origin gFrontEnd )
				)
				( attribute "PACK_TYPE" "3018"
					( Origin gFrontEnd )
				)
				( attribute "PART_NUMBER" "699013-049"
					( Origin gFrontEnd )
				)
				( attribute "PHYS_PAGE" "228"
					( Origin gFrontEnd )
				)
				( attribute "ROOM" "VDDQ_KLM_PWR_VR"
					( Origin gFrontEnd )
				)
				( attribute "ROT" "0"
					( Origin gFrontEnd )
				)
				( attribute "SEC" "1"
					( Origin gFrontEnd )
				)
				( attribute "SEC_TYPE" "3018"
					( Origin gFrontEnd )
				)
				( attribute "TOLERANCE" "20%"
					( Origin gFrontEnd )
				)
				( attribute "VALUE" "470UF"
					( Origin gFrontEnd )
				)
				( attribute "VER" "1"
					( Origin gFrontEnd )
				)
				( attribute "VOLTAGE" "2.5V"
					( Units "uVoltage" "V" 1.000000)
					( Origin gFrontEnd )
				)
				( attribute "XY" "(2900,-475)"
					( Origin gFrontEnd )
				)
				( attribute "CHIPS_PART_NAME" "CAPP"
					( Origin gPackager )
				)
				( attribute "CDS_PART_NAME" "CAPP_3018-470UF,2.5V,20%,ALUM,A"
					( Origin gPackager )
				)
				( objectStatus "C9L9" )
				( pin "a"
					( attribute "PN" "1"
						( Origin gPackager )
					)
					( objectStatus "C9L9.1" )
				)
				( pin "b"
					( attribute "PN" "2"
						( Origin gPackager )
					)
					( objectStatus "C9L9.2" )
				)
			)
			( gate "@baseboard_fab2_lib.baseboard_fab2(sch_1):page228_i76"
				( attribute "CDS_LIB" "mstr_discrete"
					( Origin gPackager )
				)
				( attribute "CDS_LOCATION" "C9L12"
					( Origin gPackager )
				)
				( attribute "CDS_SEC" "1"
					( Origin gPackager )
				)
				( attribute "LOCATION" "C9L12"
					( Origin gFrontEnd )
				)
				( attribute "MATERIAL" "ALUM"
					( Origin gFrontEnd )
				)
				( attribute "PACK_TYPE" "3018"
					( Origin gFrontEnd )
				)
				( attribute "PART_NUMBER" "699013-049"
					( Origin gFrontEnd )
				)
				( attribute "PHYS_PAGE" "228"
					( Origin gFrontEnd )
				)
				( attribute "ROOM" "VDDQ_KLM_PWR_VR"
					( Origin gFrontEnd )
				)
				( attribute "ROT" "0"
					( Origin gFrontEnd )
				)
				( attribute "SEC" "1"
					( Origin gFrontEnd )
				)
				( attribute "SEC_TYPE" "3018"
					( Origin gFrontEnd )
				)
				( attribute "TOLERANCE" "20%"
					( Origin gFrontEnd )
				)
				( attribute "VALUE" "470UF"
					( Origin gFrontEnd )
				)
				( attribute "VER" "1"
					( Origin gFrontEnd )
				)
				( attribute "VOLTAGE" "2.5V"
					( Units "uVoltage" "V" 1.000000)
					( Origin gFrontEnd )
				)
				( attribute "XY" "(3325,-475)"
					( Origin gFrontEnd )
				)
				( attribute "CHIPS_PART_NAME" "CAPP"
					( Origin gPackager )
				)
				( attribute "CDS_PART_NAME" "CAPP_3018-470UF,2.5V,20%,ALUM,A"
					( Origin gPackager )
				)
				( objectStatus "C9L12" )
				( pin "a"
					( attribute "PN" "1"
						( Origin gPackager )
					)
					( objectStatus "C9L12.1" )
				)
				( pin "b"
					( attribute "PN" "2"
						( Origin gPackager )
					)
					( objectStatus "C9L12.2" )
				)
			)
			( gate "@baseboard_fab2_lib.baseboard_fab2(sch_1):page228_i77"
				( attribute "CDS_LIB" "mstr_discrete"
					( Origin gPackager )
				)
				( attribute "CDS_LOCATION" "C9L4"
					( Origin gPackager )
				)
				( attribute "CDS_SEC" "1"
					( Origin gPackager )
				)
				( attribute "LOCATION" "C9L4"
					( Origin gFrontEnd )
				)
				( attribute "MATERIAL" "ALUM"
					( Origin gFrontEnd )
				)
				( attribute "PACK_TYPE" "3018"
					( Origin gFrontEnd )
				)
				( attribute "PART_NUMBER" "699013-049"
					( Origin gFrontEnd )
				)
				( attribute "PHYS_PAGE" "228"
					( Origin gFrontEnd )
				)
				( attribute "ROOM" "VDDQ_KLM_PWR_VR"
					( Origin gFrontEnd )
				)
				( attribute "ROT" "0"
					( Origin gFrontEnd )
				)
				( attribute "SEC" "1"
					( Origin gFrontEnd )
				)
				( attribute "SEC_TYPE" "3018"
					( Origin gFrontEnd )
				)
				( attribute "TOLERANCE" "20%"
					( Origin gFrontEnd )
				)
				( attribute "VALUE" "470UF"
					( Origin gFrontEnd )
				)
				( attribute "VER" "1"
					( Origin gFrontEnd )
				)
				( attribute "VOLTAGE" "2.5V"
					( Units "uVoltage" "V" 1.000000)
					( Origin gFrontEnd )
				)
				( attribute "XY" "(3750,-475)"
					( Origin gFrontEnd )
				)
				( attribute "CHIPS_PART_NAME" "CAPP"
					( Origin gPackager )
				)
				( attribute "CDS_PART_NAME" "CAPP_3018-470UF,2.5V,20%,ALUM,A"
					( Origin gPackager )
				)
				( objectStatus "C9L4" )
				( pin "a"
					( attribute "PN" "1"
						( Origin gPackager )
					)
					( objectStatus "C9L4.1" )
				)
				( pin "b"
					( attribute "PN" "2"
						( Origin gPackager )
					)
					( objectStatus "C9L4.2" )
				)
			)
			( gate "@baseboard_fab2_lib.baseboard_fab2(sch_1):page228_i78"
				( attribute "CDS_LIB" "mstr_discrete"
					( Origin gPackager )
				)
				( attribute "CDS_LOCATION" "C9L2"
					( Origin gPackager )
				)
				( attribute "CDS_SEC" "1"
					( Origin gPackager )
				)
				( attribute "LOCATION" "C9L2"
					( Origin gFrontEnd )
				)
				( attribute "MATERIAL" "ALUM"
					( Origin gFrontEnd )
				)
				( attribute "PACK_TYPE" "3018"
					( Origin gFrontEnd )
				)
				( attribute "PART_NUMBER" "699013-049"
					( Origin gFrontEnd )
				)
				( attribute "PHYS_PAGE" "228"
					( Origin gFrontEnd )
				)
				( attribute "ROOM" "VDDQ_KLM_PWR_VR"
					( Origin gFrontEnd )
				)
				( attribute "ROT" "0"
					( Origin gFrontEnd )
				)
				( attribute "SEC" "1"
					( Origin gFrontEnd )
				)
				( attribute "SEC_TYPE" "3018"
					( Origin gFrontEnd )
				)
				( attribute "TOLERANCE" "20%"
					( Origin gFrontEnd )
				)
				( attribute "VALUE" "470UF"
					( Origin gFrontEnd )
				)
				( attribute "VER" "1"
					( Origin gFrontEnd )
				)
				( attribute "VOLTAGE" "2.5V"
					( Units "uVoltage" "V" 1.000000)
					( Origin gFrontEnd )
				)
				( attribute "XY" "(4150,-500)"
					( Origin gFrontEnd )
				)
				( attribute "CHIPS_PART_NAME" "CAPP"
					( Origin gPackager )
				)
				( attribute "CDS_PART_NAME" "CAPP_3018-470UF,2.5V,20%,ALUM,A"
					( Origin gPackager )
				)
				( objectStatus "C9L2" )
				( pin "a"
					( attribute "PN" "1"
						( Origin gPackager )
					)
					( objectStatus "C9L2.1" )
				)
				( pin "b"
					( attribute "PN" "2"
						( Origin gPackager )
					)
					( objectStatus "C9L2.2" )
				)
			)
			( gate "@baseboard_fab2_lib.baseboard_fab2(sch_1):page228_i82"
				( attribute "BOM_COST" "MEM_VRD_PVDDQ_CD"
					( Origin gFrontEnd )
				)
				( attribute "CDS_LIB" "mstr_discrete"
					( Origin gPackager )
				)
				( attribute "CDS_LOCATION" "C2A8"
					( Origin gPackager )
				)
				( attribute "CDS_SEC" "1"
					( Origin gPackager )
				)
				( attribute "LOCATION" "C2A8"
					( Origin gFrontEnd )
				)
				( attribute "MATERIAL" "X5R"
					( Origin gFrontEnd )
				)
				( attribute "PACK_TYPE" "0805"
					( Origin gFrontEnd )
				)
				( attribute "PART_NUMBER" "602433-112"
					( Origin gFrontEnd )
				)
				( attribute "PHYS_PAGE" "228"
					( Origin gFrontEnd )
				)
				( attribute "ROOM" "VDDQ_KLM_PWR_VR"
					( Origin gFrontEnd )
				)
				( attribute "ROT" "0"
					( Origin gFrontEnd )
				)
				( attribute "SEC" "1"
					( Origin gFrontEnd )
				)
				( attribute "SEC_TYPE" "0805"
					( Origin gFrontEnd )
				)
				( attribute "TOLERANCE" "20%"
					( Origin gFrontEnd )
				)
				( attribute "VALUE" "100UF"
					( Origin gFrontEnd )
				)
				( attribute "VER" "1"
					( Origin gFrontEnd )
				)
				( attribute "VOLTAGE" "4V"
					( Units "uVoltage" "V" 1.000000)
					( Origin gFrontEnd )
				)
				( attribute "XY" "(5000,2825)"
					( Origin gFrontEnd )
				)
				( attribute "CHIPS_PART_NAME" "CAP"
					( Origin gPackager )
				)
				( attribute "CDS_PART_NAME" "CAP_0805-100UF,4V,20%,X5R,6024A"
					( Origin gPackager )
				)
				( objectStatus "C2A8" )
				( pin "a"
					( attribute "PN" "1"
						( Origin gPackager )
					)
					( objectStatus "C2A8.1" )
				)
				( pin "b"
					( attribute "PN" "2"
						( Origin gPackager )
					)
					( objectStatus "C2A8.2" )
				)
			)
			( gate "@baseboard_fab2_lib.baseboard_fab2(sch_1):page228_i83"
				( attribute "BOM_COST" "MEM_VRD_PVDDQ_CD"
					( Origin gFrontEnd )
				)
				( attribute "CDS_LIB" "mstr_discrete"
					( Origin gPackager )
				)
				( attribute "CDS_LOCATION" "C8L2"
					( Origin gPackager )
				)
				( attribute "CDS_SEC" "1"
					( Origin gPackager )
				)
				( attribute "LOCATION" "C8L2"
					( Origin gFrontEnd )
				)
				( attribute "MATERIAL" "X5R"
					( Origin gFrontEnd )
				)
				( attribute "PACK_TYPE" "0805"
					( Origin gFrontEnd )
				)
				( attribute "PART_NUMBER" "602433-112"
					( Origin gFrontEnd )
				)
				( attribute "PHYS_PAGE" "228"
					( Origin gFrontEnd )
				)
				( attribute "ROOM" "VDDQ_KLM_PWR_VR"
					( Origin gFrontEnd )
				)
				( attribute "ROT" "0"
					( Origin gFrontEnd )
				)
				( attribute "SEC" "1"
					( Origin gFrontEnd )
				)
				( attribute "SEC_TYPE" "0805"
					( Origin gFrontEnd )
				)
				( attribute "TOLERANCE" "20%"
					( Origin gFrontEnd )
				)
				( attribute "VALUE" "100UF"
					( Origin gFrontEnd )
				)
				( attribute "VER" "1"
					( Origin gFrontEnd )
				)
				( attribute "VOLTAGE" "4V"
					( Units "uVoltage" "V" 1.000000)
					( Origin gFrontEnd )
				)
				( attribute "XY" "(4600,2825)"
					( Origin gFrontEnd )
				)
				( attribute "CHIPS_PART_NAME" "CAP"
					( Origin gPackager )
				)
				( attribute "CDS_PART_NAME" "CAP_0805-100UF,4V,20%,X5R,6024A"
					( Origin gPackager )
				)
				( objectStatus "C8L2" )
				( pin "a"
					( attribute "PN" "1"
						( Origin gPackager )
					)
					( objectStatus "C8L2.1" )
				)
				( pin "b"
					( attribute "PN" "2"
						( Origin gPackager )
					)
					( objectStatus "C8L2.2" )
				)
			)
			( gate "@baseboard_fab2_lib.baseboard_fab2(sch_1):page228_i88"
				( attribute "BOM_COST" "MEM_VRD_PVDDQ_CD"
					( Origin gFrontEnd )
				)
				( attribute "CDS_LIB" "mstr_discrete"
					( Origin gPackager )
				)
				( attribute "CDS_LOCATION" "C8L11"
					( Origin gPackager )
				)
				( attribute "CDS_SEC" "1"
					( Origin gPackager )
				)
				( attribute "LOCATION" "C8L11"
					( Origin gFrontEnd )
				)
				( attribute "MATERIAL" "X5R"
					( Origin gFrontEnd )
				)
				( attribute "PACK_TYPE" "0805"
					( Origin gFrontEnd )
				)
				( attribute "PART_NUMBER" "602433-112"
					( Origin gFrontEnd )
				)
				( attribute "PHYS_PAGE" "228"
					( Origin gFrontEnd )
				)
				( attribute "ROOM" "VDDQ_KLM_PWR_VR"
					( Origin gFrontEnd )
				)
				( attribute "ROT" "0"
					( Origin gFrontEnd )
				)
				( attribute "SEC" "1"
					( Origin gFrontEnd )
				)
				( attribute "SEC_TYPE" "0805"
					( Origin gFrontEnd )
				)
				( attribute "TOLERANCE" "20%"
					( Origin gFrontEnd )
				)
				( attribute "VALUE" "100UF"
					( Origin gFrontEnd )
				)
				( attribute "VER" "1"
					( Origin gFrontEnd )
				)
				( attribute "VOLTAGE" "4V"
					( Units "uVoltage" "V" 1.000000)
					( Origin gFrontEnd )
				)
				( attribute "XY" "(4250,2825)"
					( Origin gFrontEnd )
				)
				( attribute "CHIPS_PART_NAME" "CAP"
					( Origin gPackager )
				)
				( attribute "CDS_PART_NAME" "CAP_0805-100UF,4V,20%,X5R,6024A"
					( Origin gPackager )
				)
				( objectStatus "C8L11" )
				( pin "a"
					( attribute "PN" "1"
						( Origin gPackager )
					)
					( objectStatus "C8L11.1" )
				)
				( pin "b"
					( attribute "PN" "2"
						( Origin gPackager )
					)
					( objectStatus "C8L11.2" )
				)
			)
			( gate "@baseboard_fab2_lib.baseboard_fab2(sch_1):page228_i89"
				( attribute "BOM_COST" "MEM_VRD_PVDDQ_CD"
					( Origin gFrontEnd )
				)
				( attribute "CDS_LIB" "mstr_discrete"
					( Origin gPackager )
				)
				( attribute "CDS_LOCATION" "C2A16"
					( Origin gPackager )
				)
				( attribute "CDS_SEC" "1"
					( Origin gPackager )
				)
				( attribute "LOCATION" "C2A16"
					( Origin gFrontEnd )
				)
				( attribute "MATERIAL" "X5R"
					( Origin gFrontEnd )
				)
				( attribute "PACK_TYPE" "0805"
					( Origin gFrontEnd )
				)
				( attribute "PART_NUMBER" "602433-112"
					( Origin gFrontEnd )
				)
				( attribute "PHYS_PAGE" "228"
					( Origin gFrontEnd )
				)
				( attribute "ROOM" "VDDQ_KLM_PWR_VR"
					( Origin gFrontEnd )
				)
				( attribute "ROT" "0"
					( Origin gFrontEnd )
				)
				( attribute "SEC" "1"
					( Origin gFrontEnd )
				)
				( attribute "SEC_TYPE" "0805"
					( Origin gFrontEnd )
				)
				( attribute "TOLERANCE" "20%"
					( Origin gFrontEnd )
				)
				( attribute "VALUE" "100UF"
					( Origin gFrontEnd )
				)
				( attribute "VER" "1"
					( Origin gFrontEnd )
				)
				( attribute "VOLTAGE" "4V"
					( Units "uVoltage" "V" 1.000000)
					( Origin gFrontEnd )
				)
				( attribute "XY" "(3850,2825)"
					( Origin gFrontEnd )
				)
				( attribute "CHIPS_PART_NAME" "CAP"
					( Origin gPackager )
				)
				( attribute "CDS_PART_NAME" "CAP_0805-100UF,4V,20%,X5R,6024A"
					( Origin gPackager )
				)
				( objectStatus "C2A16" )
				( pin "a"
					( attribute "PN" "1"
						( Origin gPackager )
					)
					( objectStatus "C2A16.1" )
				)
				( pin "b"
					( attribute "PN" "2"
						( Origin gPackager )
					)
					( objectStatus "C2A16.2" )
				)
			)
			( gate "@baseboard_fab2_lib.baseboard_fab2(sch_1):page228_i90"
				( attribute "BOM_COST" "MEM_VRD_PVDDQ_CD"
					( Origin gFrontEnd )
				)
				( attribute "CDS_LIB" "mstr_discrete"
					( Origin gPackager )
				)
				( attribute "CDS_LOCATION" "C8M7"
					( Origin gPackager )
				)
				( attribute "CDS_SEC" "1"
					( Origin gPackager )
				)
				( attribute "LOCATION" "C8M7"
					( Origin gFrontEnd )
				)
				( attribute "MATERIAL" "X5R"
					( Origin gFrontEnd )
				)
				( attribute "PACK_TYPE" "0805"
					( Origin gFrontEnd )
				)
				( attribute "PART_NUMBER" "602433-112"
					( Origin gFrontEnd )
				)
				( attribute "PHYS_PAGE" "228"
					( Origin gFrontEnd )
				)
				( attribute "ROOM" "VDDQ_KLM_PWR_VR"
					( Origin gFrontEnd )
				)
				( attribute "ROT" "0"
					( Origin gFrontEnd )
				)
				( attribute "SEC" "1"
					( Origin gFrontEnd )
				)
				( attribute "SEC_TYPE" "0805"
					( Origin gFrontEnd )
				)
				( attribute "TOLERANCE" "20%"
					( Origin gFrontEnd )
				)
				( attribute "VALUE" "100UF"
					( Origin gFrontEnd )
				)
				( attribute "VER" "1"
					( Origin gFrontEnd )
				)
				( attribute "VOLTAGE" "4V"
					( Units "uVoltage" "V" 1.000000)
					( Origin gFrontEnd )
				)
				( attribute "XY" "(3500,2825)"
					( Origin gFrontEnd )
				)
				( attribute "CHIPS_PART_NAME" "CAP"
					( Origin gPackager )
				)
				( attribute "CDS_PART_NAME" "CAP_0805-100UF,4V,20%,X5R,6024A"
					( Origin gPackager )
				)
				( objectStatus "C8M7" )
				( pin "a"
					( attribute "PN" "1"
						( Origin gPackager )
					)
					( objectStatus "C8M7.1" )
				)
				( pin "b"
					( attribute "PN" "2"
						( Origin gPackager )
					)
					( objectStatus "C8M7.2" )
				)
			)
			( gate "@baseboard_fab2_lib.baseboard_fab2(sch_1):page228_i91"
				( attribute "BOM_COST" "MEM_VRD_PVDDQ_CD"
					( Origin gFrontEnd )
				)
				( attribute "CDS_LIB" "mstr_discrete"
					( Origin gPackager )
				)
				( attribute "CDS_LOCATION" "C8M11"
					( Origin gPackager )
				)
				( attribute "CDS_SEC" "1"
					( Origin gPackager )
				)
				( attribute "LOCATION" "C8M11"
					( Origin gFrontEnd )
				)
				( attribute "MATERIAL" "X5R"
					( Origin gFrontEnd )
				)
				( attribute "PACK_TYPE" "0805"
					( Origin gFrontEnd )
				)
				( attribute "PART_NUMBER" "602433-112"
					( Origin gFrontEnd )
				)
				( attribute "PHYS_PAGE" "228"
					( Origin gFrontEnd )
				)
				( attribute "ROOM" "VDDQ_KLM_PWR_VR"
					( Origin gFrontEnd )
				)
				( attribute "ROT" "0"
					( Origin gFrontEnd )
				)
				( attribute "SEC" "1"
					( Origin gFrontEnd )
				)
				( attribute "SEC_TYPE" "0805"
					( Origin gFrontEnd )
				)
				( attribute "TOLERANCE" "20%"
					( Origin gFrontEnd )
				)
				( attribute "VALUE" "100UF"
					( Origin gFrontEnd )
				)
				( attribute "VER" "1"
					( Origin gFrontEnd )
				)
				( attribute "VOLTAGE" "4V"
					( Units "uVoltage" "V" 1.000000)
					( Origin gFrontEnd )
				)
				( attribute "XY" "(3150,2825)"
					( Origin gFrontEnd )
				)
				( attribute "CHIPS_PART_NAME" "CAP"
					( Origin gPackager )
				)
				( attribute "CDS_PART_NAME" "CAP_0805-100UF,4V,20%,X5R,6024A"
					( Origin gPackager )
				)
				( objectStatus "C8M11" )
				( pin "a"
					( attribute "PN" "1"
						( Origin gPackager )
					)
					( objectStatus "C8M11.1" )
				)
				( pin "b"
					( attribute "PN" "2"
						( Origin gPackager )
					)
					( objectStatus "C8M11.2" )
				)
			)
			( gate "@baseboard_fab2_lib.baseboard_fab2(sch_1):page228_i92"
				( attribute "BOM_COST" "MEM_VRD_PVDDQ_CD"
					( Origin gFrontEnd )
				)
				( attribute "CDS_LIB" "mstr_discrete"
					( Origin gPackager )
				)
				( attribute "CDS_LOCATION" "C7L1"
					( Origin gPackager )
				)
				( attribute "CDS_SEC" "1"
					( Origin gPackager )
				)
				( attribute "LOCATION" "C7L1"
					( Origin gFrontEnd )
				)
				( attribute "MATERIAL" "X5R"
					( Origin gFrontEnd )
				)
				( attribute "PACK_TYPE" "0805"
					( Origin gFrontEnd )
				)
				( attribute "PART_NUMBER" "602433-112"
					( Origin gFrontEnd )
				)
				( attribute "PHYS_PAGE" "228"
					( Origin gFrontEnd )
				)
				( attribute "ROOM" "VDDQ_KLM_PWR_VR"
					( Origin gFrontEnd )
				)
				( attribute "ROT" "0"
					( Origin gFrontEnd )
				)
				( attribute "SEC" "1"
					( Origin gFrontEnd )
				)
				( attribute "SEC_TYPE" "0805"
					( Origin gFrontEnd )
				)
				( attribute "TOLERANCE" "20%"
					( Origin gFrontEnd )
				)
				( attribute "VALUE" "100UF"
					( Origin gFrontEnd )
				)
				( attribute "VER" "1"
					( Origin gFrontEnd )
				)
				( attribute "VOLTAGE" "4V"
					( Units "uVoltage" "V" 1.000000)
					( Origin gFrontEnd )
				)
				( attribute "XY" "(2750,2825)"
					( Origin gFrontEnd )
				)
				( attribute "CHIPS_PART_NAME" "CAP"
					( Origin gPackager )
				)
				( attribute "CDS_PART_NAME" "CAP_0805-100UF,4V,20%,X5R,6024A"
					( Origin gPackager )
				)
				( objectStatus "C7L1" )
				( pin "a"
					( attribute "PN" "1"
						( Origin gPackager )
					)
					( objectStatus "C7L1.1" )
				)
				( pin "b"
					( attribute "PN" "2"
						( Origin gPackager )
					)
					( objectStatus "C7L1.2" )
				)
			)
			( gate "@baseboard_fab2_lib.baseboard_fab2(sch_1):page228_i110"
				( attribute "BOM_COST" "MEM_VRD_PVDDQ_CD"
					( Origin gFrontEnd )
				)
				( attribute "CDS_LIB" "mstr_discrete"
					( Origin gPackager )
				)
				( attribute "CDS_LOCATION" "C8L1"
					( Origin gPackager )
				)
				( attribute "CDS_SEC" "1"
					( Origin gPackager )
				)
				( attribute "LOCATION" "C8L1"
					( Origin gFrontEnd )
				)
				( attribute "MATERIAL" "X5R"
					( Origin gFrontEnd )
				)
				( attribute "PACK_TYPE" "0805"
					( Origin gFrontEnd )
				)
				( attribute "PART_NUMBER" "602433-112"
					( Origin gFrontEnd )
				)
				( attribute "PHYS_PAGE" "228"
					( Origin gFrontEnd )
				)
				( attribute "ROOM" "VDDQ_KLM_PWR_VR"
					( Origin gFrontEnd )
				)
				( attribute "ROT" "0"
					( Origin gFrontEnd )
				)
				( attribute "SEC" "1"
					( Origin gFrontEnd )
				)
				( attribute "SEC_TYPE" "0805"
					( Origin gFrontEnd )
				)
				( attribute "TOLERANCE" "20%"
					( Origin gFrontEnd )
				)
				( attribute "VALUE" "100UF"
					( Origin gFrontEnd )
				)
				( attribute "VER" "1"
					( Origin gFrontEnd )
				)
				( attribute "VOLTAGE" "4V"
					( Units "uVoltage" "V" 1.000000)
					( Origin gFrontEnd )
				)
				( attribute "XY" "(2400,2825)"
					( Origin gFrontEnd )
				)
				( attribute "CHIPS_PART_NAME" "CAP"
					( Origin gPackager )
				)
				( attribute "CDS_PART_NAME" "CAP_0805-100UF,4V,20%,X5R,6024A"
					( Origin gPackager )
				)
				( objectStatus "C8L1" )
				( pin "a"
					( attribute "PN" "1"
						( Origin gPackager )
					)
					( objectStatus "C8L1.1" )
				)
				( pin "b"
					( attribute "PN" "2"
						( Origin gPackager )
					)
					( objectStatus "C8L1.2" )
				)
			)
			( gate "@baseboard_fab2_lib.baseboard_fab2(sch_1):page228_i124"
				( attribute "BOM_COST" "MEM_VRD_PVDDQ_CD"
					( Origin gFrontEnd )
				)
				( attribute "CDS_LIB" "mstr_discrete"
					( Origin gPackager )
				)
				( attribute "CDS_LOCATION" "L1B1"
					( Origin gPackager )
				)
				( attribute "CDS_SEC" "1"
					( Origin gPackager )
				)
				( attribute "LOCATION" "L1B1"
					( Origin gFrontEnd )
				)
				( attribute "MATERIAL" "IND"
					( Origin gFrontEnd )
				)
				( attribute "PACK_TYPE" "SM"
					( Origin gFrontEnd )
				)
				( attribute "PART_NUMBER" "D92183-020"
					( Origin gFrontEnd )
				)
				( attribute "PHYS_PAGE" "228"
					( Origin gFrontEnd )
				)
				( attribute "ROOM" "VDDQ_KLM_PWR_VR"
					( Origin gFrontEnd )
				)
				( attribute "ROT" "0"
					( Origin gFrontEnd )
				)
				( attribute "SEC" "1"
					( Origin gFrontEnd )
				)
				( attribute "SEC_TYPE" "SM"
					( Origin gFrontEnd )
				)
				( attribute "VALUE" "100NH"
					( Origin gFrontEnd )
				)
				( attribute "VER" "1"
					( Origin gFrontEnd )
				)
				( attribute "XY" "(-1100,1100)"
					( Origin gFrontEnd )
				)
				( attribute "CHIPS_PART_NAME" "INDUCTOR"
					( Origin gPackager )
				)
				( attribute "CDS_PART_NAME" "INDUCTOR_SM-100NH,IND,D92183-0B"
					( Origin gPackager )
				)
				( objectStatus "L1B1" )
				( pin "ina"
					( attribute "PN" "1"
						( Origin gPackager )
					)
					( objectStatus "L1B1.1" )
				)
				( pin "inb"
					( attribute "PN" "2"
						( Origin gPackager )
					)
					( objectStatus "L1B1.2" )
				)
			)
			( gate "@baseboard_fab2_lib.baseboard_fab2(sch_1):page228_i175"
				( attribute "CDS_LIB" "mstr_discrete"
					( Origin gPackager )
				)
				( attribute "CDS_LOCATION" "C1B10"
					( Origin gPackager )
				)
				( attribute "CDS_SEC" "1"
					( Origin gPackager )
				)
				( attribute "LOCATION" "C1B10"
					( Origin gFrontEnd )
				)
				( attribute "MATERIAL" "OSCON"
					( Origin gFrontEnd )
				)
				( attribute "PACK_TYPE" "2626"
					( Origin gFrontEnd )
				)
				( attribute "PART_NUMBER" "A31228-047"
					( Origin gFrontEnd )
				)
				( attribute "PHYS_PAGE" "228"
					( Origin gFrontEnd )
				)
				( attribute "ROOM" "VDDQ_KLM_PWR_VR"
					( Origin gFrontEnd )
				)
				( attribute "ROT" "0"
					( Origin gFrontEnd )
				)
				( attribute "SEC" "1"
					( Origin gFrontEnd )
				)
				( attribute "SEC_TYPE" "2626"
					( Origin gFrontEnd )
				)
				( attribute "TOLERANCE" "20%"
					( Origin gFrontEnd )
				)
				( attribute "VALUE" "270UF"
					( Origin gFrontEnd )
				)
				( attribute "VER" "1"
					( Origin gFrontEnd )
				)
				( attribute "VOLTAGE" "16V"
					( Units "uVoltage" "V" 1.000000)
					( Origin gFrontEnd )
				)
				( attribute "XY" "(-675,900)"
					( Origin gFrontEnd )
				)
				( attribute "CHIPS_PART_NAME" "CAPP"
					( Origin gPackager )
				)
				( attribute "CDS_PART_NAME" "CAPP_2626-270UF,16V,20%,OSCON,A"
					( Origin gPackager )
				)
				( objectStatus "C1B10" )
				( pin "a"
					( attribute "PN" "1"
						( Origin gPackager )
					)
					( objectStatus "C1B10.1" )
				)
				( pin "b"
					( attribute "PN" "2"
						( Origin gPackager )
					)
					( objectStatus "C1B10.2" )
				)
			)
			( gate "@baseboard_fab2_lib.baseboard_fab2(sch_1):page228_i183"
				( attribute "BOM_COST" "MEM_VRD_PVDDQ_KLM"
					( Origin gFrontEnd )
				)
				( attribute "CDS_LIB" "mstr_discrete"
					( Origin gPackager )
				)
				( attribute "CDS_LOCATION" "C8P2"
					( Origin gPackager )
				)
				( attribute "CDS_SEC" "1"
					( Origin gPackager )
				)
				( attribute "LOCATION" "C8P2"
					( Origin gFrontEnd )
				)
				( attribute "MATERIAL" "X6S"
					( Origin gFrontEnd )
				)
				( attribute "PACK_TYPE" "0805LF"
					( Origin gFrontEnd )
				)
				( attribute "PART_NUMBER" "C95333-002"
					( Origin gFrontEnd )
				)
				( attribute "PHYS_PAGE" "228"
					( Origin gFrontEnd )
				)
				( attribute "ROOM" "VDDQ_KLM_CPU1"
					( Origin gFrontEnd )
				)
				( attribute "ROT" "0"
					( Origin gFrontEnd )
				)
				( attribute "SEC" "1"
					( Origin gFrontEnd )
				)
				( attribute "SEC_TYPE" "0805LF"
					( Origin gFrontEnd )
				)
				( attribute "TOLERANCE" "20%"
					( Origin gFrontEnd )
				)
				( attribute "VALUE" "22UF"
					( Origin gFrontEnd )
				)
				( attribute "VER" "1"
					( Origin gFrontEnd )
				)
				( attribute "VOLTAGE" "4V"
					( Units "uVoltage" "V" 1.000000)
					( Origin gFrontEnd )
				)
				( attribute "XY" "(-2300,2900)"
					( Origin gFrontEnd )
				)
				( attribute "CHIPS_PART_NAME" "CAP"
					( Origin gPackager )
				)
				( attribute "CDS_PART_NAME" "CAP_0805LF-22UF,4V,20%,X6S,C95A"
					( Origin gPackager )
				)
				( objectStatus "C8P2" )
				( pin "a"
					( attribute "PN" "1"
						( Origin gPackager )
					)
					( objectStatus "C8P2.1" )
				)
				( pin "b"
					( attribute "PN" "2"
						( Origin gPackager )
					)
					( objectStatus "C8P2.2" )
				)
			)
			( gate "@baseboard_fab2_lib.baseboard_fab2(sch_1):page228_i185"
				( attribute "BOM_COST" "MEM_VRD_PVDDQ_KLM"
					( Origin gFrontEnd )
				)
				( attribute "CDS_LIB" "mstr_discrete"
					( Origin gPackager )
				)
				( attribute "CDS_LOCATION" "C8P1"
					( Origin gPackager )
				)
				( attribute "CDS_SEC" "1"
					( Origin gPackager )
				)
				( attribute "LOCATION" "C8P1"
					( Origin gFrontEnd )
				)
				( attribute "MATERIAL" "X6S"
					( Origin gFrontEnd )
				)
				( attribute "PACK_TYPE" "0805LF"
					( Origin gFrontEnd )
				)
				( attribute "PART_NUMBER" "C95333-002"
					( Origin gFrontEnd )
				)
				( attribute "PHYS_PAGE" "228"
					( Origin gFrontEnd )
				)
				( attribute "ROOM" "VDDQ_KLM_CPU1"
					( Origin gFrontEnd )
				)
				( attribute "ROT" "0"
					( Origin gFrontEnd )
				)
				( attribute "SEC" "1"
					( Origin gFrontEnd )
				)
				( attribute "SEC_TYPE" "0805LF"
					( Origin gFrontEnd )
				)
				( attribute "TOLERANCE" "20%"
					( Origin gFrontEnd )
				)
				( attribute "VALUE" "22UF"
					( Origin gFrontEnd )
				)
				( attribute "VER" "1"
					( Origin gFrontEnd )
				)
				( attribute "VOLTAGE" "4V"
					( Units "uVoltage" "V" 1.000000)
					( Origin gFrontEnd )
				)
				( attribute "XY" "(-1900,2900)"
					( Origin gFrontEnd )
				)
				( attribute "CHIPS_PART_NAME" "CAP"
					( Origin gPackager )
				)
				( attribute "CDS_PART_NAME" "CAP_0805LF-22UF,4V,20%,X6S,C95A"
					( Origin gPackager )
				)
				( objectStatus "C8P1" )
				( pin "a"
					( attribute "PN" "1"
						( Origin gPackager )
					)
					( objectStatus "C8P1.1" )
				)
				( pin "b"
					( attribute "PN" "2"
						( Origin gPackager )
					)
					( objectStatus "C8P1.2" )
				)
			)
			( gate "@baseboard_fab2_lib.baseboard_fab2(sch_1):page228_i186"
				( attribute "BOM_COST" "MEM_VRD_PVDDQ_KLM"
					( Origin gFrontEnd )
				)
				( attribute "CDS_LIB" "mstr_discrete"
					( Origin gPackager )
				)
				( attribute "CDS_LOCATION" "C2D7"
					( Origin gPackager )
				)
				( attribute "CDS_SEC" "1"
					( Origin gPackager )
				)
				( attribute "LOCATION" "C2D7"
					( Origin gFrontEnd )
				)
				( attribute "MATERIAL" "X6S"
					( Origin gFrontEnd )
				)
				( attribute "PACK_TYPE" "0603LF"
					( Origin gFrontEnd )
				)
				( attribute "PART_NUMBER" "E15431-001"
					( Origin gFrontEnd )
				)
				( attribute "PHYS_PAGE" "228"
					( Origin gFrontEnd )
				)
				( attribute "ROOM" "VDDQ_KLM_CPU1"
					( Origin gFrontEnd )
				)
				( attribute "ROT" "0"
					( Origin gFrontEnd )
				)
				( attribute "SEC" "1"
					( Origin gFrontEnd )
				)
				( attribute "SEC_TYPE" "0603LF"
					( Origin gFrontEnd )
				)
				( attribute "TOLERANCE" "20%"
					( Origin gFrontEnd )
				)
				( attribute "VALUE" "10UF"
					( Origin gFrontEnd )
				)
				( attribute "VER" "1"
					( Origin gFrontEnd )
				)
				( attribute "VOLTAGE" "4V"
					( Units "uVoltage" "V" 1.000000)
					( Origin gFrontEnd )
				)
				( attribute "XY" "(-1550,2900)"
					( Origin gFrontEnd )
				)
				( attribute "CHIPS_PART_NAME" "CAP"
					( Origin gPackager )
				)
				( attribute "CDS_PART_NAME" "CAP_0603LF-10UF,4V,20%,X6S,E15A"
					( Origin gPackager )
				)
				( objectStatus "C2D7" )
				( pin "a"
					( attribute "PN" "1"
						( Origin gPackager )
					)
					( objectStatus "C2D7.1" )
				)
				( pin "b"
					( attribute "PN" "2"
						( Origin gPackager )
					)
					( objectStatus "C2D7.2" )
				)
			)
			( gate "@baseboard_fab2_lib.baseboard_fab2(sch_1):page228_i187"
				( attribute "BOM_COST" "MEM_VRD_PVDDQ_KLM"
					( Origin gFrontEnd )
				)
				( attribute "CDS_LIB" "mstr_discrete"
					( Origin gPackager )
				)
				( attribute "CDS_LOCATION" "C2D4"
					( Origin gPackager )
				)
				( attribute "CDS_SEC" "1"
					( Origin gPackager )
				)
				( attribute "LOCATION" "C2D4"
					( Origin gFrontEnd )
				)
				( attribute "MATERIAL" "X6S"
					( Origin gFrontEnd )
				)
				( attribute "PACK_TYPE" "0603LF"
					( Origin gFrontEnd )
				)
				( attribute "PART_NUMBER" "E15431-001"
					( Origin gFrontEnd )
				)
				( attribute "PHYS_PAGE" "228"
					( Origin gFrontEnd )
				)
				( attribute "ROOM" "VDDQ_KLM_CPU1"
					( Origin gFrontEnd )
				)
				( attribute "ROT" "0"
					( Origin gFrontEnd )
				)
				( attribute "SEC" "1"
					( Origin gFrontEnd )
				)
				( attribute "SEC_TYPE" "0603LF"
					( Origin gFrontEnd )
				)
				( attribute "TOLERANCE" "20%"
					( Origin gFrontEnd )
				)
				( attribute "VALUE" "10UF"
					( Origin gFrontEnd )
				)
				( attribute "VER" "1"
					( Origin gFrontEnd )
				)
				( attribute "VOLTAGE" "4V"
					( Units "uVoltage" "V" 1.000000)
					( Origin gFrontEnd )
				)
				( attribute "XY" "(-1200,2900)"
					( Origin gFrontEnd )
				)
				( attribute "CHIPS_PART_NAME" "CAP"
					( Origin gPackager )
				)
				( attribute "CDS_PART_NAME" "CAP_0603LF-10UF,4V,20%,X6S,E15A"
					( Origin gPackager )
				)
				( objectStatus "C2D4" )
				( pin "a"
					( attribute "PN" "1"
						( Origin gPackager )
					)
					( objectStatus "C2D4.1" )
				)
				( pin "b"
					( attribute "PN" "2"
						( Origin gPackager )
					)
					( objectStatus "C2D4.2" )
				)
			)
			( gate "@baseboard_fab2_lib.baseboard_fab2(sch_1):page228_i188"
				( attribute "BOM_COST" "MEM_VRD_PVDDQ_KLM"
					( Origin gFrontEnd )
				)
				( attribute "CDS_LIB" "mstr_discrete"
					( Origin gPackager )
				)
				( attribute "CDS_LOCATION" "C2D5"
					( Origin gPackager )
				)
				( attribute "CDS_SEC" "1"
					( Origin gPackager )
				)
				( attribute "LOCATION" "C2D5"
					( Origin gFrontEnd )
				)
				( attribute "MATERIAL" "X6S"
					( Origin gFrontEnd )
				)
				( attribute "PACK_TYPE" "0603LF"
					( Origin gFrontEnd )
				)
				( attribute "PART_NUMBER" "E15431-001"
					( Origin gFrontEnd )
				)
				( attribute "PHYS_PAGE" "228"
					( Origin gFrontEnd )
				)
				( attribute "ROOM" "VDDQ_KLM_CPU1"
					( Origin gFrontEnd )
				)
				( attribute "ROT" "0"
					( Origin gFrontEnd )
				)
				( attribute "SEC" "1"
					( Origin gFrontEnd )
				)
				( attribute "SEC_TYPE" "0603LF"
					( Origin gFrontEnd )
				)
				( attribute "TOLERANCE" "20%"
					( Origin gFrontEnd )
				)
				( attribute "VALUE" "10UF"
					( Origin gFrontEnd )
				)
				( attribute "VER" "1"
					( Origin gFrontEnd )
				)
				( attribute "VOLTAGE" "4V"
					( Units "uVoltage" "V" 1.000000)
					( Origin gFrontEnd )
				)
				( attribute "XY" "(-850,2900)"
					( Origin gFrontEnd )
				)
				( attribute "CHIPS_PART_NAME" "CAP"
					( Origin gPackager )
				)
				( attribute "CDS_PART_NAME" "CAP_0603LF-10UF,4V,20%,X6S,E15A"
					( Origin gPackager )
				)
				( objectStatus "C2D5" )
				( pin "a"
					( attribute "PN" "1"
						( Origin gPackager )
					)
					( objectStatus "C2D5.1" )
				)
				( pin "b"
					( attribute "PN" "2"
						( Origin gPackager )
					)
					( objectStatus "C2D5.2" )
				)
			)
			( gate "@baseboard_fab2_lib.baseboard_fab2(sch_1):page228_i190"
				( attribute "BOM_COST" "MEM_VRD_PVDDQ_KLM"
					( Origin gFrontEnd )
				)
				( attribute "CDS_LIB" "mstr_discrete"
					( Origin gPackager )
				)
				( attribute "CDS_LOCATION" "C2D6"
					( Origin gPackager )
				)
				( attribute "CDS_SEC" "1"
					( Origin gPackager )
				)
				( attribute "LOCATION" "C2D6"
					( Origin gFrontEnd )
				)
				( attribute "MATERIAL" "X6S"
					( Origin gFrontEnd )
				)
				( attribute "PACK_TYPE" "0603LF"
					( Origin gFrontEnd )
				)
				( attribute "PART_NUMBER" "E15431-001"
					( Origin gFrontEnd )
				)
				( attribute "PHYS_PAGE" "228"
					( Origin gFrontEnd )
				)
				( attribute "ROOM" "VDDQ_KLM_CPU1"
					( Origin gFrontEnd )
				)
				( attribute "ROT" "0"
					( Origin gFrontEnd )
				)
				( attribute "SEC" "1"
					( Origin gFrontEnd )
				)
				( attribute "SEC_TYPE" "0603LF"
					( Origin gFrontEnd )
				)
				( attribute "TOLERANCE" "20%"
					( Origin gFrontEnd )
				)
				( attribute "VALUE" "10UF"
					( Origin gFrontEnd )
				)
				( attribute "VER" "1"
					( Origin gFrontEnd )
				)
				( attribute "VOLTAGE" "4V"
					( Units "uVoltage" "V" 1.000000)
					( Origin gFrontEnd )
				)
				( attribute "XY" "(-500,2900)"
					( Origin gFrontEnd )
				)
				( attribute "CHIPS_PART_NAME" "CAP"
					( Origin gPackager )
				)
				( attribute "CDS_PART_NAME" "CAP_0603LF-10UF,4V,20%,X6S,E15A"
					( Origin gPackager )
				)
				( objectStatus "C2D6" )
				( pin "a"
					( attribute "PN" "1"
						( Origin gPackager )
					)
					( objectStatus "C2D6.1" )
				)
				( pin "b"
					( attribute "PN" "2"
						( Origin gPackager )
					)
					( objectStatus "C2D6.2" )
				)
			)
			( gate "@baseboard_fab2_lib.baseboard_fab2(sch_1):page228_i198"
				( attribute "CDS_LIB" "dev_discrete"
					( Origin gPackager )
				)
				( attribute "CDS_LOCATION" "C8M8"
					( Origin gPackager )
				)
				( attribute "CDS_SEC" "1"
					( Origin gPackager )
				)
				( attribute "LOCATION" "C8M8"
					( Origin gFrontEnd )
				)
				( attribute "MATERIAL" "X5R"
					( Origin gFrontEnd )
				)
				( attribute "PACK_TYPE" "0603V"
					( Origin gFrontEnd )
				)
				( attribute "PART_NUMBER" "602433-106"
					( Origin gFrontEnd )
				)
				( attribute "PHYS_PAGE" "228"
					( Origin gFrontEnd )
				)
				( attribute "ROT" "0"
					( Origin gFrontEnd )
				)
				( attribute "SEC" "1"
					( Origin gFrontEnd )
				)
				( attribute "SEC_TYPE" "0603V"
					( Origin gFrontEnd )
				)
				( attribute "TOLERANCE" "20%"
					( Origin gFrontEnd )
				)
				( attribute "VALUE" "47UF"
					( Origin gFrontEnd )
				)
				( attribute "VER" "1"
					( Origin gFrontEnd )
				)
				( attribute "VOLTAGE" "4V"
					( Units "uVoltage" "V" 1.000000)
					( Origin gFrontEnd )
				)
				( attribute "XY" "(2550,725)"
					( Origin gFrontEnd )
				)
				( attribute "CHIPS_PART_NAME" "CAP_A"
					( Origin gPackager )
				)
				( attribute "CDS_PART_NAME" "CAP_A_0603V-47UF,4V,20%,X5R,60A"
					( Origin gPackager )
				)
				( objectStatus "C8M8" )
				( pin "a"
					( attribute "PN" "1"
						( Origin gPackager )
					)
					( objectStatus "C8M8.1" )
				)
				( pin "b"
					( attribute "PN" "2"
						( Origin gPackager )
					)
					( objectStatus "C8M8.2" )
				)
			)
			( gate "@baseboard_fab2_lib.baseboard_fab2(sch_1):page228_i199"
				( attribute "CDS_LIB" "dev_discrete"
					( Origin gPackager )
				)
				( attribute "CDS_LOCATION" "C2A5"
					( Origin gPackager )
				)
				( attribute "CDS_SEC" "1"
					( Origin gPackager )
				)
				( attribute "LOCATION" "C2A5"
					( Origin gFrontEnd )
				)
				( attribute "MATERIAL" "X5R"
					( Origin gFrontEnd )
				)
				( attribute "PACK_TYPE" "0603V"
					( Origin gFrontEnd )
				)
				( attribute "PART_NUMBER" "602433-106"
					( Origin gFrontEnd )
				)
				( attribute "PHYS_PAGE" "228"
					( Origin gFrontEnd )
				)
				( attribute "ROT" "0"
					( Origin gFrontEnd )
				)
				( attribute "SEC" "1"
					( Origin gFrontEnd )
				)
				( attribute "SEC_TYPE" "0603V"
					( Origin gFrontEnd )
				)
				( attribute "TOLERANCE" "20%"
					( Origin gFrontEnd )
				)
				( attribute "VALUE" "47UF"
					( Origin gFrontEnd )
				)
				( attribute "VER" "1"
					( Origin gFrontEnd )
				)
				( attribute "VOLTAGE" "4V"
					( Units "uVoltage" "V" 1.000000)
					( Origin gFrontEnd )
				)
				( attribute "XY" "(2900,725)"
					( Origin gFrontEnd )
				)
				( attribute "CHIPS_PART_NAME" "CAP_A"
					( Origin gPackager )
				)
				( attribute "CDS_PART_NAME" "CAP_A_0603V-47UF,4V,20%,X5R,60A"
					( Origin gPackager )
				)
				( objectStatus "C2A5" )
				( pin "a"
					( attribute "PN" "1"
						( Origin gPackager )
					)
					( objectStatus "C2A5.1" )
				)
				( pin "b"
					( attribute "PN" "2"
						( Origin gPackager )
					)
					( objectStatus "C2A5.2" )
				)
			)
			( gate "@baseboard_fab2_lib.baseboard_fab2(sch_1):page228_i200"
				( attribute "CDS_LIB" "dev_discrete"
					( Origin gPackager )
				)
				( attribute "CDS_LOCATION" "C2B1"
					( Origin gPackager )
				)
				( attribute "CDS_SEC" "1"
					( Origin gPackager )
				)
				( attribute "LOCATION" "C2B1"
					( Origin gFrontEnd )
				)
				( attribute "MATERIAL" "X5R"
					( Origin gFrontEnd )
				)
				( attribute "PACK_TYPE" "0603V"
					( Origin gFrontEnd )
				)
				( attribute "PART_NUMBER" "602433-106"
					( Origin gFrontEnd )
				)
				( attribute "PHYS_PAGE" "228"
					( Origin gFrontEnd )
				)
				( attribute "ROT" "0"
					( Origin gFrontEnd )
				)
				( attribute "SEC" "1"
					( Origin gFrontEnd )
				)
				( attribute "SEC_TYPE" "0603V"
					( Origin gFrontEnd )
				)
				( attribute "TOLERANCE" "20%"
					( Origin gFrontEnd )
				)
				( attribute "VALUE" "47UF"
					( Origin gFrontEnd )
				)
				( attribute "VER" "1"
					( Origin gFrontEnd )
				)
				( attribute "VOLTAGE" "4V"
					( Units "uVoltage" "V" 1.000000)
					( Origin gFrontEnd )
				)
				( attribute "XY" "(3300,725)"
					( Origin gFrontEnd )
				)
				( attribute "CHIPS_PART_NAME" "CAP_A"
					( Origin gPackager )
				)
				( attribute "CDS_PART_NAME" "CAP_A_0603V-47UF,4V,20%,X5R,60A"
					( Origin gPackager )
				)
				( objectStatus "C2B1" )
				( pin "a"
					( attribute "PN" "1"
						( Origin gPackager )
					)
					( objectStatus "C2B1.1" )
				)
				( pin "b"
					( attribute "PN" "2"
						( Origin gPackager )
					)
					( objectStatus "C2B1.2" )
				)
			)
			( gate "@baseboard_fab2_lib.baseboard_fab2(sch_1):page228_i201"
				( attribute "CDS_LIB" "dev_discrete"
					( Origin gPackager )
				)
				( attribute "CDS_LOCATION" "C8L12"
					( Origin gPackager )
				)
				( attribute "CDS_SEC" "1"
					( Origin gPackager )
				)
				( attribute "LOCATION" "C8L12"
					( Origin gFrontEnd )
				)
				( attribute "MATERIAL" "X5R"
					( Origin gFrontEnd )
				)
				( attribute "PACK_TYPE" "0603V"
					( Origin gFrontEnd )
				)
				( attribute "PART_NUMBER" "602433-106"
					( Origin gFrontEnd )
				)
				( attribute "PHYS_PAGE" "228"
					( Origin gFrontEnd )
				)
				( attribute "ROT" "0"
					( Origin gFrontEnd )
				)
				( attribute "SEC" "1"
					( Origin gFrontEnd )
				)
				( attribute "SEC_TYPE" "0603V"
					( Origin gFrontEnd )
				)
				( attribute "TOLERANCE" "20%"
					( Origin gFrontEnd )
				)
				( attribute "VALUE" "47UF"
					( Origin gFrontEnd )
				)
				( attribute "VER" "1"
					( Origin gFrontEnd )
				)
				( attribute "VOLTAGE" "4V"
					( Units "uVoltage" "V" 1.000000)
					( Origin gFrontEnd )
				)
				( attribute "XY" "(2525,1425)"
					( Origin gFrontEnd )
				)
				( attribute "CHIPS_PART_NAME" "CAP_A"
					( Origin gPackager )
				)
				( attribute "CDS_PART_NAME" "CAP_A_0603V-47UF,4V,20%,X5R,60A"
					( Origin gPackager )
				)
				( objectStatus "C8L12" )
				( pin "a"
					( attribute "PN" "1"
						( Origin gPackager )
					)
					( objectStatus "C8L12.1" )
				)
				( pin "b"
					( attribute "PN" "2"
						( Origin gPackager )
					)
					( objectStatus "C8L12.2" )
				)
			)
			( gate "@baseboard_fab2_lib.baseboard_fab2(sch_1):page228_i202"
				( attribute "CDS_LIB" "dev_discrete"
					( Origin gPackager )
				)
				( attribute "CDS_LOCATION" "C7M5"
					( Origin gPackager )
				)
				( attribute "CDS_SEC" "1"
					( Origin gPackager )
				)
				( attribute "LOCATION" "C7M5"
					( Origin gFrontEnd )
				)
				( attribute "MATERIAL" "X5R"
					( Origin gFrontEnd )
				)
				( attribute "PACK_TYPE" "0603V"
					( Origin gFrontEnd )
				)
				( attribute "PART_NUMBER" "602433-106"
					( Origin gFrontEnd )
				)
				( attribute "PHYS_PAGE" "228"
					( Origin gFrontEnd )
				)
				( attribute "ROT" "0"
					( Origin gFrontEnd )
				)
				( attribute "SEC" "1"
					( Origin gFrontEnd )
				)
				( attribute "SEC_TYPE" "0603V"
					( Origin gFrontEnd )
				)
				( attribute "TOLERANCE" "20%"
					( Origin gFrontEnd )
				)
				( attribute "VALUE" "47UF"
					( Origin gFrontEnd )
				)
				( attribute "VER" "1"
					( Origin gFrontEnd )
				)
				( attribute "VOLTAGE" "4V"
					( Units "uVoltage" "V" 1.000000)
					( Origin gFrontEnd )
				)
				( attribute "XY" "(2875,1425)"
					( Origin gFrontEnd )
				)
				( attribute "CHIPS_PART_NAME" "CAP_A"
					( Origin gPackager )
				)
				( attribute "CDS_PART_NAME" "CAP_A_0603V-47UF,4V,20%,X5R,60A"
					( Origin gPackager )
				)
				( objectStatus "C7M5" )
				( pin "a"
					( attribute "PN" "1"
						( Origin gPackager )
					)
					( objectStatus "C7M5.1" )
				)
				( pin "b"
					( attribute "PN" "2"
						( Origin gPackager )
					)
					( objectStatus "C7M5.2" )
				)
			)
			( gate "@baseboard_fab2_lib.baseboard_fab2(sch_1):page228_i203"
				( attribute "CDS_LIB" "dev_discrete"
					( Origin gPackager )
				)
				( attribute "CDS_LOCATION" "C8M10"
					( Origin gPackager )
				)
				( attribute "CDS_SEC" "1"
					( Origin gPackager )
				)
				( attribute "LOCATION" "C8M10"
					( Origin gFrontEnd )
				)
				( attribute "MATERIAL" "X5R"
					( Origin gFrontEnd )
				)
				( attribute "PACK_TYPE" "0603V"
					( Origin gFrontEnd )
				)
				( attribute "PART_NUMBER" "602433-106"
					( Origin gFrontEnd )
				)
				( attribute "PHYS_PAGE" "228"
					( Origin gFrontEnd )
				)
				( attribute "ROT" "0"
					( Origin gFrontEnd )
				)
				( attribute "SEC" "1"
					( Origin gFrontEnd )
				)
				( attribute "SEC_TYPE" "0603V"
					( Origin gFrontEnd )
				)
				( attribute "TOLERANCE" "20%"
					( Origin gFrontEnd )
				)
				( attribute "VALUE" "47UF"
					( Origin gFrontEnd )
				)
				( attribute "VER" "1"
					( Origin gFrontEnd )
				)
				( attribute "VOLTAGE" "4V"
					( Units "uVoltage" "V" 1.000000)
					( Origin gFrontEnd )
				)
				( attribute "XY" "(3275,1425)"
					( Origin gFrontEnd )
				)
				( attribute "CHIPS_PART_NAME" "CAP_A"
					( Origin gPackager )
				)
				( attribute "CDS_PART_NAME" "CAP_A_0603V-47UF,4V,20%,X5R,60A"
					( Origin gPackager )
				)
				( objectStatus "C8M10" )
				( pin "a"
					( attribute "PN" "1"
						( Origin gPackager )
					)
					( objectStatus "C8M10.1" )
				)
				( pin "b"
					( attribute "PN" "2"
						( Origin gPackager )
					)
					( objectStatus "C8M10.2" )
				)
			)
			( gate "@baseboard_fab2_lib.baseboard_fab2(sch_1):page228_i204"
				( attribute "CDS_LIB" "dev_discrete"
					( Origin gPackager )
				)
				( attribute "CDS_LOCATION" "C2B2"
					( Origin gPackager )
				)
				( attribute "CDS_SEC" "1"
					( Origin gPackager )
				)
				( attribute "LOCATION" "C2B2"
					( Origin gFrontEnd )
				)
				( attribute "MATERIAL" "X5R"
					( Origin gFrontEnd )
				)
				( attribute "PACK_TYPE" "0603V"
					( Origin gFrontEnd )
				)
				( attribute "PART_NUMBER" "602433-106"
					( Origin gFrontEnd )
				)
				( attribute "PHYS_PAGE" "228"
					( Origin gFrontEnd )
				)
				( attribute "ROT" "0"
					( Origin gFrontEnd )
				)
				( attribute "SEC" "1"
					( Origin gFrontEnd )
				)
				( attribute "SEC_TYPE" "0603V"
					( Origin gFrontEnd )
				)
				( attribute "TOLERANCE" "20%"
					( Origin gFrontEnd )
				)
				( attribute "VALUE" "47UF"
					( Origin gFrontEnd )
				)
				( attribute "VER" "1"
					( Origin gFrontEnd )
				)
				( attribute "VOLTAGE" "4V"
					( Units "uVoltage" "V" 1.000000)
					( Origin gFrontEnd )
				)
				( attribute "XY" "(3625,1425)"
					( Origin gFrontEnd )
				)
				( attribute "CHIPS_PART_NAME" "CAP_A"
					( Origin gPackager )
				)
				( attribute "CDS_PART_NAME" "CAP_A_0603V-47UF,4V,20%,X5R,60A"
					( Origin gPackager )
				)
				( objectStatus "C2B2" )
				( pin "a"
					( attribute "PN" "1"
						( Origin gPackager )
					)
					( objectStatus "C2B2.1" )
				)
				( pin "b"
					( attribute "PN" "2"
						( Origin gPackager )
					)
					( objectStatus "C2B2.2" )
				)
			)
			( gate "@baseboard_fab2_lib.baseboard_fab2(sch_1):page228_i205"
				( attribute "CDS_LIB" "dev_discrete"
					( Origin gPackager )
				)
				( attribute "CDS_LOCATION" "C8M9"
					( Origin gPackager )
				)
				( attribute "CDS_SEC" "1"
					( Origin gPackager )
				)
				( attribute "LOCATION" "C8M9"
					( Origin gFrontEnd )
				)
				( attribute "MATERIAL" "X5R"
					( Origin gFrontEnd )
				)
				( attribute "PACK_TYPE" "0603V"
					( Origin gFrontEnd )
				)
				( attribute "PART_NUMBER" "602433-106"
					( Origin gFrontEnd )
				)
				( attribute "PHYS_PAGE" "228"
					( Origin gFrontEnd )
				)
				( attribute "ROT" "0"
					( Origin gFrontEnd )
				)
				( attribute "SEC" "1"
					( Origin gFrontEnd )
				)
				( attribute "SEC_TYPE" "0603V"
					( Origin gFrontEnd )
				)
				( attribute "TOLERANCE" "20%"
					( Origin gFrontEnd )
				)
				( attribute "VALUE" "47UF"
					( Origin gFrontEnd )
				)
				( attribute "VER" "1"
					( Origin gFrontEnd )
				)
				( attribute "VOLTAGE" "4V"
					( Units "uVoltage" "V" 1.000000)
					( Origin gFrontEnd )
				)
				( attribute "XY" "(3975,1425)"
					( Origin gFrontEnd )
				)
				( attribute "CHIPS_PART_NAME" "CAP_A"
					( Origin gPackager )
				)
				( attribute "CDS_PART_NAME" "CAP_A_0603V-47UF,4V,20%,X5R,60A"
					( Origin gPackager )
				)
				( objectStatus "C8M9" )
				( pin "a"
					( attribute "PN" "1"
						( Origin gPackager )
					)
					( objectStatus "C8M9.1" )
				)
				( pin "b"
					( attribute "PN" "2"
						( Origin gPackager )
					)
					( objectStatus "C8M9.2" )
				)
			)
			( gate "@baseboard_fab2_lib.baseboard_fab2(sch_1):page228_i206"
				( attribute "CDS_LIB" "dev_discrete"
					( Origin gPackager )
				)
				( attribute "CDS_LOCATION" "C8M2"
					( Origin gPackager )
				)
				( attribute "CDS_SEC" "1"
					( Origin gPackager )
				)
				( attribute "LOCATION" "C8M2"
					( Origin gFrontEnd )
				)
				( attribute "MATERIAL" "X5R"
					( Origin gFrontEnd )
				)
				( attribute "PACK_TYPE" "0603V"
					( Origin gFrontEnd )
				)
				( attribute "PART_NUMBER" "602433-106"
					( Origin gFrontEnd )
				)
				( attribute "PHYS_PAGE" "228"
					( Origin gFrontEnd )
				)
				( attribute "ROT" "0"
					( Origin gFrontEnd )
				)
				( attribute "SEC" "1"
					( Origin gFrontEnd )
				)
				( attribute "SEC_TYPE" "0603V"
					( Origin gFrontEnd )
				)
				( attribute "TOLERANCE" "20%"
					( Origin gFrontEnd )
				)
				( attribute "VALUE" "47UF"
					( Origin gFrontEnd )
				)
				( attribute "VER" "1"
					( Origin gFrontEnd )
				)
				( attribute "VOLTAGE" "4V"
					( Units "uVoltage" "V" 1.000000)
					( Origin gFrontEnd )
				)
				( attribute "XY" "(4375,1425)"
					( Origin gFrontEnd )
				)
				( attribute "CHIPS_PART_NAME" "CAP_A"
					( Origin gPackager )
				)
				( attribute "CDS_PART_NAME" "CAP_A_0603V-47UF,4V,20%,X5R,60A"
					( Origin gPackager )
				)
				( objectStatus "C8M2" )
				( pin "a"
					( attribute "PN" "1"
						( Origin gPackager )
					)
					( objectStatus "C8M2.1" )
				)
				( pin "b"
					( attribute "PN" "2"
						( Origin gPackager )
					)
					( objectStatus "C8M2.2" )
				)
			)
			( gate "@baseboard_fab2_lib.baseboard_fab2(sch_1):page228_i209"
				( attribute "CDS_LIB" "dev_discrete"
					( Origin gPackager )
				)
				( attribute "CDS_LOCATION" "C2A2"
					( Origin gPackager )
				)
				( attribute "CDS_SEC" "1"
					( Origin gPackager )
				)
				( attribute "LOCATION" "C2A2"
					( Origin gFrontEnd )
				)
				( attribute "MATERIAL" "X6S"
					( Origin gFrontEnd )
				)
				( attribute "PACK_TYPE" "0603V"
					( Origin gFrontEnd )
				)
				( attribute "PART_NUMBER" "E15431-004"
					( Origin gFrontEnd )
				)
				( attribute "PHYS_PAGE" "228"
					( Origin gFrontEnd )
				)
				( attribute "ROOM" "PVDDQ_KLM"
					( Origin gFrontEnd )
				)
				( attribute "ROT" "0"
					( Origin gFrontEnd )
				)
				( attribute "SEC" "1"
					( Origin gFrontEnd )
				)
				( attribute "SEC_TYPE" "0603V"
					( Origin gFrontEnd )
				)
				( attribute "TOLERANCE" "20%"
					( Origin gFrontEnd )
				)
				( attribute "VALUE" "22.0UF"
					( Origin gFrontEnd )
				)
				( attribute "VER" "1"
					( Origin gFrontEnd )
				)
				( attribute "VOLTAGE" "4V"
					( Units "uVoltage" "V" 1.000000)
					( Origin gFrontEnd )
				)
				( attribute "XY" "(2125,-75)"
					( Origin gFrontEnd )
				)
				( attribute "CHIPS_PART_NAME" "CAP_A"
					( Origin gPackager )
				)
				( attribute "CDS_PART_NAME" "CAP_A_0603V-22.0UF,4V,20%,X6S,A"
					( Origin gPackager )
				)
				( objectStatus "C2A2" )
				( pin "a"
					( attribute "PN" "1"
						( Origin gPackager )
					)
					( objectStatus "C2A2.1" )
				)
				( pin "b"
					( attribute "PN" "2"
						( Origin gPackager )
					)
					( objectStatus "C2A2.2" )
				)
			)
			( gate "@baseboard_fab2_lib.baseboard_fab2(sch_1):page228_i210"
				( attribute "CDS_LIB" "dev_discrete"
					( Origin gPackager )
				)
				( attribute "CDS_LOCATION" "C2A1"
					( Origin gPackager )
				)
				( attribute "CDS_SEC" "1"
					( Origin gPackager )
				)
				( attribute "LOCATION" "C2A1"
					( Origin gFrontEnd )
				)
				( attribute "MATERIAL" "X6S"
					( Origin gFrontEnd )
				)
				( attribute "PACK_TYPE" "0603V"
					( Origin gFrontEnd )
				)
				( attribute "PART_NUMBER" "E15431-004"
					( Origin gFrontEnd )
				)
				( attribute "PHYS_PAGE" "228"
					( Origin gFrontEnd )
				)
				( attribute "ROOM" "PVDDQ_KLM"
					( Origin gFrontEnd )
				)
				( attribute "ROT" "0"
					( Origin gFrontEnd )
				)
				( attribute "SEC" "1"
					( Origin gFrontEnd )
				)
				( attribute "SEC_TYPE" "0603V"
					( Origin gFrontEnd )
				)
				( attribute "TOLERANCE" "20%"
					( Origin gFrontEnd )
				)
				( attribute "VALUE" "22.0UF"
					( Origin gFrontEnd )
				)
				( attribute "VER" "1"
					( Origin gFrontEnd )
				)
				( attribute "VOLTAGE" "4V"
					( Units "uVoltage" "V" 1.000000)
					( Origin gFrontEnd )
				)
				( attribute "XY" "(1850,-75)"
					( Origin gFrontEnd )
				)
				( attribute "CHIPS_PART_NAME" "CAP_A"
					( Origin gPackager )
				)
				( attribute "CDS_PART_NAME" "CAP_A_0603V-22.0UF,4V,20%,X6S,A"
					( Origin gPackager )
				)
				( objectStatus "C2A1" )
				( pin "a"
					( attribute "PN" "1"
						( Origin gPackager )
					)
					( objectStatus "C2A1.1" )
				)
				( pin "b"
					( attribute "PN" "2"
						( Origin gPackager )
					)
					( objectStatus "C2A1.2" )
				)
			)
			( gate "@baseboard_fab2_lib.baseboard_fab2(sch_1):page228_i211"
				( attribute "CDS_LIB" "dev_discrete"
					( Origin gPackager )
				)
				( attribute "CDS_LOCATION" "C2A12"
					( Origin gPackager )
				)
				( attribute "CDS_SEC" "1"
					( Origin gPackager )
				)
				( attribute "LOCATION" "C2A12"
					( Origin gFrontEnd )
				)
				( attribute "MATERIAL" "X6S"
					( Origin gFrontEnd )
				)
				( attribute "PACK_TYPE" "0603V"
					( Origin gFrontEnd )
				)
				( attribute "PART_NUMBER" "E15431-004"
					( Origin gFrontEnd )
				)
				( attribute "PHYS_PAGE" "228"
					( Origin gFrontEnd )
				)
				( attribute "ROOM" "PVDDQ_KLM"
					( Origin gFrontEnd )
				)
				( attribute "ROT" "0"
					( Origin gFrontEnd )
				)
				( attribute "SEC" "1"
					( Origin gFrontEnd )
				)
				( attribute "SEC_TYPE" "0603V"
					( Origin gFrontEnd )
				)
				( attribute "TOLERANCE" "20%"
					( Origin gFrontEnd )
				)
				( attribute "VALUE" "22.0UF"
					( Origin gFrontEnd )
				)
				( attribute "VER" "1"
					( Origin gFrontEnd )
				)
				( attribute "VOLTAGE" "4V"
					( Units "uVoltage" "V" 1.000000)
					( Origin gFrontEnd )
				)
				( attribute "XY" "(1550,-75)"
					( Origin gFrontEnd )
				)
				( attribute "CHIPS_PART_NAME" "CAP_A"
					( Origin gPackager )
				)
				( attribute "CDS_PART_NAME" "CAP_A_0603V-22.0UF,4V,20%,X6S,A"
					( Origin gPackager )
				)
				( objectStatus "C2A12" )
				( pin "a"
					( attribute "PN" "1"
						( Origin gPackager )
					)
					( objectStatus "C2A12.1" )
				)
				( pin "b"
					( attribute "PN" "2"
						( Origin gPackager )
					)
					( objectStatus "C2A12.2" )
				)
			)
			( gate "@baseboard_fab2_lib.baseboard_fab2(sch_1):page228_i212"
				( attribute "CDS_LIB" "dev_discrete"
					( Origin gPackager )
				)
				( attribute "CDS_LOCATION" "C2A13"
					( Origin gPackager )
				)
				( attribute "CDS_SEC" "1"
					( Origin gPackager )
				)
				( attribute "LOCATION" "C2A13"
					( Origin gFrontEnd )
				)
				( attribute "MATERIAL" "X6S"
					( Origin gFrontEnd )
				)
				( attribute "PACK_TYPE" "0603V"
					( Origin gFrontEnd )
				)
				( attribute "PART_NUMBER" "E15431-004"
					( Origin gFrontEnd )
				)
				( attribute "PHYS_PAGE" "228"
					( Origin gFrontEnd )
				)
				( attribute "ROOM" "PVDDQ_KLM"
					( Origin gFrontEnd )
				)
				( attribute "ROT" "0"
					( Origin gFrontEnd )
				)
				( attribute "SEC" "1"
					( Origin gFrontEnd )
				)
				( attribute "SEC_TYPE" "0603V"
					( Origin gFrontEnd )
				)
				( attribute "TOLERANCE" "20%"
					( Origin gFrontEnd )
				)
				( attribute "VALUE" "22.0UF"
					( Origin gFrontEnd )
				)
				( attribute "VER" "1"
					( Origin gFrontEnd )
				)
				( attribute "VOLTAGE" "4V"
					( Units "uVoltage" "V" 1.000000)
					( Origin gFrontEnd )
				)
				( attribute "XY" "(1250,-75)"
					( Origin gFrontEnd )
				)
				( attribute "CHIPS_PART_NAME" "CAP_A"
					( Origin gPackager )
				)
				( attribute "CDS_PART_NAME" "CAP_A_0603V-22.0UF,4V,20%,X6S,A"
					( Origin gPackager )
				)
				( objectStatus "C2A13" )
				( pin "a"
					( attribute "PN" "1"
						( Origin gPackager )
					)
					( objectStatus "C2A13.1" )
				)
				( pin "b"
					( attribute "PN" "2"
						( Origin gPackager )
					)
					( objectStatus "C2A13.2" )
				)
			)
			( gate "@baseboard_fab2_lib.baseboard_fab2(sch_1):page228_i213"
				( attribute "CDS_LIB" "dev_discrete"
					( Origin gPackager )
				)
				( attribute "CDS_LOCATION" "C2A11"
					( Origin gPackager )
				)
				( attribute "CDS_SEC" "1"
					( Origin gPackager )
				)
				( attribute "LOCATION" "C2A11"
					( Origin gFrontEnd )
				)
				( attribute "MATERIAL" "X6S"
					( Origin gFrontEnd )
				)
				( attribute "PACK_TYPE" "0603V"
					( Origin gFrontEnd )
				)
				( attribute "PART_NUMBER" "E15431-004"
					( Origin gFrontEnd )
				)
				( attribute "PHYS_PAGE" "228"
					( Origin gFrontEnd )
				)
				( attribute "ROOM" "PVDDQ_KLM"
					( Origin gFrontEnd )
				)
				( attribute "ROT" "0"
					( Origin gFrontEnd )
				)
				( attribute "SEC" "1"
					( Origin gFrontEnd )
				)
				( attribute "SEC_TYPE" "0603V"
					( Origin gFrontEnd )
				)
				( attribute "TOLERANCE" "20%"
					( Origin gFrontEnd )
				)
				( attribute "VALUE" "22.0UF"
					( Origin gFrontEnd )
				)
				( attribute "VER" "1"
					( Origin gFrontEnd )
				)
				( attribute "VOLTAGE" "4V"
					( Units "uVoltage" "V" 1.000000)
					( Origin gFrontEnd )
				)
				( attribute "XY" "(975,-75)"
					( Origin gFrontEnd )
				)
				( attribute "CHIPS_PART_NAME" "CAP_A"
					( Origin gPackager )
				)
				( attribute "CDS_PART_NAME" "CAP_A_0603V-22.0UF,4V,20%,X6S,A"
					( Origin gPackager )
				)
				( objectStatus "C2A11" )
				( pin "a"
					( attribute "PN" "1"
						( Origin gPackager )
					)
					( objectStatus "C2A11.1" )
				)
				( pin "b"
					( attribute "PN" "2"
						( Origin gPackager )
					)
					( objectStatus "C2A11.2" )
				)
			)
			( gate "@baseboard_fab2_lib.baseboard_fab2(sch_1):page228_i214"
				( attribute "CDS_LIB" "dev_discrete"
					( Origin gPackager )
				)
				( attribute "CDS_LOCATION" "C2A10"
					( Origin gPackager )
				)
				( attribute "CDS_SEC" "1"
					( Origin gPackager )
				)
				( attribute "LOCATION" "C2A10"
					( Origin gFrontEnd )
				)
				( attribute "MATERIAL" "X6S"
					( Origin gFrontEnd )
				)
				( attribute "PACK_TYPE" "0603V"
					( Origin gFrontEnd )
				)
				( attribute "PART_NUMBER" "E15431-004"
					( Origin gFrontEnd )
				)
				( attribute "PHYS_PAGE" "228"
					( Origin gFrontEnd )
				)
				( attribute "ROOM" "PVDDQ_KLM"
					( Origin gFrontEnd )
				)
				( attribute "ROT" "0"
					( Origin gFrontEnd )
				)
				( attribute "SEC" "1"
					( Origin gFrontEnd )
				)
				( attribute "SEC_TYPE" "0603V"
					( Origin gFrontEnd )
				)
				( attribute "TOLERANCE" "20%"
					( Origin gFrontEnd )
				)
				( attribute "VALUE" "22.0UF"
					( Origin gFrontEnd )
				)
				( attribute "VER" "1"
					( Origin gFrontEnd )
				)
				( attribute "VOLTAGE" "4V"
					( Units "uVoltage" "V" 1.000000)
					( Origin gFrontEnd )
				)
				( attribute "XY" "(700,-75)"
					( Origin gFrontEnd )
				)
				( attribute "CHIPS_PART_NAME" "CAP_A"
					( Origin gPackager )
				)
				( attribute "CDS_PART_NAME" "CAP_A_0603V-22.0UF,4V,20%,X6S,A"
					( Origin gPackager )
				)
				( objectStatus "C2A10" )
				( pin "a"
					( attribute "PN" "1"
						( Origin gPackager )
					)
					( objectStatus "C2A10.1" )
				)
				( pin "b"
					( attribute "PN" "2"
						( Origin gPackager )
					)
					( objectStatus "C2A10.2" )
				)
			)
			( gate "@baseboard_fab2_lib.baseboard_fab2(sch_1):page228_i215"
				( attribute "CDS_LIB" "dev_discrete"
					( Origin gPackager )
				)
				( attribute "CDS_LOCATION" "C2A9"
					( Origin gPackager )
				)
				( attribute "CDS_SEC" "1"
					( Origin gPackager )
				)
				( attribute "LOCATION" "C2A9"
					( Origin gFrontEnd )
				)
				( attribute "MATERIAL" "X6S"
					( Origin gFrontEnd )
				)
				( attribute "PACK_TYPE" "0603V"
					( Origin gFrontEnd )
				)
				( attribute "PART_NUMBER" "E15431-004"
					( Origin gFrontEnd )
				)
				( attribute "PHYS_PAGE" "228"
					( Origin gFrontEnd )
				)
				( attribute "ROOM" "PVDDQ_KLM"
					( Origin gFrontEnd )
				)
				( attribute "ROT" "0"
					( Origin gFrontEnd )
				)
				( attribute "SEC" "1"
					( Origin gFrontEnd )
				)
				( attribute "SEC_TYPE" "0603V"
					( Origin gFrontEnd )
				)
				( attribute "TOLERANCE" "20%"
					( Origin gFrontEnd )
				)
				( attribute "VALUE" "22.0UF"
					( Origin gFrontEnd )
				)
				( attribute "VER" "1"
					( Origin gFrontEnd )
				)
				( attribute "VOLTAGE" "4V"
					( Units "uVoltage" "V" 1.000000)
					( Origin gFrontEnd )
				)
				( attribute "XY" "(400,-75)"
					( Origin gFrontEnd )
				)
				( attribute "CHIPS_PART_NAME" "CAP_A"
					( Origin gPackager )
				)
				( attribute "CDS_PART_NAME" "CAP_A_0603V-22.0UF,4V,20%,X6S,A"
					( Origin gPackager )
				)
				( objectStatus "C2A9" )
				( pin "a"
					( attribute "PN" "1"
						( Origin gPackager )
					)
					( objectStatus "C2A9.1" )
				)
				( pin "b"
					( attribute "PN" "2"
						( Origin gPackager )
					)
					( objectStatus "C2A9.2" )
				)
			)
			( gate "@baseboard_fab2_lib.baseboard_fab2(sch_1):page228_i216"
				( attribute "CDS_LIB" "dev_discrete"
					( Origin gPackager )
				)
				( attribute "CDS_LOCATION" "C3A2"
					( Origin gPackager )
				)
				( attribute "CDS_SEC" "1"
					( Origin gPackager )
				)
				( attribute "LOCATION" "C3A2"
					( Origin gFrontEnd )
				)
				( attribute "MATERIAL" "X6S"
					( Origin gFrontEnd )
				)
				( attribute "PACK_TYPE" "0603V"
					( Origin gFrontEnd )
				)
				( attribute "PART_NUMBER" "E15431-004"
					( Origin gFrontEnd )
				)
				( attribute "PHYS_PAGE" "228"
					( Origin gFrontEnd )
				)
				( attribute "ROOM" "PVDDQ_KLM"
					( Origin gFrontEnd )
				)
				( attribute "ROT" "0"
					( Origin gFrontEnd )
				)
				( attribute "SEC" "1"
					( Origin gFrontEnd )
				)
				( attribute "SEC_TYPE" "0603V"
					( Origin gFrontEnd )
				)
				( attribute "TOLERANCE" "20%"
					( Origin gFrontEnd )
				)
				( attribute "VALUE" "22.0UF"
					( Origin gFrontEnd )
				)
				( attribute "VER" "1"
					( Origin gFrontEnd )
				)
				( attribute "VOLTAGE" "4V"
					( Units "uVoltage" "V" 1.000000)
					( Origin gFrontEnd )
				)
				( attribute "XY" "(100,-75)"
					( Origin gFrontEnd )
				)
				( attribute "CHIPS_PART_NAME" "CAP_A"
					( Origin gPackager )
				)
				( attribute "CDS_PART_NAME" "CAP_A_0603V-22.0UF,4V,20%,X6S,A"
					( Origin gPackager )
				)
				( objectStatus "C3A2" )
				( pin "a"
					( attribute "PN" "1"
						( Origin gPackager )
					)
					( objectStatus "C3A2.1" )
				)
				( pin "b"
					( attribute "PN" "2"
						( Origin gPackager )
					)
					( objectStatus "C3A2.2" )
				)
			)
			( gate "@baseboard_fab2_lib.baseboard_fab2(sch_1):page228_i217"
				( attribute "CDS_LIB" "dev_discrete"
					( Origin gPackager )
				)
				( attribute "CDS_LOCATION" "C3A1"
					( Origin gPackager )
				)
				( attribute "CDS_SEC" "1"
					( Origin gPackager )
				)
				( attribute "LOCATION" "C3A1"
					( Origin gFrontEnd )
				)
				( attribute "MATERIAL" "X6S"
					( Origin gFrontEnd )
				)
				( attribute "PACK_TYPE" "0603V"
					( Origin gFrontEnd )
				)
				( attribute "PART_NUMBER" "E15431-004"
					( Origin gFrontEnd )
				)
				( attribute "PHYS_PAGE" "228"
					( Origin gFrontEnd )
				)
				( attribute "ROOM" "PVDDQ_KLM"
					( Origin gFrontEnd )
				)
				( attribute "ROT" "0"
					( Origin gFrontEnd )
				)
				( attribute "SEC" "1"
					( Origin gFrontEnd )
				)
				( attribute "SEC_TYPE" "0603V"
					( Origin gFrontEnd )
				)
				( attribute "TOLERANCE" "20%"
					( Origin gFrontEnd )
				)
				( attribute "VALUE" "22.0UF"
					( Origin gFrontEnd )
				)
				( attribute "VER" "1"
					( Origin gFrontEnd )
				)
				( attribute "VOLTAGE" "4V"
					( Units "uVoltage" "V" 1.000000)
					( Origin gFrontEnd )
				)
				( attribute "XY" "(-225,-75)"
					( Origin gFrontEnd )
				)
				( attribute "CHIPS_PART_NAME" "CAP_A"
					( Origin gPackager )
				)
				( attribute "CDS_PART_NAME" "CAP_A_0603V-22.0UF,4V,20%,X6S,A"
					( Origin gPackager )
				)
				( objectStatus "C3A1" )
				( pin "a"
					( attribute "PN" "1"
						( Origin gPackager )
					)
					( objectStatus "C3A1.1" )
				)
				( pin "b"
					( attribute "PN" "2"
						( Origin gPackager )
					)
					( objectStatus "C3A1.2" )
				)
			)
			( gate "@baseboard_fab2_lib.baseboard_fab2(sch_1):page228_i218"
				( attribute "CDS_LIB" "dev_discrete"
					( Origin gPackager )
				)
				( attribute "CDS_LOCATION" "C2A7"
					( Origin gPackager )
				)
				( attribute "CDS_SEC" "1"
					( Origin gPackager )
				)
				( attribute "LOCATION" "C2A7"
					( Origin gFrontEnd )
				)
				( attribute "MATERIAL" "X6S"
					( Origin gFrontEnd )
				)
				( attribute "PACK_TYPE" "0603V"
					( Origin gFrontEnd )
				)
				( attribute "PART_NUMBER" "E15431-004"
					( Origin gFrontEnd )
				)
				( attribute "PHYS_PAGE" "228"
					( Origin gFrontEnd )
				)
				( attribute "ROOM" "PVDDQ_KLM"
					( Origin gFrontEnd )
				)
				( attribute "ROT" "0"
					( Origin gFrontEnd )
				)
				( attribute "SEC" "1"
					( Origin gFrontEnd )
				)
				( attribute "SEC_TYPE" "0603V"
					( Origin gFrontEnd )
				)
				( attribute "TOLERANCE" "20%"
					( Origin gFrontEnd )
				)
				( attribute "VALUE" "22.0UF"
					( Origin gFrontEnd )
				)
				( attribute "VER" "1"
					( Origin gFrontEnd )
				)
				( attribute "VOLTAGE" "4V"
					( Units "uVoltage" "V" 1.000000)
					( Origin gFrontEnd )
				)
				( attribute "XY" "(-500,-75)"
					( Origin gFrontEnd )
				)
				( attribute "CHIPS_PART_NAME" "CAP_A"
					( Origin gPackager )
				)
				( attribute "CDS_PART_NAME" "CAP_A_0603V-22.0UF,4V,20%,X6S,A"
					( Origin gPackager )
				)
				( objectStatus "C2A7" )
				( pin "a"
					( attribute "PN" "1"
						( Origin gPackager )
					)
					( objectStatus "C2A7.1" )
				)
				( pin "b"
					( attribute "PN" "2"
						( Origin gPackager )
					)
					( objectStatus "C2A7.2" )
				)
			)
			( gate "@baseboard_fab2_lib.baseboard_fab2(sch_1):page228_i219"
				( attribute "CDS_LIB" "dev_discrete"
					( Origin gPackager )
				)
				( attribute "CDS_LOCATION" "C2A6"
					( Origin gPackager )
				)
				( attribute "CDS_SEC" "1"
					( Origin gPackager )
				)
				( attribute "LOCATION" "C2A6"
					( Origin gFrontEnd )
				)
				( attribute "MATERIAL" "X6S"
					( Origin gFrontEnd )
				)
				( attribute "PACK_TYPE" "0603V"
					( Origin gFrontEnd )
				)
				( attribute "PART_NUMBER" "E15431-004"
					( Origin gFrontEnd )
				)
				( attribute "PHYS_PAGE" "228"
					( Origin gFrontEnd )
				)
				( attribute "ROOM" "PVDDQ_KLM"
					( Origin gFrontEnd )
				)
				( attribute "ROT" "0"
					( Origin gFrontEnd )
				)
				( attribute "SEC" "1"
					( Origin gFrontEnd )
				)
				( attribute "SEC_TYPE" "0603V"
					( Origin gFrontEnd )
				)
				( attribute "TOLERANCE" "20%"
					( Origin gFrontEnd )
				)
				( attribute "VALUE" "22.0UF"
					( Origin gFrontEnd )
				)
				( attribute "VER" "1"
					( Origin gFrontEnd )
				)
				( attribute "VOLTAGE" "4V"
					( Units "uVoltage" "V" 1.000000)
					( Origin gFrontEnd )
				)
				( attribute "XY" "(-800,-75)"
					( Origin gFrontEnd )
				)
				( attribute "CHIPS_PART_NAME" "CAP_A"
					( Origin gPackager )
				)
				( attribute "CDS_PART_NAME" "CAP_A_0603V-22.0UF,4V,20%,X6S,A"
					( Origin gPackager )
				)
				( objectStatus "C2A6" )
				( pin "a"
					( attribute "PN" "1"
						( Origin gPackager )
					)
					( objectStatus "C2A6.1" )
				)
				( pin "b"
					( attribute "PN" "2"
						( Origin gPackager )
					)
					( objectStatus "C2A6.2" )
				)
			)
			( gate "@baseboard_fab2_lib.baseboard_fab2(sch_1):page228_i220"
				( attribute "CDS_LIB" "dev_discrete"
					( Origin gPackager )
				)
				( attribute "CDS_LOCATION" "C2A14"
					( Origin gPackager )
				)
				( attribute "CDS_SEC" "1"
					( Origin gPackager )
				)
				( attribute "LOCATION" "C2A14"
					( Origin gFrontEnd )
				)
				( attribute "MATERIAL" "X6S"
					( Origin gFrontEnd )
				)
				( attribute "PACK_TYPE" "0603V"
					( Origin gFrontEnd )
				)
				( attribute "PART_NUMBER" "E15431-004"
					( Origin gFrontEnd )
				)
				( attribute "PHYS_PAGE" "228"
					( Origin gFrontEnd )
				)
				( attribute "ROOM" "PVDDQ_KLM"
					( Origin gFrontEnd )
				)
				( attribute "ROT" "0"
					( Origin gFrontEnd )
				)
				( attribute "SEC" "1"
					( Origin gFrontEnd )
				)
				( attribute "SEC_TYPE" "0603V"
					( Origin gFrontEnd )
				)
				( attribute "TOLERANCE" "20%"
					( Origin gFrontEnd )
				)
				( attribute "VALUE" "22.0UF"
					( Origin gFrontEnd )
				)
				( attribute "VER" "1"
					( Origin gFrontEnd )
				)
				( attribute "VOLTAGE" "4V"
					( Units "uVoltage" "V" 1.000000)
					( Origin gFrontEnd )
				)
				( attribute "XY" "(-1100,-75)"
					( Origin gFrontEnd )
				)
				( attribute "CHIPS_PART_NAME" "CAP_A"
					( Origin gPackager )
				)
				( attribute "CDS_PART_NAME" "CAP_A_0603V-22.0UF,4V,20%,X6S,A"
					( Origin gPackager )
				)
				( objectStatus "C2A14" )
				( pin "a"
					( attribute "PN" "1"
						( Origin gPackager )
					)
					( objectStatus "C2A14.1" )
				)
				( pin "b"
					( attribute "PN" "2"
						( Origin gPackager )
					)
					( objectStatus "C2A14.2" )
				)
			)
			( gate "@baseboard_fab2_lib.baseboard_fab2(sch_1):page228_i221"
				( attribute "CDS_LIB" "dev_discrete"
					( Origin gPackager )
				)
				( attribute "CDS_LOCATION" "C2A15"
					( Origin gPackager )
				)
				( attribute "CDS_SEC" "1"
					( Origin gPackager )
				)
				( attribute "LOCATION" "C2A15"
					( Origin gFrontEnd )
				)
				( attribute "MATERIAL" "X6S"
					( Origin gFrontEnd )
				)
				( attribute "PACK_TYPE" "0603V"
					( Origin gFrontEnd )
				)
				( attribute "PART_NUMBER" "E15431-004"
					( Origin gFrontEnd )
				)
				( attribute "PHYS_PAGE" "228"
					( Origin gFrontEnd )
				)
				( attribute "ROOM" "PVDDQ_KLM"
					( Origin gFrontEnd )
				)
				( attribute "ROT" "0"
					( Origin gFrontEnd )
				)
				( attribute "SEC" "1"
					( Origin gFrontEnd )
				)
				( attribute "SEC_TYPE" "0603V"
					( Origin gFrontEnd )
				)
				( attribute "TOLERANCE" "20%"
					( Origin gFrontEnd )
				)
				( attribute "VALUE" "22.0UF"
					( Origin gFrontEnd )
				)
				( attribute "VER" "1"
					( Origin gFrontEnd )
				)
				( attribute "VOLTAGE" "4V"
					( Units "uVoltage" "V" 1.000000)
					( Origin gFrontEnd )
				)
				( attribute "XY" "(-1375,-75)"
					( Origin gFrontEnd )
				)
				( attribute "CHIPS_PART_NAME" "CAP_A"
					( Origin gPackager )
				)
				( attribute "CDS_PART_NAME" "CAP_A_0603V-22.0UF,4V,20%,X6S,A"
					( Origin gPackager )
				)
				( objectStatus "C2A15" )
				( pin "a"
					( attribute "PN" "1"
						( Origin gPackager )
					)
					( objectStatus "C2A15.1" )
				)
				( pin "b"
					( attribute "PN" "2"
						( Origin gPackager )
					)
					( objectStatus "C2A15.2" )
				)
			)
			( gate "@baseboard_fab2_lib.baseboard_fab2(sch_1):page228_i222"
				( attribute "CDS_LIB" "dev_discrete"
					( Origin gPackager )
				)
				( attribute "CDS_LOCATION" "C3A5"
					( Origin gPackager )
				)
				( attribute "CDS_SEC" "1"
					( Origin gPackager )
				)
				( attribute "LOCATION" "C3A5"
					( Origin gFrontEnd )
				)
				( attribute "MATERIAL" "X6S"
					( Origin gFrontEnd )
				)
				( attribute "PACK_TYPE" "0603V"
					( Origin gFrontEnd )
				)
				( attribute "PART_NUMBER" "E15431-004"
					( Origin gFrontEnd )
				)
				( attribute "PHYS_PAGE" "228"
					( Origin gFrontEnd )
				)
				( attribute "ROOM" "PVDDQ_KLM"
					( Origin gFrontEnd )
				)
				( attribute "ROT" "0"
					( Origin gFrontEnd )
				)
				( attribute "SEC" "1"
					( Origin gFrontEnd )
				)
				( attribute "SEC_TYPE" "0603V"
					( Origin gFrontEnd )
				)
				( attribute "TOLERANCE" "20%"
					( Origin gFrontEnd )
				)
				( attribute "VALUE" "22.0UF"
					( Origin gFrontEnd )
				)
				( attribute "VER" "1"
					( Origin gFrontEnd )
				)
				( attribute "VOLTAGE" "4V"
					( Units "uVoltage" "V" 1.000000)
					( Origin gFrontEnd )
				)
				( attribute "XY" "(-1650,-75)"
					( Origin gFrontEnd )
				)
				( attribute "CHIPS_PART_NAME" "CAP_A"
					( Origin gPackager )
				)
				( attribute "CDS_PART_NAME" "CAP_A_0603V-22.0UF,4V,20%,X6S,A"
					( Origin gPackager )
				)
				( objectStatus "C3A5" )
				( pin "a"
					( attribute "PN" "1"
						( Origin gPackager )
					)
					( objectStatus "C3A5.1" )
				)
				( pin "b"
					( attribute "PN" "2"
						( Origin gPackager )
					)
					( objectStatus "C3A5.2" )
				)
			)
			( gate "@baseboard_fab2_lib.baseboard_fab2(sch_1):page228_i223"
				( attribute "CDS_LIB" "dev_discrete"
					( Origin gPackager )
				)
				( attribute "CDS_LOCATION" "C3A6"
					( Origin gPackager )
				)
				( attribute "CDS_SEC" "1"
					( Origin gPackager )
				)
				( attribute "LOCATION" "C3A6"
					( Origin gFrontEnd )
				)
				( attribute "MATERIAL" "X6S"
					( Origin gFrontEnd )
				)
				( attribute "PACK_TYPE" "0603V"
					( Origin gFrontEnd )
				)
				( attribute "PART_NUMBER" "E15431-004"
					( Origin gFrontEnd )
				)
				( attribute "PHYS_PAGE" "228"
					( Origin gFrontEnd )
				)
				( attribute "ROOM" "PVDDQ_KLM"
					( Origin gFrontEnd )
				)
				( attribute "ROT" "0"
					( Origin gFrontEnd )
				)
				( attribute "SEC" "1"
					( Origin gFrontEnd )
				)
				( attribute "SEC_TYPE" "0603V"
					( Origin gFrontEnd )
				)
				( attribute "TOLERANCE" "20%"
					( Origin gFrontEnd )
				)
				( attribute "VALUE" "22.0UF"
					( Origin gFrontEnd )
				)
				( attribute "VER" "1"
					( Origin gFrontEnd )
				)
				( attribute "VOLTAGE" "4V"
					( Units "uVoltage" "V" 1.000000)
					( Origin gFrontEnd )
				)
				( attribute "XY" "(-1950,-75)"
					( Origin gFrontEnd )
				)
				( attribute "CHIPS_PART_NAME" "CAP_A"
					( Origin gPackager )
				)
				( attribute "CDS_PART_NAME" "CAP_A_0603V-22.0UF,4V,20%,X6S,A"
					( Origin gPackager )
				)
				( objectStatus "C3A6" )
				( pin "a"
					( attribute "PN" "1"
						( Origin gPackager )
					)
					( objectStatus "C3A6.1" )
				)
				( pin "b"
					( attribute "PN" "2"
						( Origin gPackager )
					)
					( objectStatus "C3A6.2" )
				)
			)
			( gate "@baseboard_fab2_lib.baseboard_fab2(sch_1):page228_i225"
				( attribute "CDS_LIB" "dev_discrete"
					( Origin gPackager )
				)
				( attribute "CDS_LOCATION" "C7L5"
					( Origin gPackager )
				)
				( attribute "CDS_SEC" "1"
					( Origin gPackager )
				)
				( attribute "LOCATION" "C7L5"
					( Origin gFrontEnd )
				)
				( attribute "MATERIAL" "X6S"
					( Origin gFrontEnd )
				)
				( attribute "PACK_TYPE" "0603V"
					( Origin gFrontEnd )
				)
				( attribute "PART_NUMBER" "E15431-004"
					( Origin gFrontEnd )
				)
				( attribute "PHYS_PAGE" "228"
					( Origin gFrontEnd )
				)
				( attribute "ROOM" "PVDDQ_KLM"
					( Origin gFrontEnd )
				)
				( attribute "ROT" "0"
					( Origin gFrontEnd )
				)
				( attribute "SEC" "1"
					( Origin gFrontEnd )
				)
				( attribute "SEC_TYPE" "0603V"
					( Origin gFrontEnd )
				)
				( attribute "TOLERANCE" "20%"
					( Origin gFrontEnd )
				)
				( attribute "VALUE" "22.0UF"
					( Origin gFrontEnd )
				)
				( attribute "VER" "1"
					( Origin gFrontEnd )
				)
				( attribute "VOLTAGE" "4V"
					( Units "uVoltage" "V" 1.000000)
					( Origin gFrontEnd )
				)
				( attribute "XY" "(-2250,-75)"
					( Origin gFrontEnd )
				)
				( attribute "CHIPS_PART_NAME" "CAP_A"
					( Origin gPackager )
				)
				( attribute "CDS_PART_NAME" "CAP_A_0603V-22.0UF,4V,20%,X6S,A"
					( Origin gPackager )
				)
				( objectStatus "C7L5" )
				( pin "a"
					( attribute "PN" "1"
						( Origin gPackager )
					)
					( objectStatus "C7L5.1" )
				)
				( pin "b"
					( attribute "PN" "2"
						( Origin gPackager )
					)
					( objectStatus "C7L5.2" )
				)
			)
			( gate "@baseboard_fab2_lib.baseboard_fab2(sch_1):page228_i227"
				( attribute "CDS_LIB" "dev_discrete"
					( Origin gPackager )
				)
				( attribute "CDS_LOCATION" "C8M3"
					( Origin gPackager )
				)
				( attribute "CDS_SEC" "1"
					( Origin gPackager )
				)
				( attribute "LOCATION" "C8M3"
					( Origin gFrontEnd )
				)
				( attribute "MATERIAL" "X6S"
					( Origin gFrontEnd )
				)
				( attribute "PACK_TYPE" "0603V"
					( Origin gFrontEnd )
				)
				( attribute "PART_NUMBER" "E15431-004"
					( Origin gFrontEnd )
				)
				( attribute "PHYS_PAGE" "228"
					( Origin gFrontEnd )
				)
				( attribute "ROOM" "PVDDQ_KLM"
					( Origin gFrontEnd )
				)
				( attribute "ROT" "0"
					( Origin gFrontEnd )
				)
				( attribute "SEC" "1"
					( Origin gFrontEnd )
				)
				( attribute "SEC_TYPE" "0603V"
					( Origin gFrontEnd )
				)
				( attribute "TOLERANCE" "20%"
					( Origin gFrontEnd )
				)
				( attribute "VALUE" "22.0UF"
					( Origin gFrontEnd )
				)
				( attribute "VER" "1"
					( Origin gFrontEnd )
				)
				( attribute "VOLTAGE" "4V"
					( Units "uVoltage" "V" 1.000000)
					( Origin gFrontEnd )
				)
				( attribute "XY" "(2150,-775)"
					( Origin gFrontEnd )
				)
				( attribute "CHIPS_PART_NAME" "CAP_A"
					( Origin gPackager )
				)
				( attribute "CDS_PART_NAME" "CAP_A_0603V-22.0UF,4V,20%,X6S,A"
					( Origin gPackager )
				)
				( objectStatus "C8M3" )
				( pin "a"
					( attribute "PN" "1"
						( Origin gPackager )
					)
					( objectStatus "C8M3.1" )
				)
				( pin "b"
					( attribute "PN" "2"
						( Origin gPackager )
					)
					( objectStatus "C8M3.2" )
				)
			)
			( gate "@baseboard_fab2_lib.baseboard_fab2(sch_1):page228_i228"
				( attribute "CDS_LIB" "dev_discrete"
					( Origin gPackager )
				)
				( attribute "CDS_LOCATION" "C8M5"
					( Origin gPackager )
				)
				( attribute "CDS_SEC" "1"
					( Origin gPackager )
				)
				( attribute "LOCATION" "C8M5"
					( Origin gFrontEnd )
				)
				( attribute "MATERIAL" "X6S"
					( Origin gFrontEnd )
				)
				( attribute "PACK_TYPE" "0603V"
					( Origin gFrontEnd )
				)
				( attribute "PART_NUMBER" "E15431-004"
					( Origin gFrontEnd )
				)
				( attribute "PHYS_PAGE" "228"
					( Origin gFrontEnd )
				)
				( attribute "ROOM" "PVDDQ_KLM"
					( Origin gFrontEnd )
				)
				( attribute "ROT" "0"
					( Origin gFrontEnd )
				)
				( attribute "SEC" "1"
					( Origin gFrontEnd )
				)
				( attribute "SEC_TYPE" "0603V"
					( Origin gFrontEnd )
				)
				( attribute "TOLERANCE" "20%"
					( Origin gFrontEnd )
				)
				( attribute "VALUE" "22.0UF"
					( Origin gFrontEnd )
				)
				( attribute "VER" "1"
					( Origin gFrontEnd )
				)
				( attribute "VOLTAGE" "4V"
					( Units "uVoltage" "V" 1.000000)
					( Origin gFrontEnd )
				)
				( attribute "XY" "(1875,-775)"
					( Origin gFrontEnd )
				)
				( attribute "CHIPS_PART_NAME" "CAP_A"
					( Origin gPackager )
				)
				( attribute "CDS_PART_NAME" "CAP_A_0603V-22.0UF,4V,20%,X6S,A"
					( Origin gPackager )
				)
				( objectStatus "C8M5" )
				( pin "a"
					( attribute "PN" "1"
						( Origin gPackager )
					)
					( objectStatus "C8M5.1" )
				)
				( pin "b"
					( attribute "PN" "2"
						( Origin gPackager )
					)
					( objectStatus "C8M5.2" )
				)
			)
			( gate "@baseboard_fab2_lib.baseboard_fab2(sch_1):page228_i229"
				( attribute "CDS_LIB" "dev_discrete"
					( Origin gPackager )
				)
				( attribute "CDS_LOCATION" "C8L10"
					( Origin gPackager )
				)
				( attribute "CDS_SEC" "1"
					( Origin gPackager )
				)
				( attribute "LOCATION" "C8L10"
					( Origin gFrontEnd )
				)
				( attribute "MATERIAL" "X6S"
					( Origin gFrontEnd )
				)
				( attribute "PACK_TYPE" "0603V"
					( Origin gFrontEnd )
				)
				( attribute "PART_NUMBER" "E15431-004"
					( Origin gFrontEnd )
				)
				( attribute "PHYS_PAGE" "228"
					( Origin gFrontEnd )
				)
				( attribute "ROOM" "PVDDQ_KLM"
					( Origin gFrontEnd )
				)
				( attribute "ROT" "0"
					( Origin gFrontEnd )
				)
				( attribute "SEC" "1"
					( Origin gFrontEnd )
				)
				( attribute "SEC_TYPE" "0603V"
					( Origin gFrontEnd )
				)
				( attribute "TOLERANCE" "20%"
					( Origin gFrontEnd )
				)
				( attribute "VALUE" "22.0UF"
					( Origin gFrontEnd )
				)
				( attribute "VER" "1"
					( Origin gFrontEnd )
				)
				( attribute "VOLTAGE" "4V"
					( Units "uVoltage" "V" 1.000000)
					( Origin gFrontEnd )
				)
				( attribute "XY" "(1575,-775)"
					( Origin gFrontEnd )
				)
				( attribute "CHIPS_PART_NAME" "CAP_A"
					( Origin gPackager )
				)
				( attribute "CDS_PART_NAME" "CAP_A_0603V-22.0UF,4V,20%,X6S,A"
					( Origin gPackager )
				)
				( objectStatus "C8L10" )
				( pin "a"
					( attribute "PN" "1"
						( Origin gPackager )
					)
					( objectStatus "C8L10.1" )
				)
				( pin "b"
					( attribute "PN" "2"
						( Origin gPackager )
					)
					( objectStatus "C8L10.2" )
				)
			)
			( gate "@baseboard_fab2_lib.baseboard_fab2(sch_1):page228_i230"
				( attribute "CDS_LIB" "dev_discrete"
					( Origin gPackager )
				)
				( attribute "CDS_LOCATION" "C2A3"
					( Origin gPackager )
				)
				( attribute "CDS_SEC" "1"
					( Origin gPackager )
				)
				( attribute "LOCATION" "C2A3"
					( Origin gFrontEnd )
				)
				( attribute "MATERIAL" "X6S"
					( Origin gFrontEnd )
				)
				( attribute "PACK_TYPE" "0603V"
					( Origin gFrontEnd )
				)
				( attribute "PART_NUMBER" "E15431-004"
					( Origin gFrontEnd )
				)
				( attribute "PHYS_PAGE" "228"
					( Origin gFrontEnd )
				)
				( attribute "ROOM" "PVDDQ_KLM"
					( Origin gFrontEnd )
				)
				( attribute "ROT" "0"
					( Origin gFrontEnd )
				)
				( attribute "SEC" "1"
					( Origin gFrontEnd )
				)
				( attribute "SEC_TYPE" "0603V"
					( Origin gFrontEnd )
				)
				( attribute "TOLERANCE" "20%"
					( Origin gFrontEnd )
				)
				( attribute "VALUE" "22.0UF"
					( Origin gFrontEnd )
				)
				( attribute "VER" "1"
					( Origin gFrontEnd )
				)
				( attribute "VOLTAGE" "4V"
					( Units "uVoltage" "V" 1.000000)
					( Origin gFrontEnd )
				)
				( attribute "XY" "(1275,-775)"
					( Origin gFrontEnd )
				)
				( attribute "CHIPS_PART_NAME" "CAP_A"
					( Origin gPackager )
				)
				( attribute "CDS_PART_NAME" "CAP_A_0603V-22.0UF,4V,20%,X6S,A"
					( Origin gPackager )
				)
				( objectStatus "C2A3" )
				( pin "a"
					( attribute "PN" "1"
						( Origin gPackager )
					)
					( objectStatus "C2A3.1" )
				)
				( pin "b"
					( attribute "PN" "2"
						( Origin gPackager )
					)
					( objectStatus "C2A3.2" )
				)
			)
			( gate "@baseboard_fab2_lib.baseboard_fab2(sch_1):page228_i231"
				( attribute "CDS_LIB" "dev_discrete"
					( Origin gPackager )
				)
				( attribute "CDS_LOCATION" "C7M1"
					( Origin gPackager )
				)
				( attribute "CDS_SEC" "1"
					( Origin gPackager )
				)
				( attribute "LOCATION" "C7M1"
					( Origin gFrontEnd )
				)
				( attribute "MATERIAL" "X6S"
					( Origin gFrontEnd )
				)
				( attribute "PACK_TYPE" "0603V"
					( Origin gFrontEnd )
				)
				( attribute "PART_NUMBER" "E15431-004"
					( Origin gFrontEnd )
				)
				( attribute "PHYS_PAGE" "228"
					( Origin gFrontEnd )
				)
				( attribute "ROOM" "PVDDQ_KLM"
					( Origin gFrontEnd )
				)
				( attribute "ROT" "0"
					( Origin gFrontEnd )
				)
				( attribute "SEC" "1"
					( Origin gFrontEnd )
				)
				( attribute "SEC_TYPE" "0603V"
					( Origin gFrontEnd )
				)
				( attribute "TOLERANCE" "20%"
					( Origin gFrontEnd )
				)
				( attribute "VALUE" "22.0UF"
					( Origin gFrontEnd )
				)
				( attribute "VER" "1"
					( Origin gFrontEnd )
				)
				( attribute "VOLTAGE" "4V"
					( Units "uVoltage" "V" 1.000000)
					( Origin gFrontEnd )
				)
				( attribute "XY" "(1000,-775)"
					( Origin gFrontEnd )
				)
				( attribute "CHIPS_PART_NAME" "CAP_A"
					( Origin gPackager )
				)
				( attribute "CDS_PART_NAME" "CAP_A_0603V-22.0UF,4V,20%,X6S,A"
					( Origin gPackager )
				)
				( objectStatus "C7M1" )
				( pin "a"
					( attribute "PN" "1"
						( Origin gPackager )
					)
					( objectStatus "C7M1.1" )
				)
				( pin "b"
					( attribute "PN" "2"
						( Origin gPackager )
					)
					( objectStatus "C7M1.2" )
				)
			)
			( gate "@baseboard_fab2_lib.baseboard_fab2(sch_1):page228_i232"
				( attribute "CDS_LIB" "dev_discrete"
					( Origin gPackager )
				)
				( attribute "CDS_LOCATION" "C7M2"
					( Origin gPackager )
				)
				( attribute "CDS_SEC" "1"
					( Origin gPackager )
				)
				( attribute "LOCATION" "C7M2"
					( Origin gFrontEnd )
				)
				( attribute "MATERIAL" "X6S"
					( Origin gFrontEnd )
				)
				( attribute "PACK_TYPE" "0603V"
					( Origin gFrontEnd )
				)
				( attribute "PART_NUMBER" "E15431-004"
					( Origin gFrontEnd )
				)
				( attribute "PHYS_PAGE" "228"
					( Origin gFrontEnd )
				)
				( attribute "ROOM" "PVDDQ_KLM"
					( Origin gFrontEnd )
				)
				( attribute "ROT" "0"
					( Origin gFrontEnd )
				)
				( attribute "SEC" "1"
					( Origin gFrontEnd )
				)
				( attribute "SEC_TYPE" "0603V"
					( Origin gFrontEnd )
				)
				( attribute "TOLERANCE" "20%"
					( Origin gFrontEnd )
				)
				( attribute "VALUE" "22.0UF"
					( Origin gFrontEnd )
				)
				( attribute "VER" "1"
					( Origin gFrontEnd )
				)
				( attribute "VOLTAGE" "4V"
					( Units "uVoltage" "V" 1.000000)
					( Origin gFrontEnd )
				)
				( attribute "XY" "(725,-775)"
					( Origin gFrontEnd )
				)
				( attribute "CHIPS_PART_NAME" "CAP_A"
					( Origin gPackager )
				)
				( attribute "CDS_PART_NAME" "CAP_A_0603V-22.0UF,4V,20%,X6S,A"
					( Origin gPackager )
				)
				( objectStatus "C7M2" )
				( pin "a"
					( attribute "PN" "1"
						( Origin gPackager )
					)
					( objectStatus "C7M2.1" )
				)
				( pin "b"
					( attribute "PN" "2"
						( Origin gPackager )
					)
					( objectStatus "C7M2.2" )
				)
			)
			( gate "@baseboard_fab2_lib.baseboard_fab2(sch_1):page228_i233"
				( attribute "CDS_LIB" "dev_discrete"
					( Origin gPackager )
				)
				( attribute "CDS_LOCATION" "C8M4"
					( Origin gPackager )
				)
				( attribute "CDS_SEC" "1"
					( Origin gPackager )
				)
				( attribute "LOCATION" "C8M4"
					( Origin gFrontEnd )
				)
				( attribute "MATERIAL" "X6S"
					( Origin gFrontEnd )
				)
				( attribute "PACK_TYPE" "0603V"
					( Origin gFrontEnd )
				)
				( attribute "PART_NUMBER" "E15431-004"
					( Origin gFrontEnd )
				)
				( attribute "PHYS_PAGE" "228"
					( Origin gFrontEnd )
				)
				( attribute "ROOM" "PVDDQ_KLM"
					( Origin gFrontEnd )
				)
				( attribute "ROT" "0"
					( Origin gFrontEnd )
				)
				( attribute "SEC" "1"
					( Origin gFrontEnd )
				)
				( attribute "SEC_TYPE" "0603V"
					( Origin gFrontEnd )
				)
				( attribute "TOLERANCE" "20%"
					( Origin gFrontEnd )
				)
				( attribute "VALUE" "22.0UF"
					( Origin gFrontEnd )
				)
				( attribute "VER" "1"
					( Origin gFrontEnd )
				)
				( attribute "VOLTAGE" "4V"
					( Units "uVoltage" "V" 1.000000)
					( Origin gFrontEnd )
				)
				( attribute "XY" "(425,-775)"
					( Origin gFrontEnd )
				)
				( attribute "CHIPS_PART_NAME" "CAP_A"
					( Origin gPackager )
				)
				( attribute "CDS_PART_NAME" "CAP_A_0603V-22.0UF,4V,20%,X6S,A"
					( Origin gPackager )
				)
				( objectStatus "C8M4" )
				( pin "a"
					( attribute "PN" "1"
						( Origin gPackager )
					)
					( objectStatus "C8M4.1" )
				)
				( pin "b"
					( attribute "PN" "2"
						( Origin gPackager )
					)
					( objectStatus "C8M4.2" )
				)
			)
			( gate "@baseboard_fab2_lib.baseboard_fab2(sch_1):page228_i234"
				( attribute "CDS_LIB" "dev_discrete"
					( Origin gPackager )
				)
				( attribute "CDS_LOCATION" "C2A4"
					( Origin gPackager )
				)
				( attribute "CDS_SEC" "1"
					( Origin gPackager )
				)
				( attribute "LOCATION" "C2A4"
					( Origin gFrontEnd )
				)
				( attribute "MATERIAL" "X6S"
					( Origin gFrontEnd )
				)
				( attribute "PACK_TYPE" "0603V"
					( Origin gFrontEnd )
				)
				( attribute "PART_NUMBER" "E15431-004"
					( Origin gFrontEnd )
				)
				( attribute "PHYS_PAGE" "228"
					( Origin gFrontEnd )
				)
				( attribute "ROOM" "PVDDQ_KLM"
					( Origin gFrontEnd )
				)
				( attribute "ROT" "0"
					( Origin gFrontEnd )
				)
				( attribute "SEC" "1"
					( Origin gFrontEnd )
				)
				( attribute "SEC_TYPE" "0603V"
					( Origin gFrontEnd )
				)
				( attribute "TOLERANCE" "20%"
					( Origin gFrontEnd )
				)
				( attribute "VALUE" "22.0UF"
					( Origin gFrontEnd )
				)
				( attribute "VER" "1"
					( Origin gFrontEnd )
				)
				( attribute "VOLTAGE" "4V"
					( Units "uVoltage" "V" 1.000000)
					( Origin gFrontEnd )
				)
				( attribute "XY" "(125,-775)"
					( Origin gFrontEnd )
				)
				( attribute "CHIPS_PART_NAME" "CAP_A"
					( Origin gPackager )
				)
				( attribute "CDS_PART_NAME" "CAP_A_0603V-22.0UF,4V,20%,X6S,A"
					( Origin gPackager )
				)
				( objectStatus "C2A4" )
				( pin "a"
					( attribute "PN" "1"
						( Origin gPackager )
					)
					( objectStatus "C2A4.1" )
				)
				( pin "b"
					( attribute "PN" "2"
						( Origin gPackager )
					)
					( objectStatus "C2A4.2" )
				)
			)
			( gate "@baseboard_fab2_lib.baseboard_fab2(sch_1):page228_i235"
				( attribute "CDS_LIB" "dev_discrete"
					( Origin gPackager )
				)
				( attribute "CDS_LOCATION" "C8M6"
					( Origin gPackager )
				)
				( attribute "CDS_SEC" "1"
					( Origin gPackager )
				)
				( attribute "LOCATION" "C8M6"
					( Origin gFrontEnd )
				)
				( attribute "MATERIAL" "X6S"
					( Origin gFrontEnd )
				)
				( attribute "PACK_TYPE" "0603V"
					( Origin gFrontEnd )
				)
				( attribute "PART_NUMBER" "E15431-004"
					( Origin gFrontEnd )
				)
				( attribute "PHYS_PAGE" "228"
					( Origin gFrontEnd )
				)
				( attribute "ROOM" "PVDDQ_KLM"
					( Origin gFrontEnd )
				)
				( attribute "ROT" "0"
					( Origin gFrontEnd )
				)
				( attribute "SEC" "1"
					( Origin gFrontEnd )
				)
				( attribute "SEC_TYPE" "0603V"
					( Origin gFrontEnd )
				)
				( attribute "TOLERANCE" "20%"
					( Origin gFrontEnd )
				)
				( attribute "VALUE" "22.0UF"
					( Origin gFrontEnd )
				)
				( attribute "VER" "1"
					( Origin gFrontEnd )
				)
				( attribute "VOLTAGE" "4V"
					( Units "uVoltage" "V" 1.000000)
					( Origin gFrontEnd )
				)
				( attribute "XY" "(-200,-775)"
					( Origin gFrontEnd )
				)
				( attribute "CHIPS_PART_NAME" "CAP_A"
					( Origin gPackager )
				)
				( attribute "CDS_PART_NAME" "CAP_A_0603V-22.0UF,4V,20%,X6S,A"
					( Origin gPackager )
				)
				( objectStatus "C8M6" )
				( pin "a"
					( attribute "PN" "1"
						( Origin gPackager )
					)
					( objectStatus "C8M6.1" )
				)
				( pin "b"
					( attribute "PN" "2"
						( Origin gPackager )
					)
					( objectStatus "C8M6.2" )
				)
			)
			( gate "@baseboard_fab2_lib.baseboard_fab2(sch_1):page228_i236"
				( attribute "CDS_LIB" "dev_discrete"
					( Origin gPackager )
				)
				( attribute "CDS_LOCATION" "C8L9"
					( Origin gPackager )
				)
				( attribute "CDS_SEC" "1"
					( Origin gPackager )
				)
				( attribute "LOCATION" "C8L9"
					( Origin gFrontEnd )
				)
				( attribute "MATERIAL" "X6S"
					( Origin gFrontEnd )
				)
				( attribute "PACK_TYPE" "0603V"
					( Origin gFrontEnd )
				)
				( attribute "PART_NUMBER" "E15431-004"
					( Origin gFrontEnd )
				)
				( attribute "PHYS_PAGE" "228"
					( Origin gFrontEnd )
				)
				( attribute "ROOM" "PVDDQ_KLM"
					( Origin gFrontEnd )
				)
				( attribute "ROT" "0"
					( Origin gFrontEnd )
				)
				( attribute "SEC" "1"
					( Origin gFrontEnd )
				)
				( attribute "SEC_TYPE" "0603V"
					( Origin gFrontEnd )
				)
				( attribute "TOLERANCE" "20%"
					( Origin gFrontEnd )
				)
				( attribute "VALUE" "22.0UF"
					( Origin gFrontEnd )
				)
				( attribute "VER" "1"
					( Origin gFrontEnd )
				)
				( attribute "VOLTAGE" "4V"
					( Units "uVoltage" "V" 1.000000)
					( Origin gFrontEnd )
				)
				( attribute "XY" "(-475,-775)"
					( Origin gFrontEnd )
				)
				( attribute "CHIPS_PART_NAME" "CAP_A"
					( Origin gPackager )
				)
				( attribute "CDS_PART_NAME" "CAP_A_0603V-22.0UF,4V,20%,X6S,A"
					( Origin gPackager )
				)
				( objectStatus "C8L9" )
				( pin "a"
					( attribute "PN" "1"
						( Origin gPackager )
					)
					( objectStatus "C8L9.1" )
				)
				( pin "b"
					( attribute "PN" "2"
						( Origin gPackager )
					)
					( objectStatus "C8L9.2" )
				)
			)
			( gate "@baseboard_fab2_lib.baseboard_fab2(sch_1):page228_i237"
				( attribute "CDS_LIB" "dev_discrete"
					( Origin gPackager )
				)
				( attribute "CDS_LOCATION" "C8L8"
					( Origin gPackager )
				)
				( attribute "CDS_SEC" "1"
					( Origin gPackager )
				)
				( attribute "LOCATION" "C8L8"
					( Origin gFrontEnd )
				)
				( attribute "MATERIAL" "X6S"
					( Origin gFrontEnd )
				)
				( attribute "PACK_TYPE" "0603V"
					( Origin gFrontEnd )
				)
				( attribute "PART_NUMBER" "E15431-004"
					( Origin gFrontEnd )
				)
				( attribute "PHYS_PAGE" "228"
					( Origin gFrontEnd )
				)
				( attribute "ROOM" "PVDDQ_KLM"
					( Origin gFrontEnd )
				)
				( attribute "ROT" "0"
					( Origin gFrontEnd )
				)
				( attribute "SEC" "1"
					( Origin gFrontEnd )
				)
				( attribute "SEC_TYPE" "0603V"
					( Origin gFrontEnd )
				)
				( attribute "TOLERANCE" "20%"
					( Origin gFrontEnd )
				)
				( attribute "VALUE" "22.0UF"
					( Origin gFrontEnd )
				)
				( attribute "VER" "1"
					( Origin gFrontEnd )
				)
				( attribute "VOLTAGE" "4V"
					( Units "uVoltage" "V" 1.000000)
					( Origin gFrontEnd )
				)
				( attribute "XY" "(-775,-775)"
					( Origin gFrontEnd )
				)
				( attribute "CHIPS_PART_NAME" "CAP_A"
					( Origin gPackager )
				)
				( attribute "CDS_PART_NAME" "CAP_A_0603V-22.0UF,4V,20%,X6S,A"
					( Origin gPackager )
				)
				( objectStatus "C8L8" )
				( pin "a"
					( attribute "PN" "1"
						( Origin gPackager )
					)
					( objectStatus "C8L8.1" )
				)
				( pin "b"
					( attribute "PN" "2"
						( Origin gPackager )
					)
					( objectStatus "C8L8.2" )
				)
			)
			( gate "@baseboard_fab2_lib.baseboard_fab2(sch_1):page228_i238"
				( attribute "CDS_LIB" "dev_discrete"
					( Origin gPackager )
				)
				( attribute "CDS_LOCATION" "C7L4"
					( Origin gPackager )
				)
				( attribute "CDS_SEC" "1"
					( Origin gPackager )
				)
				( attribute "LOCATION" "C7L4"
					( Origin gFrontEnd )
				)
				( attribute "MATERIAL" "X6S"
					( Origin gFrontEnd )
				)
				( attribute "PACK_TYPE" "0603V"
					( Origin gFrontEnd )
				)
				( attribute "PART_NUMBER" "E15431-004"
					( Origin gFrontEnd )
				)
				( attribute "PHYS_PAGE" "228"
					( Origin gFrontEnd )
				)
				( attribute "ROOM" "PVDDQ_KLM"
					( Origin gFrontEnd )
				)
				( attribute "ROT" "0"
					( Origin gFrontEnd )
				)
				( attribute "SEC" "1"
					( Origin gFrontEnd )
				)
				( attribute "SEC_TYPE" "0603V"
					( Origin gFrontEnd )
				)
				( attribute "TOLERANCE" "20%"
					( Origin gFrontEnd )
				)
				( attribute "VALUE" "22.0UF"
					( Origin gFrontEnd )
				)
				( attribute "VER" "1"
					( Origin gFrontEnd )
				)
				( attribute "VOLTAGE" "4V"
					( Units "uVoltage" "V" 1.000000)
					( Origin gFrontEnd )
				)
				( attribute "XY" "(-1075,-775)"
					( Origin gFrontEnd )
				)
				( attribute "CHIPS_PART_NAME" "CAP_A"
					( Origin gPackager )
				)
				( attribute "CDS_PART_NAME" "CAP_A_0603V-22.0UF,4V,20%,X6S,A"
					( Origin gPackager )
				)
				( objectStatus "C7L4" )
				( pin "a"
					( attribute "PN" "1"
						( Origin gPackager )
					)
					( objectStatus "C7L4.1" )
				)
				( pin "b"
					( attribute "PN" "2"
						( Origin gPackager )
					)
					( objectStatus "C7L4.2" )
				)
			)
			( gate "@baseboard_fab2_lib.baseboard_fab2(sch_1):page228_i239"
				( attribute "CDS_LIB" "dev_discrete"
					( Origin gPackager )
				)
				( attribute "CDS_LOCATION" "C8L7"
					( Origin gPackager )
				)
				( attribute "CDS_SEC" "1"
					( Origin gPackager )
				)
				( attribute "LOCATION" "C8L7"
					( Origin gFrontEnd )
				)
				( attribute "MATERIAL" "X6S"
					( Origin gFrontEnd )
				)
				( attribute "PACK_TYPE" "0603V"
					( Origin gFrontEnd )
				)
				( attribute "PART_NUMBER" "E15431-004"
					( Origin gFrontEnd )
				)
				( attribute "PHYS_PAGE" "228"
					( Origin gFrontEnd )
				)
				( attribute "ROOM" "PVDDQ_KLM"
					( Origin gFrontEnd )
				)
				( attribute "ROT" "0"
					( Origin gFrontEnd )
				)
				( attribute "SEC" "1"
					( Origin gFrontEnd )
				)
				( attribute "SEC_TYPE" "0603V"
					( Origin gFrontEnd )
				)
				( attribute "TOLERANCE" "20%"
					( Origin gFrontEnd )
				)
				( attribute "VALUE" "22.0UF"
					( Origin gFrontEnd )
				)
				( attribute "VER" "1"
					( Origin gFrontEnd )
				)
				( attribute "VOLTAGE" "4V"
					( Units "uVoltage" "V" 1.000000)
					( Origin gFrontEnd )
				)
				( attribute "XY" "(-1350,-775)"
					( Origin gFrontEnd )
				)
				( attribute "CHIPS_PART_NAME" "CAP_A"
					( Origin gPackager )
				)
				( attribute "CDS_PART_NAME" "CAP_A_0603V-22.0UF,4V,20%,X6S,A"
					( Origin gPackager )
				)
				( objectStatus "C8L7" )
				( pin "a"
					( attribute "PN" "1"
						( Origin gPackager )
					)
					( objectStatus "C8L7.1" )
				)
				( pin "b"
					( attribute "PN" "2"
						( Origin gPackager )
					)
					( objectStatus "C8L7.2" )
				)
			)
			( gate "@baseboard_fab2_lib.baseboard_fab2(sch_1):page228_i240"
				( attribute "CDS_LIB" "dev_discrete"
					( Origin gPackager )
				)
				( attribute "CDS_LOCATION" "C8L6"
					( Origin gPackager )
				)
				( attribute "CDS_SEC" "1"
					( Origin gPackager )
				)
				( attribute "LOCATION" "C8L6"
					( Origin gFrontEnd )
				)
				( attribute "MATERIAL" "X6S"
					( Origin gFrontEnd )
				)
				( attribute "PACK_TYPE" "0603V"
					( Origin gFrontEnd )
				)
				( attribute "PART_NUMBER" "E15431-004"
					( Origin gFrontEnd )
				)
				( attribute "PHYS_PAGE" "228"
					( Origin gFrontEnd )
				)
				( attribute "ROOM" "PVDDQ_KLM"
					( Origin gFrontEnd )
				)
				( attribute "ROT" "0"
					( Origin gFrontEnd )
				)
				( attribute "SEC" "1"
					( Origin gFrontEnd )
				)
				( attribute "SEC_TYPE" "0603V"
					( Origin gFrontEnd )
				)
				( attribute "TOLERANCE" "20%"
					( Origin gFrontEnd )
				)
				( attribute "VALUE" "22.0UF"
					( Origin gFrontEnd )
				)
				( attribute "VER" "1"
					( Origin gFrontEnd )
				)
				( attribute "VOLTAGE" "4V"
					( Units "uVoltage" "V" 1.000000)
					( Origin gFrontEnd )
				)
				( attribute "XY" "(-1625,-775)"
					( Origin gFrontEnd )
				)
				( attribute "CHIPS_PART_NAME" "CAP_A"
					( Origin gPackager )
				)
				( attribute "CDS_PART_NAME" "CAP_A_0603V-22.0UF,4V,20%,X6S,A"
					( Origin gPackager )
				)
				( objectStatus "C8L6" )
				( pin "a"
					( attribute "PN" "1"
						( Origin gPackager )
					)
					( objectStatus "C8L6.1" )
				)
				( pin "b"
					( attribute "PN" "2"
						( Origin gPackager )
					)
					( objectStatus "C8L6.2" )
				)
			)
			( gate "@baseboard_fab2_lib.baseboard_fab2(sch_1):page228_i241"
				( attribute "CDS_LIB" "dev_discrete"
					( Origin gPackager )
				)
				( attribute "CDS_LOCATION" "C8L5"
					( Origin gPackager )
				)
				( attribute "CDS_SEC" "1"
					( Origin gPackager )
				)
				( attribute "LOCATION" "C8L5"
					( Origin gFrontEnd )
				)
				( attribute "MATERIAL" "X6S"
					( Origin gFrontEnd )
				)
				( attribute "PACK_TYPE" "0603V"
					( Origin gFrontEnd )
				)
				( attribute "PART_NUMBER" "E15431-004"
					( Origin gFrontEnd )
				)
				( attribute "PHYS_PAGE" "228"
					( Origin gFrontEnd )
				)
				( attribute "ROOM" "PVDDQ_KLM"
					( Origin gFrontEnd )
				)
				( attribute "ROT" "0"
					( Origin gFrontEnd )
				)
				( attribute "SEC" "1"
					( Origin gFrontEnd )
				)
				( attribute "SEC_TYPE" "0603V"
					( Origin gFrontEnd )
				)
				( attribute "TOLERANCE" "20%"
					( Origin gFrontEnd )
				)
				( attribute "VALUE" "22.0UF"
					( Origin gFrontEnd )
				)
				( attribute "VER" "1"
					( Origin gFrontEnd )
				)
				( attribute "VOLTAGE" "4V"
					( Units "uVoltage" "V" 1.000000)
					( Origin gFrontEnd )
				)
				( attribute "XY" "(-1925,-775)"
					( Origin gFrontEnd )
				)
				( attribute "CHIPS_PART_NAME" "CAP_A"
					( Origin gPackager )
				)
				( attribute "CDS_PART_NAME" "CAP_A_0603V-22.0UF,4V,20%,X6S,A"
					( Origin gPackager )
				)
				( objectStatus "C8L5" )
				( pin "a"
					( attribute "PN" "1"
						( Origin gPackager )
					)
					( objectStatus "C8L5.1" )
				)
				( pin "b"
					( attribute "PN" "2"
						( Origin gPackager )
					)
					( objectStatus "C8L5.2" )
				)
			)
			( gate "@baseboard_fab2_lib.baseboard_fab2(sch_1):page228_i243"
				( attribute "CDS_LIB" "dev_discrete"
					( Origin gPackager )
				)
				( attribute "CDS_LOCATION" "C8M1"
					( Origin gPackager )
				)
				( attribute "CDS_SEC" "1"
					( Origin gPackager )
				)
				( attribute "LOCATION" "C8M1"
					( Origin gFrontEnd )
				)
				( attribute "MATERIAL" "X6S"
					( Origin gFrontEnd )
				)
				( attribute "PACK_TYPE" "0603V"
					( Origin gFrontEnd )
				)
				( attribute "PART_NUMBER" "E15431-004"
					( Origin gFrontEnd )
				)
				( attribute "PHYS_PAGE" "228"
					( Origin gFrontEnd )
				)
				( attribute "ROOM" "PVDDQ_KLM"
					( Origin gFrontEnd )
				)
				( attribute "ROT" "0"
					( Origin gFrontEnd )
				)
				( attribute "SEC" "1"
					( Origin gFrontEnd )
				)
				( attribute "SEC_TYPE" "0603V"
					( Origin gFrontEnd )
				)
				( attribute "TOLERANCE" "20%"
					( Origin gFrontEnd )
				)
				( attribute "VALUE" "22.0UF"
					( Origin gFrontEnd )
				)
				( attribute "VER" "1"
					( Origin gFrontEnd )
				)
				( attribute "VOLTAGE" "4V"
					( Units "uVoltage" "V" 1.000000)
					( Origin gFrontEnd )
				)
				( attribute "XY" "(-2225,-775)"
					( Origin gFrontEnd )
				)
				( attribute "CHIPS_PART_NAME" "CAP_A"
					( Origin gPackager )
				)
				( attribute "CDS_PART_NAME" "CAP_A_0603V-22.0UF,4V,20%,X6S,A"
					( Origin gPackager )
				)
				( objectStatus "C8M1" )
				( pin "a"
					( attribute "PN" "1"
						( Origin gPackager )
					)
					( objectStatus "C8M1.1" )
				)
				( pin "b"
					( attribute "PN" "2"
						( Origin gPackager )
					)
					( objectStatus "C8M1.2" )
				)
			)
			( gate "@baseboard_fab2_lib.baseboard_fab2(sch_1):page228_i245"
				( attribute "CDS_LIB" "mstr_misc"
					( Origin gPackager )
				)
				( attribute "CDS_LOCATION" "SH7L2"
					( Origin gPackager )
				)
				( attribute "CDS_SEC" "1"
					( Origin gPackager )
				)
				( attribute "LOCATION" "SH7L2"
					( Origin gFrontEnd )
				)
				( attribute "MATERIAL" "EMPTY"
					( Origin gFrontEnd )
				)
				( attribute "PACK_TYPE" "SH0201"
					( Origin gFrontEnd )
				)
				( attribute "PART_NUMBER" "N_A"
					( Origin gFrontEnd )
				)
				( attribute "PHYS_PAGE" "228"
					( Origin gFrontEnd )
				)
				( attribute "PIN_SHORT" "A:B"
					( Origin gFrontEnd )
				)
				( attribute "ROT" "0"
					( Origin gFrontEnd )
				)
				( attribute "SEC" "1"
					( Origin gFrontEnd )
				)
				( attribute "SEC_TYPE" "SH0201"
					( Origin gFrontEnd )
				)
				( attribute "VER" "1"
					( Origin gFrontEnd )
				)
				( attribute "XY" "(75,2175)"
					( Origin gFrontEnd )
				)
				( attribute "CHIPS_PART_NAME" "SHUNT"
					( Origin gPackager )
				)
				( attribute "CDS_PART_NAME" "SHUNT_SH0201-EMPTY,N_A"
					( Origin gPackager )
				)
				( objectStatus "SH7L2" )
				( pin "a"
					( attribute "PN" "1"
						( Origin gPackager )
					)
					( objectStatus "SH7L2.1" )
				)
				( pin "b"
					( attribute "PN" "2"
						( Origin gPackager )
					)
					( objectStatus "SH7L2.2" )
				)
			)
			( gate "@baseboard_fab2_lib.baseboard_fab2(sch_1):page228_i246"
				( attribute "CDS_LIB" "mstr_misc"
					( Origin gPackager )
				)
				( attribute "CDS_LOCATION" "SH7L1"
					( Origin gPackager )
				)
				( attribute "CDS_SEC" "1"
					( Origin gPackager )
				)
				( attribute "LOCATION" "SH7L1"
					( Origin gFrontEnd )
				)
				( attribute "MATERIAL" "EMPTY"
					( Origin gFrontEnd )
				)
				( attribute "PACK_TYPE" "SH0201"
					( Origin gFrontEnd )
				)
				( attribute "PART_NUMBER" "N_A"
					( Origin gFrontEnd )
				)
				( attribute "PHYS_PAGE" "228"
					( Origin gFrontEnd )
				)
				( attribute "PIN_SHORT" "A:B"
					( Origin gFrontEnd )
				)
				( attribute "ROT" "0"
					( Origin gFrontEnd )
				)
				( attribute "SEC" "1"
					( Origin gFrontEnd )
				)
				( attribute "SEC_TYPE" "SH0201"
					( Origin gFrontEnd )
				)
				( attribute "VER" "1"
					( Origin gFrontEnd )
				)
				( attribute "XY" "(75,1725)"
					( Origin gFrontEnd )
				)
				( attribute "CHIPS_PART_NAME" "SHUNT"
					( Origin gPackager )
				)
				( attribute "CDS_PART_NAME" "SHUNT_SH0201-EMPTY,N_A"
					( Origin gPackager )
				)
				( objectStatus "SH7L1" )
				( pin "a"
					( attribute "PN" "1"
						( Origin gPackager )
					)
					( objectStatus "SH7L1.1" )
				)
				( pin "b"
					( attribute "PN" "2"
						( Origin gPackager )
					)
					( objectStatus "SH7L1.2" )
				)
			)
			( gate "@baseboard_fab2_lib.baseboard_fab2(sch_1):page229_i14"
				( attribute "BOM_COST" "MEM_VRD_VTT_GHJ"
					( Origin gFrontEnd )
				)
				( attribute "CDS_LIB" "mstr_discrete"
					( Origin gPackager )
				)
				( attribute "CDS_LOCATION" "R4G17"
					( Origin gPackager )
				)
				( attribute "CDS_SEC" "1"
					( Origin gPackager )
				)
				( attribute "LOCATION" "R4G17"
					( Origin gFrontEnd )
				)
				( attribute "MATERIAL" "CHIP"
					( Origin gFrontEnd )
				)
				( attribute "PACK_TYPE" "0402"
					( Origin gFrontEnd )
				)
				( attribute "PART_NUMBER" "G21796-016"
					( Origin gFrontEnd )
				)
				( attribute "PHYS_PAGE" "229"
					( Origin gFrontEnd )
				)
				( attribute "ROOM" "VTT_GHJ_PWR_VR"
					( Origin gFrontEnd )
				)
				( attribute "ROT" "0"
					( Origin gFrontEnd )
				)
				( attribute "SEC" "1"
					( Origin gFrontEnd )
				)
				( attribute "SEC_TYPE" "0402"
					( Origin gFrontEnd )
				)
				( attribute "TOLERANCE" "1%"
					( Origin gFrontEnd )
				)
				( attribute "VALUE" "10.0K"
					( Origin gFrontEnd )
				)
				( attribute "VER" "2"
					( Origin gFrontEnd )
				)
				( attribute "WATTAGE" "1/16W"
					( Origin gFrontEnd )
				)
				( attribute "XY" "(3450,2025)"
					( Origin gFrontEnd )
				)
				( attribute "CHIPS_PART_NAME" "RES"
					( Origin gPackager )
				)
				( attribute "CDS_PART_NAME" "RES_0402-10.0K,1%,1/16W,CHIP,GA"
					( Origin gPackager )
				)
				( objectStatus "R4G17" )
				( pin "a"
					( attribute "PN" "1"
						( Origin gPackager )
					)
					( objectStatus "R4G17.1" )
				)
				( pin "b"
					( attribute "PN" "2"
						( Origin gPackager )
					)
					( objectStatus "R4G17.2" )
				)
			)
			( gate "@baseboard_fab2_lib.baseboard_fab2(sch_1):page229_i15"
				( attribute "BOM_COST" "MEM_VRD_VTT_GHJ"
					( Origin gFrontEnd )
				)
				( attribute "CDS_LIB" "mstr_discrete"
					( Origin gPackager )
				)
				( attribute "CDS_LOCATION" "C4G13"
					( Origin gPackager )
				)
				( attribute "CDS_SEC" "1"
					( Origin gPackager )
				)
				( attribute "LOCATION" "C4G13"
					( Origin gFrontEnd )
				)
				( attribute "MATERIAL" "X7R"
					( Origin gFrontEnd )
				)
				( attribute "PACK_TYPE" "0402LF"
					( Origin gFrontEnd )
				)
				( attribute "PART_NUMBER" "A36096-046"
					( Origin gFrontEnd )
				)
				( attribute "PHYS_PAGE" "229"
					( Origin gFrontEnd )
				)
				( attribute "ROOM" "VTT_GHJ_PWR_VR"
					( Origin gFrontEnd )
				)
				( attribute "ROT" "2"
					( Origin gFrontEnd )
				)
				( attribute "SEC" "1"
					( Origin gFrontEnd )
				)
				( attribute "SEC_TYPE" "0402LF"
					( Origin gFrontEnd )
				)
				( attribute "TOLERANCE" "10%"
					( Origin gFrontEnd )
				)
				( attribute "VALUE" "1000PF"
					( Origin gFrontEnd )
				)
				( attribute "VER" "1"
					( Origin gFrontEnd )
				)
				( attribute "VOLTAGE" "50V"
					( Units "uVoltage" "V" 1.000000)
					( Origin gFrontEnd )
				)
				( attribute "XY" "(3825,1625)"
					( Origin gFrontEnd )
				)
				( attribute "CHIPS_PART_NAME" "CAP"
					( Origin gPackager )
				)
				( attribute "CDS_PART_NAME" "CAP_0402LF-1000PF,50V,10%,X7R,A"
					( Origin gPackager )
				)
				( objectStatus "C4G13" )
				( pin "a"
					( attribute "PN" "1"
						( Origin gPackager )
					)
					( objectStatus "C4G13.1" )
				)
				( pin "b"
					( attribute "PN" "2"
						( Origin gPackager )
					)
					( objectStatus "C4G13.2" )
				)
			)
			( gate "@baseboard_fab2_lib.baseboard_fab2(sch_1):page229_i17"
				( attribute "BOM_COST" "MEM_VRD_VTT_GHJ"
					( Origin gFrontEnd )
				)
				( attribute "CDS_LIB" "mstr_discrete"
					( Origin gPackager )
				)
				( attribute "CDS_LOCATION" "C4G20"
					( Origin gPackager )
				)
				( attribute "CDS_SEC" "1"
					( Origin gPackager )
				)
				( attribute "LOCATION" "C4G20"
					( Origin gFrontEnd )
				)
				( attribute "MATERIAL" "X6S"
					( Origin gFrontEnd )
				)
				( attribute "PACK_TYPE" "0805LF"
					( Origin gFrontEnd )
				)
				( attribute "PART_NUMBER" "C95333-002"
					( Origin gFrontEnd )
				)
				( attribute "PHYS_PAGE" "229"
					( Origin gFrontEnd )
				)
				( attribute "ROOM" "VTT_GHJ_PWR_VR"
					( Origin gFrontEnd )
				)
				( attribute "ROT" "0"
					( Origin gFrontEnd )
				)
				( attribute "SEC" "1"
					( Origin gFrontEnd )
				)
				( attribute "SEC_TYPE" "0805LF"
					( Origin gFrontEnd )
				)
				( attribute "TOLERANCE" "20%"
					( Origin gFrontEnd )
				)
				( attribute "VALUE" "22UF"
					( Origin gFrontEnd )
				)
				( attribute "VER" "1"
					( Origin gFrontEnd )
				)
				( attribute "VOLTAGE" "4V"
					( Units "uVoltage" "V" 1.000000)
					( Origin gFrontEnd )
				)
				( attribute "XY" "(3925,1075)"
					( Origin gFrontEnd )
				)
				( attribute "CHIPS_PART_NAME" "CAP"
					( Origin gPackager )
				)
				( attribute "CDS_PART_NAME" "CAP_0805LF-22UF,4V,20%,X6S,C95A"
					( Origin gPackager )
				)
				( objectStatus "C4G20" )
				( pin "a"
					( attribute "PN" "1"
						( Origin gPackager )
					)
					( objectStatus "C4G20.1" )
				)
				( pin "b"
					( attribute "PN" "2"
						( Origin gPackager )
					)
					( objectStatus "C4G20.2" )
				)
			)
			( gate "@baseboard_fab2_lib.baseboard_fab2(sch_1):page229_i21"
				( attribute "BOM_COST" "MEM_VRD_VTT_GHJ"
					( Origin gFrontEnd )
				)
				( attribute "CDS_LIB" "mstr_discrete"
					( Origin gPackager )
				)
				( attribute "CDS_LOCATION" "C4G21"
					( Origin gPackager )
				)
				( attribute "CDS_SEC" "1"
					( Origin gPackager )
				)
				( attribute "LOCATION" "C4G21"
					( Origin gFrontEnd )
				)
				( attribute "MATERIAL" "X6S"
					( Origin gFrontEnd )
				)
				( attribute "PACK_TYPE" "0402"
					( Origin gFrontEnd )
				)
				( attribute "PART_NUMBER" "D97712-011"
					( Origin gFrontEnd )
				)
				( attribute "PHYS_PAGE" "229"
					( Origin gFrontEnd )
				)
				( attribute "ROOM" "VTT_GHJ_PWR_VR"
					( Origin gFrontEnd )
				)
				( attribute "ROT" "0"
					( Origin gFrontEnd )
				)
				( attribute "SEC" "1"
					( Origin gFrontEnd )
				)
				( attribute "SEC_TYPE" "0402"
					( Origin gFrontEnd )
				)
				( attribute "TOLERANCE" "10%"
					( Origin gFrontEnd )
				)
				( attribute "VALUE" "1.0UF"
					( Origin gFrontEnd )
				)
				( attribute "VER" "1"
					( Origin gFrontEnd )
				)
				( attribute "VOLTAGE" "16V"
					( Units "uVoltage" "V" 1.000000)
					( Origin gFrontEnd )
				)
				( attribute "XY" "(2275,850)"
					( Origin gFrontEnd )
				)
				( attribute "CHIPS_PART_NAME" "CAP"
					( Origin gPackager )
				)
				( attribute "CDS_PART_NAME" "CAP_0402-1.0UF,16V,10%,X6S,D97A"
					( Origin gPackager )
				)
				( objectStatus "C4G21" )
				( pin "a"
					( attribute "PN" "1"
						( Origin gPackager )
					)
					( objectStatus "C4G21.1" )
				)
				( pin "b"
					( attribute "PN" "2"
						( Origin gPackager )
					)
					( objectStatus "C4G21.2" )
				)
			)
			( gate "@baseboard_fab2_lib.baseboard_fab2(sch_1):page229_i24"
				( attribute "BOM_COST" "MEM_VRD_VTT_GHJ"
					( Origin gFrontEnd )
				)
				( attribute "CDS_LIB" "mstr_vreg"
					( Origin gPackager )
				)
				( attribute "CDS_LMAN_SYM_OUTLINE" "-250,350,250,-350"
					( Origin gPackager )
				)
				( attribute "CDS_LOCATION" "EU4G2"
					( Origin gPackager )
				)
				( attribute "CDS_SEC" "1"
					( Origin gPackager )
				)
				( attribute "LOCATION" "EU4G2"
					( Origin gFrontEnd )
				)
				( attribute "MATERIAL" "IC"
					( Origin gFrontEnd )
				)
				( attribute "PACK_TYPE" "DFN"
					( Origin gFrontEnd )
				)
				( attribute "PART_NUMBER" "H55101-001"
					( Origin gFrontEnd )
				)
				( attribute "PHYS_PAGE" "229"
					( Origin gFrontEnd )
				)
				( attribute "ROOM" "VTT_GHJ_PWR_VR"
					( Origin gFrontEnd )
				)
				( attribute "ROT" "0"
					( Origin gFrontEnd )
				)
				( attribute "SEC" "1"
					( Origin gFrontEnd )
				)
				( attribute "SEC_TYPE" "DFN"
					( Origin gFrontEnd )
				)
				( attribute "VER" "1"
					( Origin gFrontEnd )
				)
				( attribute "XY" "(1500,1075)"
					( Origin gFrontEnd )
				)
				( attribute "CHIPS_PART_NAME" "MIC5166"
					( Origin gPackager )
				)
				( attribute "CDS_PART_NAME" "MIC5166_DFN-IC,H55101-001"
					( Origin gPackager )
				)
				( objectStatus "EU4G2" )
				( pin "agnd"
					( attribute "PN" "3"
						( Origin gPackager )
					)
					( objectStatus "EU4G2.3" )
				)
				( pin "bias"
					( attribute "PN" "2"
						( Origin gPackager )
					)
					( objectStatus "EU4G2.2" )
				)
				( pin "en"
					( attribute "PN" "7"
						( Origin gPackager )
					)
					( objectStatus "EU4G2.7" )
				)
				( pin "pg"
					( attribute "PN" "5"
						( Origin gPackager )
					)
					( objectStatus "EU4G2.5" )
				)
				( pin "pgnd"
					( attribute "PN" "8"
						( Origin gPackager )
					)
					( objectStatus "EU4G2.8" )
				)
				( pin "sns"
					( attribute "PN" "6"
						( Origin gPackager )
					)
					( objectStatus "EU4G2.6" )
				)
				( pin "thpad"
					( attribute "PN" "11"
						( Origin gPackager )
					)
					( objectStatus "EU4G2.11" )
				)
				( pin "vddq"
					( attribute "PN" "4"
						( Origin gPackager )
					)
					( objectStatus "EU4G2.4" )
				)
				( pin "vin"
					( attribute "PN" "10"
						( Origin gPackager )
					)
					( objectStatus "EU4G2.10" )
				)
				( pin "vref"
					( attribute "PN" "1"
						( Origin gPackager )
					)
					( objectStatus "EU4G2.1" )
				)
				( pin "vtt"
					( attribute "PN" "9"
						( Origin gPackager )
					)
					( objectStatus "EU4G2.9" )
				)
			)
			( gate "@baseboard_fab2_lib.baseboard_fab2(sch_1):page229_i25"
				( attribute "BOM_COST" "MEM_VRD_VTT_GHJ"
					( Origin gFrontEnd )
				)
				( attribute "CDS_LIB" "mstr_discrete"
					( Origin gPackager )
				)
				( attribute "CDS_LOCATION" "C6U14"
					( Origin gPackager )
				)
				( attribute "CDS_SEC" "1"
					( Origin gPackager )
				)
				( attribute "LOCATION" "C6U14"
					( Origin gFrontEnd )
				)
				( attribute "MATERIAL" "X6S"
					( Origin gFrontEnd )
				)
				( attribute "PACK_TYPE" "0603LF"
					( Origin gFrontEnd )
				)
				( attribute "PART_NUMBER" "E15431-001"
					( Origin gFrontEnd )
				)
				( attribute "PHYS_PAGE" "229"
					( Origin gFrontEnd )
				)
				( attribute "ROOM" "VTT_GHJ_PWR_VR"
					( Origin gFrontEnd )
				)
				( attribute "ROT" "0"
					( Origin gFrontEnd )
				)
				( attribute "SEC" "1"
					( Origin gFrontEnd )
				)
				( attribute "SEC_TYPE" "0603LF"
					( Origin gFrontEnd )
				)
				( attribute "TOLERANCE" "20%"
					( Origin gFrontEnd )
				)
				( attribute "VALUE" "10UF"
					( Origin gFrontEnd )
				)
				( attribute "VER" "1"
					( Origin gFrontEnd )
				)
				( attribute "VOLTAGE" "4V"
					( Units "uVoltage" "V" 1.000000)
					( Origin gFrontEnd )
				)
				( attribute "XY" "(425,2375)"
					( Origin gFrontEnd )
				)
				( attribute "CHIPS_PART_NAME" "CAP"
					( Origin gPackager )
				)
				( attribute "CDS_PART_NAME" "CAP_0603LF-10UF,4V,20%,X6S,E15A"
					( Origin gPackager )
				)
				( objectStatus "C6U14" )
				( pin "a"
					( attribute "PN" "1"
						( Origin gPackager )
					)
					( objectStatus "C6U14.1" )
				)
				( pin "b"
					( attribute "PN" "2"
						( Origin gPackager )
					)
					( objectStatus "C6U14.2" )
				)
			)
			( gate "@baseboard_fab2_lib.baseboard_fab2(sch_1):page229_i27"
				( attribute "BOM_COST" "MEM_VRD_VTT_GHJ"
					( Origin gFrontEnd )
				)
				( attribute "CDS_LIB" "mstr_discrete"
					( Origin gPackager )
				)
				( attribute "CDS_LOCATION" "C4G18"
					( Origin gPackager )
				)
				( attribute "CDS_SEC" "1"
					( Origin gPackager )
				)
				( attribute "LOCATION" "C4G18"
					( Origin gFrontEnd )
				)
				( attribute "MATERIAL" "X6S"
					( Origin gFrontEnd )
				)
				( attribute "PACK_TYPE" "0402"
					( Origin gFrontEnd )
				)
				( attribute "PART_NUMBER" "D97712-011"
					( Origin gFrontEnd )
				)
				( attribute "PHYS_PAGE" "229"
					( Origin gFrontEnd )
				)
				( attribute "ROOM" "VTT_GHJ_PWR_VR"
					( Origin gFrontEnd )
				)
				( attribute "ROT" "0"
					( Origin gFrontEnd )
				)
				( attribute "SEC" "1"
					( Origin gFrontEnd )
				)
				( attribute "SEC_TYPE" "0402"
					( Origin gFrontEnd )
				)
				( attribute "TOLERANCE" "10%"
					( Origin gFrontEnd )
				)
				( attribute "VALUE" "1.0UF"
					( Origin gFrontEnd )
				)
				( attribute "VER" "1"
					( Origin gFrontEnd )
				)
				( attribute "VOLTAGE" "16V"
					( Units "uVoltage" "V" 1.000000)
					( Origin gFrontEnd )
				)
				( attribute "XY" "(425,1500)"
					( Origin gFrontEnd )
				)
				( attribute "CHIPS_PART_NAME" "CAP"
					( Origin gPackager )
				)
				( attribute "CDS_PART_NAME" "CAP_0402-1.0UF,16V,10%,X6S,D97A"
					( Origin gPackager )
				)
				( objectStatus "C4G18" )
				( pin "a"
					( attribute "PN" "1"
						( Origin gPackager )
					)
					( objectStatus "C4G18.1" )
				)
				( pin "b"
					( attribute "PN" "2"
						( Origin gPackager )
					)
					( objectStatus "C4G18.2" )
				)
			)
			( gate "@baseboard_fab2_lib.baseboard_fab2(sch_1):page229_i29"
				( attribute "BOM_COST" "MEM_VRD_VTT_GHJ"
					( Origin gFrontEnd )
				)
				( attribute "CDS_LIB" "mstr_discrete"
					( Origin gPackager )
				)
				( attribute "CDS_LOCATION" "C6U13"
					( Origin gPackager )
				)
				( attribute "CDS_SEC" "1"
					( Origin gPackager )
				)
				( attribute "LOCATION" "C6U13"
					( Origin gFrontEnd )
				)
				( attribute "MATERIAL" "X6S"
					( Origin gFrontEnd )
				)
				( attribute "PACK_TYPE" "0603LF"
					( Origin gFrontEnd )
				)
				( attribute "PART_NUMBER" "E15431-001"
					( Origin gFrontEnd )
				)
				( attribute "PHYS_PAGE" "229"
					( Origin gFrontEnd )
				)
				( attribute "ROOM" "VTT_GHJ_PWR_VR"
					( Origin gFrontEnd )
				)
				( attribute "ROT" "0"
					( Origin gFrontEnd )
				)
				( attribute "SEC" "1"
					( Origin gFrontEnd )
				)
				( attribute "SEC_TYPE" "0603LF"
					( Origin gFrontEnd )
				)
				( attribute "TOLERANCE" "20%"
					( Origin gFrontEnd )
				)
				( attribute "VALUE" "10UF"
					( Origin gFrontEnd )
				)
				( attribute "VER" "1"
					( Origin gFrontEnd )
				)
				( attribute "VOLTAGE" "4V"
					( Units "uVoltage" "V" 1.000000)
					( Origin gFrontEnd )
				)
				( attribute "XY" "(0,2350)"
					( Origin gFrontEnd )
				)
				( attribute "CHIPS_PART_NAME" "CAP"
					( Origin gPackager )
				)
				( attribute "CDS_PART_NAME" "CAP_0603LF-10UF,4V,20%,X6S,E15A"
					( Origin gPackager )
				)
				( objectStatus "C6U13" )
				( pin "a"
					( attribute "PN" "1"
						( Origin gPackager )
					)
					( objectStatus "C6U13.1" )
				)
				( pin "b"
					( attribute "PN" "2"
						( Origin gPackager )
					)
					( objectStatus "C6U13.2" )
				)
			)
			( gate "@baseboard_fab2_lib.baseboard_fab2(sch_1):page229_i32"
				( attribute "BOM_COST" "MEM_VRD_VTT_GHJ"
					( Origin gFrontEnd )
				)
				( attribute "CDS_LIB" "mstr_discrete"
					( Origin gPackager )
				)
				( attribute "CDS_LOCATION" "R6U7"
					( Origin gPackager )
				)
				( attribute "CDS_SEC" "1"
					( Origin gPackager )
				)
				( attribute "LOCATION" "R6U7"
					( Origin gFrontEnd )
				)
				( attribute "MATERIAL" "CHIP"
					( Origin gFrontEnd )
				)
				( attribute "PACK_TYPE" "0402"
					( Origin gFrontEnd )
				)
				( attribute "PART_NUMBER" "G21497-005"
					( Origin gFrontEnd )
				)
				( attribute "PHYS_PAGE" "229"
					( Origin gFrontEnd )
				)
				( attribute "ROOM" "VTT_GHJ_PWR_VR"
					( Origin gFrontEnd )
				)
				( attribute "ROT" "0"
					( Origin gFrontEnd )
				)
				( attribute "SEC" "1"
					( Origin gFrontEnd )
				)
				( attribute "SEC_TYPE" "0402"
					( Origin gFrontEnd )
				)
				( attribute "TOLERANCE" "5%"
					( Origin gFrontEnd )
				)
				( attribute "VALUE" "0.0"
					( Origin gFrontEnd )
				)
				( attribute "VER" "1"
					( Origin gFrontEnd )
				)
				( attribute "WATTAGE" "1/16W"
					( Origin gFrontEnd )
				)
				( attribute "XY" "(100,1775)"
					( Origin gFrontEnd )
				)
				( attribute "CHIPS_PART_NAME" "RES"
					( Origin gPackager )
				)
				( attribute "CDS_PART_NAME" "RES_0402-0.0,5%,1/16W,CHIP,G21A"
					( Origin gPackager )
				)
				( objectStatus "R6U7" )
				( pin "a"
					( attribute "PN" "1"
						( Origin gPackager )
					)
					( objectStatus "R6U7.1" )
				)
				( pin "b"
					( attribute "PN" "2"
						( Origin gPackager )
					)
					( objectStatus "R6U7.2" )
				)
			)
			( gate "@baseboard_fab2_lib.baseboard_fab2(sch_1):page229_i34"
				( attribute "BOM_COST" "MEM_VRD_VTT_GHJ"
					( Origin gFrontEnd )
				)
				( attribute "CDS_LIB" "mstr_discrete"
					( Origin gPackager )
				)
				( attribute "CDS_LOCATION" "R6U3"
					( Origin gPackager )
				)
				( attribute "CDS_SEC" "1"
					( Origin gPackager )
				)
				( attribute "LOCATION" "R6U3"
					( Origin gFrontEnd )
				)
				( attribute "MATERIAL" "EMPTY"
					( Origin gFrontEnd )
				)
				( attribute "PACK_TYPE" "0402"
					( Origin gFrontEnd )
				)
				( attribute "PART_NUMBER" "G21796-021"
					( Origin gFrontEnd )
				)
				( attribute "PHYS_PAGE" "229"
					( Origin gFrontEnd )
				)
				( attribute "ROOM" "VTT_GHJ_PWR_VR"
					( Origin gFrontEnd )
				)
				( attribute "ROT" "2"
					( Origin gFrontEnd )
				)
				( attribute "SEC" "1"
					( Origin gFrontEnd )
				)
				( attribute "SEC_TYPE" "0402"
					( Origin gFrontEnd )
				)
				( attribute "TOLERANCE" "1%"
					( Origin gFrontEnd )
				)
				( attribute "VALUE" "1.0M"
					( Origin gFrontEnd )
				)
				( attribute "VER" "2"
					( Origin gFrontEnd )
				)
				( attribute "WATTAGE" "1/16W"
					( Origin gFrontEnd )
				)
				( attribute "XY" "(-350,675)"
					( Origin gFrontEnd )
				)
				( attribute "CHIPS_PART_NAME" "RES"
					( Origin gPackager )
				)
				( attribute "CDS_PART_NAME" "RES_0402-1.0M,1%,1/16W,EMPTY,GA"
					( Origin gPackager )
				)
				( objectStatus "R6U3" )
				( pin "a"
					( attribute "PN" "1"
						( Origin gPackager )
					)
					( objectStatus "R6U3.1" )
				)
				( pin "b"
					( attribute "PN" "2"
						( Origin gPackager )
					)
					( objectStatus "R6U3.2" )
				)
			)
			( gate "@baseboard_fab2_lib.baseboard_fab2(sch_1):page229_i35"
				( attribute "BOM_COST" "MEM_VRD_VTT_GHJ"
					( Origin gFrontEnd )
				)
				( attribute "CDS_LIB" "mstr_discrete"
					( Origin gPackager )
				)
				( attribute "CDS_LOCATION" "R4G16"
					( Origin gPackager )
				)
				( attribute "CDS_SEC" "1"
					( Origin gPackager )
				)
				( attribute "LOCATION" "R4G16"
					( Origin gFrontEnd )
				)
				( attribute "MATERIAL" "CHIP"
					( Origin gFrontEnd )
				)
				( attribute "PACK_TYPE" "0402"
					( Origin gFrontEnd )
				)
				( attribute "PART_NUMBER" "G21497-005"
					( Origin gFrontEnd )
				)
				( attribute "PHYS_PAGE" "229"
					( Origin gFrontEnd )
				)
				( attribute "ROOM" "VTT_GHJ_PWR_VR"
					( Origin gFrontEnd )
				)
				( attribute "ROT" "0"
					( Origin gFrontEnd )
				)
				( attribute "SEC" "1"
					( Origin gFrontEnd )
				)
				( attribute "SEC_TYPE" "0402"
					( Origin gFrontEnd )
				)
				( attribute "TOLERANCE" "5%"
					( Origin gFrontEnd )
				)
				( attribute "VALUE" "0.0"
					( Origin gFrontEnd )
				)
				( attribute "VER" "1"
					( Origin gFrontEnd )
				)
				( attribute "WATTAGE" "1/16W"
					( Origin gFrontEnd )
				)
				( attribute "XY" "(-575,150)"
					( Origin gFrontEnd )
				)
				( attribute "CHIPS_PART_NAME" "RES"
					( Origin gPackager )
				)
				( attribute "CDS_PART_NAME" "RES_0402-0.0,5%,1/16W,CHIP,G21A"
					( Origin gPackager )
				)
				( objectStatus "R4G16" )
				( pin "a"
					( attribute "PN" "1"
						( Origin gPackager )
					)
					( objectStatus "R4G16.1" )
				)
				( pin "b"
					( attribute "PN" "2"
						( Origin gPackager )
					)
					( objectStatus "R4G16.2" )
				)
			)
			( gate "@baseboard_fab2_lib.baseboard_fab2(sch_1):page229_i36"
				( attribute "BOM_COST" "MEM_VRD_VTT_GHJ"
					( Origin gFrontEnd )
				)
				( attribute "CDS_LIB" "mstr_discrete"
					( Origin gPackager )
				)
				( attribute "CDS_LOCATION" "C4G12"
					( Origin gPackager )
				)
				( attribute "CDS_SEC" "1"
					( Origin gPackager )
				)
				( attribute "LOCATION" "C4G12"
					( Origin gFrontEnd )
				)
				( attribute "MATERIAL" "EMPTY"
					( Origin gFrontEnd )
				)
				( attribute "PACK_TYPE" "0402LF"
					( Origin gFrontEnd )
				)
				( attribute "PART_NUMBER" "A36096-046"
					( Origin gFrontEnd )
				)
				( attribute "PHYS_PAGE" "229"
					( Origin gFrontEnd )
				)
				( attribute "ROOM" "VTT_GHJ_PWR_VR"
					( Origin gFrontEnd )
				)
				( attribute "ROT" "2"
					( Origin gFrontEnd )
				)
				( attribute "SEC" "1"
					( Origin gFrontEnd )
				)
				( attribute "SEC_TYPE" "0402LF"
					( Origin gFrontEnd )
				)
				( attribute "TOLERANCE" "10%"
					( Origin gFrontEnd )
				)
				( attribute "VALUE" "1000PF"
					( Origin gFrontEnd )
				)
				( attribute "VER" "1"
					( Origin gFrontEnd )
				)
				( attribute "VOLTAGE" "50V"
					( Units "uVoltage" "V" 1.000000)
					( Origin gFrontEnd )
				)
				( attribute "XY" "(-400,-375)"
					( Origin gFrontEnd )
				)
				( attribute "CHIPS_PART_NAME" "CAP"
					( Origin gPackager )
				)
				( attribute "CDS_PART_NAME" "CAP_0402LF-1000PF,50V,10%,EMPTA"
					( Origin gPackager )
				)
				( objectStatus "C4G12" )
				( pin "a"
					( attribute "PN" "1"
						( Origin gPackager )
					)
					( objectStatus "C4G12.1" )
				)
				( pin "b"
					( attribute "PN" "2"
						( Origin gPackager )
					)
					( objectStatus "C4G12.2" )
				)
			)
			( gate "@baseboard_fab2_lib.baseboard_fab2(sch_1):page229_i39"
				( attribute "BOM_COST" "MEM_VRD_VTT_GHJ"
					( Origin gFrontEnd )
				)
				( attribute "CDS_LIB" "mstr_discrete"
					( Origin gPackager )
				)
				( attribute "CDS_LOCATION" "R6U6"
					( Origin gPackager )
				)
				( attribute "CDS_SEC" "1"
					( Origin gPackager )
				)
				( attribute "LOCATION" "R6U6"
					( Origin gFrontEnd )
				)
				( attribute "MATERIAL" "CHIP"
					( Origin gFrontEnd )
				)
				( attribute "NO_XNET_CONNECTION" "1"
					( Origin gFrontEnd )
				)
				( attribute "PACK_TYPE" "0402"
					( Origin gFrontEnd )
				)
				( attribute "PART_NUMBER" "G21497-005"
					( Origin gFrontEnd )
				)
				( attribute "PHYS_PAGE" "229"
					( Origin gFrontEnd )
				)
				( attribute "ROOM" "VTT_GHJ_PWR_VR"
					( Origin gFrontEnd )
				)
				( attribute "ROT" "1"
					( Origin gFrontEnd )
				)
				( attribute "SEC" "1"
					( Origin gFrontEnd )
				)
				( attribute "SEC_TYPE" "0402"
					( Origin gFrontEnd )
				)
				( attribute "TOLERANCE" "5%"
					( Origin gFrontEnd )
				)
				( attribute "VALUE" "0.0"
					( Origin gFrontEnd )
				)
				( attribute "VER" "2"
					( Origin gFrontEnd )
				)
				( attribute "WATTAGE" "1/16W"
					( Origin gFrontEnd )
				)
				( attribute "XY" "(-775,1575)"
					( Origin gFrontEnd )
				)
				( attribute "CHIPS_PART_NAME" "RES"
					( Origin gPackager )
				)
				( attribute "CDS_PART_NAME" "RES_0402-0.0,5%,1/16W,CHIP,G21A"
					( Origin gPackager )
				)
				( objectStatus "R6U6" )
				( pin "a"
					( attribute "PN" "1"
						( Origin gPackager )
					)
					( objectStatus "R6U6.1" )
				)
				( pin "b"
					( attribute "PN" "2"
						( Origin gPackager )
					)
					( objectStatus "R6U6.2" )
				)
			)
			( gate "@baseboard_fab2_lib.baseboard_fab2(sch_1):page229_i46"
				( attribute "CDS_LIB" "mstr_discrete"
					( Origin gPackager )
				)
				( attribute "CDS_LOCATION" "C6U11"
					( Origin gPackager )
				)
				( attribute "CDS_SEC" "1"
					( Origin gPackager )
				)
				( attribute "LOCATION" "C6U11"
					( Origin gFrontEnd )
				)
				( attribute "MATERIAL" "X6S"
					( Origin gFrontEnd )
				)
				( attribute "PACK_TYPE" "0603"
					( Origin gFrontEnd )
				)
				( attribute "PART_NUMBER" "E15431-003"
					( Origin gFrontEnd )
				)
				( attribute "PHYS_PAGE" "229"
					( Origin gFrontEnd )
				)
				( attribute "ROOM" "VTT_GHJ_PWR_VR"
					( Origin gFrontEnd )
				)
				( attribute "ROT" "0"
					( Origin gFrontEnd )
				)
				( attribute "SEC" "1"
					( Origin gFrontEnd )
				)
				( attribute "SEC_TYPE" "0603"
					( Origin gFrontEnd )
				)
				( attribute "TOLERANCE" "10%"
					( Origin gFrontEnd )
				)
				( attribute "VALUE" "4.7UF"
					( Origin gFrontEnd )
				)
				( attribute "VER" "1"
					( Origin gFrontEnd )
				)
				( attribute "VOLTAGE" "6.3V"
					( Units "uVoltage" "V" 1.000000)
					( Origin gFrontEnd )
				)
				( attribute "XY" "(275,1000)"
					( Origin gFrontEnd )
				)
				( attribute "CHIPS_PART_NAME" "CAP"
					( Origin gPackager )
				)
				( attribute "CDS_PART_NAME" "CAP_0603-4.7UF,6.3V,10%,X6S,E1A"
					( Origin gPackager )
				)
				( objectStatus "C6U11" )
				( pin "a"
					( attribute "PN" "1"
						( Origin gPackager )
					)
					( objectStatus "C6U11.1" )
				)
				( pin "b"
					( attribute "PN" "2"
						( Origin gPackager )
					)
					( objectStatus "C6U11.2" )
				)
			)
			( gate "@baseboard_fab2_lib.baseboard_fab2(sch_1):page229_i47"
				( attribute "CDS_LIB" "dev_discrete"
					( Origin gPackager )
				)
				( attribute "CDS_LOCATION" "C2F2"
					( Origin gPackager )
				)
				( attribute "CDS_SEC" "1"
					( Origin gPackager )
				)
				( attribute "LOCATION" "C2F2"
					( Origin gFrontEnd )
				)
				( attribute "MATERIAL" "X5R"
					( Origin gFrontEnd )
				)
				( attribute "PACK_TYPE" "0603V"
					( Origin gFrontEnd )
				)
				( attribute "PART_NUMBER" "602433-106"
					( Origin gFrontEnd )
				)
				( attribute "PHYS_PAGE" "229"
					( Origin gFrontEnd )
				)
				( attribute "ROT" "0"
					( Origin gFrontEnd )
				)
				( attribute "SEC" "1"
					( Origin gFrontEnd )
				)
				( attribute "SEC_TYPE" "0603V"
					( Origin gFrontEnd )
				)
				( attribute "TOLERANCE" "20%"
					( Origin gFrontEnd )
				)
				( attribute "VALUE" "47UF"
					( Origin gFrontEnd )
				)
				( attribute "VER" "1"
					( Origin gFrontEnd )
				)
				( attribute "VOLTAGE" "4V"
					( Units "uVoltage" "V" 1.000000)
					( Origin gFrontEnd )
				)
				( attribute "XY" "(3475,3375)"
					( Origin gFrontEnd )
				)
				( attribute "CHIPS_PART_NAME" "CAP_A"
					( Origin gPackager )
				)
				( attribute "CDS_PART_NAME" "CAP_A_0603V-47UF,4V,20%,X5R,60A"
					( Origin gPackager )
				)
				( objectStatus "C2F2" )
				( pin "a"
					( attribute "PN" "1"
						( Origin gPackager )
					)
					( objectStatus "C2F2.1" )
				)
				( pin "b"
					( attribute "PN" "2"
						( Origin gPackager )
					)
					( objectStatus "C2F2.2" )
				)
			)
			( gate "@baseboard_fab2_lib.baseboard_fab2(sch_1):page229_i48"
				( attribute "CDS_LIB" "dev_discrete"
					( Origin gPackager )
				)
				( attribute "CDS_LOCATION" "C8T3"
					( Origin gPackager )
				)
				( attribute "CDS_SEC" "1"
					( Origin gPackager )
				)
				( attribute "LOCATION" "C8T3"
					( Origin gFrontEnd )
				)
				( attribute "MATERIAL" "X5R"
					( Origin gFrontEnd )
				)
				( attribute "PACK_TYPE" "0603V"
					( Origin gFrontEnd )
				)
				( attribute "PART_NUMBER" "602433-106"
					( Origin gFrontEnd )
				)
				( attribute "PHYS_PAGE" "229"
					( Origin gFrontEnd )
				)
				( attribute "ROT" "0"
					( Origin gFrontEnd )
				)
				( attribute "SEC" "1"
					( Origin gFrontEnd )
				)
				( attribute "SEC_TYPE" "0603V"
					( Origin gFrontEnd )
				)
				( attribute "TOLERANCE" "20%"
					( Origin gFrontEnd )
				)
				( attribute "VALUE" "47UF"
					( Origin gFrontEnd )
				)
				( attribute "VER" "1"
					( Origin gFrontEnd )
				)
				( attribute "VOLTAGE" "4V"
					( Units "uVoltage" "V" 1.000000)
					( Origin gFrontEnd )
				)
				( attribute "XY" "(3825,3375)"
					( Origin gFrontEnd )
				)
				( attribute "CHIPS_PART_NAME" "CAP_A"
					( Origin gPackager )
				)
				( attribute "CDS_PART_NAME" "CAP_A_0603V-47UF,4V,20%,X5R,60A"
					( Origin gPackager )
				)
				( objectStatus "C8T3" )
				( pin "a"
					( attribute "PN" "1"
						( Origin gPackager )
					)
					( objectStatus "C8T3.1" )
				)
				( pin "b"
					( attribute "PN" "2"
						( Origin gPackager )
					)
					( objectStatus "C8T3.2" )
				)
			)
			( gate "@baseboard_fab2_lib.baseboard_fab2(sch_1):page229_i49"
				( attribute "CDS_LIB" "dev_discrete"
					( Origin gPackager )
				)
				( attribute "CDS_LOCATION" "C8U10"
					( Origin gPackager )
				)
				( attribute "CDS_SEC" "1"
					( Origin gPackager )
				)
				( attribute "LOCATION" "C8U10"
					( Origin gFrontEnd )
				)
				( attribute "MATERIAL" "X5R"
					( Origin gFrontEnd )
				)
				( attribute "PACK_TYPE" "0603V"
					( Origin gFrontEnd )
				)
				( attribute "PART_NUMBER" "602433-106"
					( Origin gFrontEnd )
				)
				( attribute "PHYS_PAGE" "229"
					( Origin gFrontEnd )
				)
				( attribute "ROT" "0"
					( Origin gFrontEnd )
				)
				( attribute "SEC" "1"
					( Origin gFrontEnd )
				)
				( attribute "SEC_TYPE" "0603V"
					( Origin gFrontEnd )
				)
				( attribute "TOLERANCE" "20%"
					( Origin gFrontEnd )
				)
				( attribute "VALUE" "47UF"
					( Origin gFrontEnd )
				)
				( attribute "VER" "1"
					( Origin gFrontEnd )
				)
				( attribute "VOLTAGE" "4V"
					( Units "uVoltage" "V" 1.000000)
					( Origin gFrontEnd )
				)
				( attribute "XY" "(4225,3375)"
					( Origin gFrontEnd )
				)
				( attribute "CHIPS_PART_NAME" "CAP_A"
					( Origin gPackager )
				)
				( attribute "CDS_PART_NAME" "CAP_A_0603V-47UF,4V,20%,X5R,60A"
					( Origin gPackager )
				)
				( objectStatus "C8U10" )
				( pin "a"
					( attribute "PN" "1"
						( Origin gPackager )
					)
					( objectStatus "C8U10.1" )
				)
				( pin "b"
					( attribute "PN" "2"
						( Origin gPackager )
					)
					( objectStatus "C8U10.2" )
				)
			)
			( gate "@baseboard_fab2_lib.baseboard_fab2(sch_1):page229_i51"
				( attribute "CDS_LIB" "mstr_discrete"
					( Origin gPackager )
				)
				( attribute "CDS_LOCATION" "R4G15"
					( Origin gPackager )
				)
				( attribute "CDS_SEC" "1"
					( Origin gPackager )
				)
				( attribute "LOCATION" "R4G15"
					( Origin gFrontEnd )
				)
				( attribute "MATERIAL" "CHIP"
					( Origin gFrontEnd )
				)
				( attribute "PACK_TYPE" "0402"
					( Origin gFrontEnd )
				)
				( attribute "PART_NUMBER" "G21796-074"
					( Origin gFrontEnd )
				)
				( attribute "PHYS_PAGE" "229"
					( Origin gFrontEnd )
				)
				( attribute "ROT" "0"
					( Origin gFrontEnd )
				)
				( attribute "SEC" "1"
					( Origin gFrontEnd )
				)
				( attribute "SEC_TYPE" "0402"
					( Origin gFrontEnd )
				)
				( attribute "TOLERANCE" "1%"
					( Origin gFrontEnd )
				)
				( attribute "VALUE" "33.2"
					( Origin gFrontEnd )
				)
				( attribute "VER" "1"
					( Origin gFrontEnd )
				)
				( attribute "WATTAGE" "1/16W"
					( Origin gFrontEnd )
				)
				( attribute "XY" "(4025,1825)"
					( Origin gFrontEnd )
				)
				( attribute "CHIPS_PART_NAME" "RES"
					( Origin gPackager )
				)
				( attribute "CDS_PART_NAME" "RES_0402-33.2,1%,1/16W,CHIP,G2A"
					( Origin gPackager )
				)
				( objectStatus "R4G15" )
				( pin "a"
					( attribute "PN" "1"
						( Origin gPackager )
					)
					( objectStatus "R4G15.1" )
				)
				( pin "b"
					( attribute "PN" "2"
						( Origin gPackager )
					)
					( objectStatus "R4G15.2" )
				)
			)
			( gate "@baseboard_fab2_lib.baseboard_fab2(sch_1):page229_i52"
				( attribute "CDS_LIB" "mstr_discrete"
					( Origin gPackager )
				)
				( attribute "CDS_LOCATION" "R6U8"
					( Origin gPackager )
				)
				( attribute "CDS_SEC" "1"
					( Origin gPackager )
				)
				( attribute "LOCATION" "R6U8"
					( Origin gFrontEnd )
				)
				( attribute "MATERIAL" "CHIP"
					( Origin gFrontEnd )
				)
				( attribute "PACK_TYPE" "0402"
					( Origin gFrontEnd )
				)
				( attribute "PART_NUMBER" "G21796-208"
					( Origin gFrontEnd )
				)
				( attribute "PHYS_PAGE" "229"
					( Origin gFrontEnd )
				)
				( attribute "ROT" "1"
					( Origin gFrontEnd )
				)
				( attribute "SEC" "1"
					( Origin gPackager )
				)
				( attribute "TOLERANCE" "1.0%"
					( Origin gFrontEnd )
				)
				( attribute "VALUE" "51.1"
					( Origin gFrontEnd )
				)
				( attribute "VER" "1"
					( Origin gFrontEnd )
				)
				( attribute "WATTAGE" "1/16W"
					( Origin gFrontEnd )
				)
				( attribute "XY" "(4775,1000)"
					( Origin gFrontEnd )
				)
				( attribute "CHIPS_PART_NAME" "RES"
					( Origin gPackager )
				)
				( attribute "CDS_PART_NAME" "RES_0402-51.1,1.0%,1/16W,CHIP,A"
					( Origin gPackager )
				)
				( objectStatus "R6U8" )
				( pin "a"
					( attribute "PN" "1"
						( Origin gPackager )
					)
					( objectStatus "R6U8.1" )
				)
				( pin "b"
					( attribute "PN" "2"
						( Origin gPackager )
					)
					( objectStatus "R6U8.2" )
				)
			)
			( gate "@baseboard_fab2_lib.baseboard_fab2(sch_1):page229_i53"
				( attribute "CDS_LIB" "mstr_misc"
					( Origin gPackager )
				)
				( attribute "CDS_LOCATION" "SH8U1"
					( Origin gPackager )
				)
				( attribute "CDS_SEC" "1"
					( Origin gPackager )
				)
				( attribute "LOCATION" "SH8U1"
					( Origin gFrontEnd )
				)
				( attribute "MATERIAL" "EMPTY"
					( Origin gFrontEnd )
				)
				( attribute "PACK_TYPE" "SH0201"
					( Origin gFrontEnd )
				)
				( attribute "PART_NUMBER" "N_A"
					( Origin gFrontEnd )
				)
				( attribute "PHYS_PAGE" "229"
					( Origin gFrontEnd )
				)
				( attribute "PIN_SHORT" "A:B"
					( Origin gFrontEnd )
				)
				( attribute "ROT" "0"
					( Origin gFrontEnd )
				)
				( attribute "SEC" "1"
					( Origin gFrontEnd )
				)
				( attribute "SEC_TYPE" "SH0201"
					( Origin gFrontEnd )
				)
				( attribute "VER" "1"
					( Origin gFrontEnd )
				)
				( attribute "XY" "(4925,25)"
					( Origin gFrontEnd )
				)
				( attribute "CHIPS_PART_NAME" "SHUNT"
					( Origin gPackager )
				)
				( attribute "CDS_PART_NAME" "SHUNT_SH0201-EMPTY,N_A"
					( Origin gPackager )
				)
				( objectStatus "SH8U1" )
				( pin "a"
					( attribute "PN" "1"
						( Origin gPackager )
					)
					( objectStatus "SH8U1.1" )
				)
				( pin "b"
					( attribute "PN" "2"
						( Origin gPackager )
					)
					( objectStatus "SH8U1.2" )
				)
			)
			( gate "@baseboard_fab2_lib.baseboard_fab2(sch_1):page230_i16"
				( attribute "BOM_COST" "MEM_VRD_VTT_KLM"
					( Origin gFrontEnd )
				)
				( attribute "CDS_LIB" "mstr_discrete"
					( Origin gPackager )
				)
				( attribute "CDS_LOCATION" "C4A3"
					( Origin gPackager )
				)
				( attribute "CDS_SEC" "1"
					( Origin gPackager )
				)
				( attribute "LOCATION" "C4A3"
					( Origin gFrontEnd )
				)
				( attribute "MATERIAL" "X7R"
					( Origin gFrontEnd )
				)
				( attribute "PACK_TYPE" "0402LF"
					( Origin gFrontEnd )
				)
				( attribute "PART_NUMBER" "A36096-046"
					( Origin gFrontEnd )
				)
				( attribute "PHYS_PAGE" "230"
					( Origin gFrontEnd )
				)
				( attribute "ROOM" "VTT_KLM_PWR_VR"
					( Origin gFrontEnd )
				)
				( attribute "ROT" "2"
					( Origin gFrontEnd )
				)
				( attribute "SEC" "1"
					( Origin gFrontEnd )
				)
				( attribute "SEC_TYPE" "0402LF"
					( Origin gFrontEnd )
				)
				( attribute "TOLERANCE" "10%"
					( Origin gFrontEnd )
				)
				( attribute "VALUE" "1000PF"
					( Origin gFrontEnd )
				)
				( attribute "VER" "1"
					( Origin gFrontEnd )
				)
				( attribute "VOLTAGE" "50V"
					( Units "uVoltage" "V" 1.000000)
					( Origin gFrontEnd )
				)
				( attribute "XY" "(3875,1650)"
					( Origin gFrontEnd )
				)
				( attribute "CHIPS_PART_NAME" "CAP"
					( Origin gPackager )
				)
				( attribute "CDS_PART_NAME" "CAP_0402LF-1000PF,50V,10%,X7R,A"
					( Origin gPackager )
				)
				( objectStatus "C4A3" )
				( pin "a"
					( attribute "PN" "1"
						( Origin gPackager )
					)
					( objectStatus "C4A3.1" )
				)
				( pin "b"
					( attribute "PN" "2"
						( Origin gPackager )
					)
					( objectStatus "C4A3.2" )
				)
			)
			( gate "@baseboard_fab2_lib.baseboard_fab2(sch_1):page230_i17"
				( attribute "BOM_COST" "MEM_VRD_VTT_KLM"
					( Origin gFrontEnd )
				)
				( attribute "CDS_LIB" "mstr_discrete"
					( Origin gPackager )
				)
				( attribute "CDS_LOCATION" "R4A5"
					( Origin gPackager )
				)
				( attribute "CDS_SEC" "1"
					( Origin gPackager )
				)
				( attribute "LOCATION" "R4A5"
					( Origin gFrontEnd )
				)
				( attribute "MATERIAL" "CHIP"
					( Origin gFrontEnd )
				)
				( attribute "PACK_TYPE" "0402"
					( Origin gFrontEnd )
				)
				( attribute "PART_NUMBER" "G21796-016"
					( Origin gFrontEnd )
				)
				( attribute "PHYS_PAGE" "230"
					( Origin gFrontEnd )
				)
				( attribute "ROOM" "VTT_KLM_PWR_VR"
					( Origin gFrontEnd )
				)
				( attribute "ROT" "2"
					( Origin gFrontEnd )
				)
				( attribute "SEC" "1"
					( Origin gFrontEnd )
				)
				( attribute "SEC_TYPE" "0402"
					( Origin gFrontEnd )
				)
				( attribute "TOLERANCE" "1%"
					( Origin gFrontEnd )
				)
				( attribute "VALUE" "10.0K"
					( Origin gFrontEnd )
				)
				( attribute "VER" "2"
					( Origin gFrontEnd )
				)
				( attribute "WATTAGE" "1/16W"
					( Origin gFrontEnd )
				)
				( attribute "XY" "(3500,2025)"
					( Origin gFrontEnd )
				)
				( attribute "CHIPS_PART_NAME" "RES"
					( Origin gPackager )
				)
				( attribute "CDS_PART_NAME" "RES_0402-10.0K,1%,1/16W,CHIP,GA"
					( Origin gPackager )
				)
				( objectStatus "R4A5" )
				( pin "a"
					( attribute "PN" "1"
						( Origin gPackager )
					)
					( objectStatus "R4A5.1" )
				)
				( pin "b"
					( attribute "PN" "2"
						( Origin gPackager )
					)
					( objectStatus "R4A5.2" )
				)
			)
			( gate "@baseboard_fab2_lib.baseboard_fab2(sch_1):page230_i18"
				( attribute "BOM_COST" "MEM_VRD_VTT_KLM"
					( Origin gFrontEnd )
				)
				( attribute "CDS_LIB" "mstr_discrete"
					( Origin gPackager )
				)
				( attribute "CDS_LOCATION" "C4A13"
					( Origin gPackager )
				)
				( attribute "CDS_SEC" "1"
					( Origin gPackager )
				)
				( attribute "LOCATION" "C4A13"
					( Origin gFrontEnd )
				)
				( attribute "MATERIAL" "X6S"
					( Origin gFrontEnd )
				)
				( attribute "PACK_TYPE" "0805LF"
					( Origin gFrontEnd )
				)
				( attribute "PART_NUMBER" "C95333-002"
					( Origin gFrontEnd )
				)
				( attribute "PHYS_PAGE" "230"
					( Origin gFrontEnd )
				)
				( attribute "ROOM" "VTT_KLM_PWR_VR"
					( Origin gFrontEnd )
				)
				( attribute "ROT" "0"
					( Origin gFrontEnd )
				)
				( attribute "SEC" "1"
					( Origin gFrontEnd )
				)
				( attribute "SEC_TYPE" "0805LF"
					( Origin gFrontEnd )
				)
				( attribute "TOLERANCE" "20%"
					( Origin gFrontEnd )
				)
				( attribute "VALUE" "22UF"
					( Origin gFrontEnd )
				)
				( attribute "VER" "1"
					( Origin gFrontEnd )
				)
				( attribute "VOLTAGE" "4V"
					( Units "uVoltage" "V" 1.000000)
					( Origin gFrontEnd )
				)
				( attribute "XY" "(4000,1050)"
					( Origin gFrontEnd )
				)
				( attribute "CHIPS_PART_NAME" "CAP"
					( Origin gPackager )
				)
				( attribute "CDS_PART_NAME" "CAP_0805LF-22UF,4V,20%,X6S,C95A"
					( Origin gPackager )
				)
				( objectStatus "C4A13" )
				( pin "a"
					( attribute "PN" "1"
						( Origin gPackager )
					)
					( objectStatus "C4A13.1" )
				)
				( pin "b"
					( attribute "PN" "2"
						( Origin gPackager )
					)
					( objectStatus "C4A13.2" )
				)
			)
			( gate "@baseboard_fab2_lib.baseboard_fab2(sch_1):page230_i21"
				( attribute "BOM_COST" "MEM_VRD_VTT_KLM"
					( Origin gFrontEnd )
				)
				( attribute "CDS_LIB" "mstr_discrete"
					( Origin gPackager )
				)
				( attribute "CDS_LOCATION" "C4A14"
					( Origin gPackager )
				)
				( attribute "CDS_SEC" "1"
					( Origin gPackager )
				)
				( attribute "LOCATION" "C4A14"
					( Origin gFrontEnd )
				)
				( attribute "MATERIAL" "X6S"
					( Origin gFrontEnd )
				)
				( attribute "PACK_TYPE" "0402"
					( Origin gFrontEnd )
				)
				( attribute "PART_NUMBER" "D97712-011"
					( Origin gFrontEnd )
				)
				( attribute "PHYS_PAGE" "230"
					( Origin gFrontEnd )
				)
				( attribute "ROOM" "VTT_KLM_PWR_VR"
					( Origin gFrontEnd )
				)
				( attribute "ROT" "0"
					( Origin gFrontEnd )
				)
				( attribute "SEC" "1"
					( Origin gFrontEnd )
				)
				( attribute "SEC_TYPE" "0402"
					( Origin gFrontEnd )
				)
				( attribute "TOLERANCE" "10%"
					( Origin gFrontEnd )
				)
				( attribute "VALUE" "1.0UF"
					( Origin gFrontEnd )
				)
				( attribute "VER" "1"
					( Origin gFrontEnd )
				)
				( attribute "VOLTAGE" "16V"
					( Units "uVoltage" "V" 1.000000)
					( Origin gFrontEnd )
				)
				( attribute "XY" "(2350,875)"
					( Origin gFrontEnd )
				)
				( attribute "CHIPS_PART_NAME" "CAP"
					( Origin gPackager )
				)
				( attribute "CDS_PART_NAME" "CAP_0402-1.0UF,16V,10%,X6S,D97A"
					( Origin gPackager )
				)
				( objectStatus "C4A14" )
				( pin "a"
					( attribute "PN" "1"
						( Origin gPackager )
					)
					( objectStatus "C4A14.1" )
				)
				( pin "b"
					( attribute "PN" "2"
						( Origin gPackager )
					)
					( objectStatus "C4A14.2" )
				)
			)
			( gate "@baseboard_fab2_lib.baseboard_fab2(sch_1):page230_i25"
				( attribute "BOM_COST" "MEM_VRD_VTT_KLM"
					( Origin gFrontEnd )
				)
				( attribute "CDS_LIB" "mstr_discrete"
					( Origin gPackager )
				)
				( attribute "CDS_LOCATION" "C4A15"
					( Origin gPackager )
				)
				( attribute "CDS_SEC" "1"
					( Origin gPackager )
				)
				( attribute "LOCATION" "C4A15"
					( Origin gFrontEnd )
				)
				( attribute "MATERIAL" "X6S"
					( Origin gFrontEnd )
				)
				( attribute "PACK_TYPE" "0603LF"
					( Origin gFrontEnd )
				)
				( attribute "PART_NUMBER" "E15431-001"
					( Origin gFrontEnd )
				)
				( attribute "PHYS_PAGE" "230"
					( Origin gFrontEnd )
				)
				( attribute "ROOM" "VTT_KLM_PWR_VR"
					( Origin gFrontEnd )
				)
				( attribute "ROT" "0"
					( Origin gFrontEnd )
				)
				( attribute "SEC" "1"
					( Origin gFrontEnd )
				)
				( attribute "SEC_TYPE" "0603LF"
					( Origin gFrontEnd )
				)
				( attribute "TOLERANCE" "20%"
					( Origin gFrontEnd )
				)
				( attribute "VALUE" "10UF"
					( Origin gFrontEnd )
				)
				( attribute "VER" "1"
					( Origin gFrontEnd )
				)
				( attribute "VOLTAGE" "4V"
					( Units "uVoltage" "V" 1.000000)
					( Origin gFrontEnd )
				)
				( attribute "XY" "(475,2400)"
					( Origin gFrontEnd )
				)
				( attribute "CHIPS_PART_NAME" "CAP"
					( Origin gPackager )
				)
				( attribute "CDS_PART_NAME" "CAP_0603LF-10UF,4V,20%,X6S,E15A"
					( Origin gPackager )
				)
				( objectStatus "C4A15" )
				( pin "a"
					( attribute "PN" "1"
						( Origin gPackager )
					)
					( objectStatus "C4A15.1" )
				)
				( pin "b"
					( attribute "PN" "2"
						( Origin gPackager )
					)
					( objectStatus "C4A15.2" )
				)
			)
			( gate "@baseboard_fab2_lib.baseboard_fab2(sch_1):page230_i26"
				( attribute "BOM_COST" "MEM_VRD_VTT_KLM"
					( Origin gFrontEnd )
				)
				( attribute "CDS_LIB" "mstr_discrete"
					( Origin gPackager )
				)
				( attribute "CDS_LOCATION" "C6L5"
					( Origin gPackager )
				)
				( attribute "CDS_SEC" "1"
					( Origin gPackager )
				)
				( attribute "LOCATION" "C6L5"
					( Origin gFrontEnd )
				)
				( attribute "MATERIAL" "X6S"
					( Origin gFrontEnd )
				)
				( attribute "PACK_TYPE" "0603LF"
					( Origin gFrontEnd )
				)
				( attribute "PART_NUMBER" "E15431-001"
					( Origin gFrontEnd )
				)
				( attribute "PHYS_PAGE" "230"
					( Origin gFrontEnd )
				)
				( attribute "ROOM" "VTT_KLM_PWR_VR"
					( Origin gFrontEnd )
				)
				( attribute "ROT" "0"
					( Origin gFrontEnd )
				)
				( attribute "SEC" "1"
					( Origin gFrontEnd )
				)
				( attribute "SEC_TYPE" "0603LF"
					( Origin gFrontEnd )
				)
				( attribute "TOLERANCE" "20%"
					( Origin gFrontEnd )
				)
				( attribute "VALUE" "10UF"
					( Origin gFrontEnd )
				)
				( attribute "VER" "1"
					( Origin gFrontEnd )
				)
				( attribute "VOLTAGE" "4V"
					( Units "uVoltage" "V" 1.000000)
					( Origin gFrontEnd )
				)
				( attribute "XY" "(50,2375)"
					( Origin gFrontEnd )
				)
				( attribute "CHIPS_PART_NAME" "CAP"
					( Origin gPackager )
				)
				( attribute "CDS_PART_NAME" "CAP_0603LF-10UF,4V,20%,X6S,E15A"
					( Origin gPackager )
				)
				( objectStatus "C6L5" )
				( pin "a"
					( attribute "PN" "1"
						( Origin gPackager )
					)
					( objectStatus "C6L5.1" )
				)
				( pin "b"
					( attribute "PN" "2"
						( Origin gPackager )
					)
					( objectStatus "C6L5.2" )
				)
			)
			( gate "@baseboard_fab2_lib.baseboard_fab2(sch_1):page230_i28"
				( attribute "BOM_COST" "MEM_VRD_VTT_KLM"
					( Origin gFrontEnd )
				)
				( attribute "CDS_LIB" "mstr_discrete"
					( Origin gPackager )
				)
				( attribute "CDS_LOCATION" "C4A8"
					( Origin gPackager )
				)
				( attribute "CDS_SEC" "1"
					( Origin gPackager )
				)
				( attribute "LOCATION" "C4A8"
					( Origin gFrontEnd )
				)
				( attribute "MATERIAL" "X6S"
					( Origin gFrontEnd )
				)
				( attribute "PACK_TYPE" "0402"
					( Origin gFrontEnd )
				)
				( attribute "PART_NUMBER" "D97712-011"
					( Origin gFrontEnd )
				)
				( attribute "PHYS_PAGE" "230"
					( Origin gFrontEnd )
				)
				( attribute "ROOM" "VTT_KLM_PWR_VR"
					( Origin gFrontEnd )
				)
				( attribute "ROT" "0"
					( Origin gFrontEnd )
				)
				( attribute "SEC" "1"
					( Origin gFrontEnd )
				)
				( attribute "SEC_TYPE" "0402"
					( Origin gFrontEnd )
				)
				( attribute "TOLERANCE" "10%"
					( Origin gFrontEnd )
				)
				( attribute "VALUE" "1.0UF"
					( Origin gFrontEnd )
				)
				( attribute "VER" "1"
					( Origin gFrontEnd )
				)
				( attribute "VOLTAGE" "16V"
					( Units "uVoltage" "V" 1.000000)
					( Origin gFrontEnd )
				)
				( attribute "XY" "(475,1525)"
					( Origin gFrontEnd )
				)
				( attribute "CHIPS_PART_NAME" "CAP"
					( Origin gPackager )
				)
				( attribute "CDS_PART_NAME" "CAP_0402-1.0UF,16V,10%,X6S,D97A"
					( Origin gPackager )
				)
				( objectStatus "C4A8" )
				( pin "a"
					( attribute "PN" "1"
						( Origin gPackager )
					)
					( objectStatus "C4A8.1" )
				)
				( pin "b"
					( attribute "PN" "2"
						( Origin gPackager )
					)
					( objectStatus "C4A8.2" )
				)
			)
			( gate "@baseboard_fab2_lib.baseboard_fab2(sch_1):page230_i30"
				( attribute "BOM_COST" "MEM_VRD_VTT_KLM"
					( Origin gFrontEnd )
				)
				( attribute "CDS_LIB" "mstr_discrete"
					( Origin gPackager )
				)
				( attribute "CDS_LOCATION" "R6L8"
					( Origin gPackager )
				)
				( attribute "CDS_SEC" "1"
					( Origin gPackager )
				)
				( attribute "LOCATION" "R6L8"
					( Origin gFrontEnd )
				)
				( attribute "MATERIAL" "CHIP"
					( Origin gFrontEnd )
				)
				( attribute "PACK_TYPE" "0402"
					( Origin gFrontEnd )
				)
				( attribute "PART_NUMBER" "G21497-005"
					( Origin gFrontEnd )
				)
				( attribute "PHYS_PAGE" "230"
					( Origin gFrontEnd )
				)
				( attribute "ROOM" "VTT_KLM_PWR_VR"
					( Origin gFrontEnd )
				)
				( attribute "ROT" "0"
					( Origin gFrontEnd )
				)
				( attribute "SEC" "1"
					( Origin gFrontEnd )
				)
				( attribute "SEC_TYPE" "0402"
					( Origin gFrontEnd )
				)
				( attribute "TOLERANCE" "5%"
					( Origin gFrontEnd )
				)
				( attribute "VALUE" "0.0"
					( Origin gFrontEnd )
				)
				( attribute "VER" "1"
					( Origin gFrontEnd )
				)
				( attribute "WATTAGE" "1/16W"
					( Origin gFrontEnd )
				)
				( attribute "XY" "(150,1775)"
					( Origin gFrontEnd )
				)
				( attribute "CHIPS_PART_NAME" "RES"
					( Origin gPackager )
				)
				( attribute "CDS_PART_NAME" "RES_0402-0.0,5%,1/16W,CHIP,G21A"
					( Origin gPackager )
				)
				( objectStatus "R6L8" )
				( pin "a"
					( attribute "PN" "1"
						( Origin gPackager )
					)
					( objectStatus "R6L8.1" )
				)
				( pin "b"
					( attribute "PN" "2"
						( Origin gPackager )
					)
					( objectStatus "R6L8.2" )
				)
			)
			( gate "@baseboard_fab2_lib.baseboard_fab2(sch_1):page230_i31"
				( attribute "BOM_COST" "MEM_VRD_VTT_KLM"
					( Origin gFrontEnd )
				)
				( attribute "CDS_LIB" "mstr_vreg"
					( Origin gPackager )
				)
				( attribute "CDS_LMAN_SYM_OUTLINE" "-250,350,250,-350"
					( Origin gPackager )
				)
				( attribute "CDS_LOCATION" "EU4A2"
					( Origin gPackager )
				)
				( attribute "CDS_SEC" "1"
					( Origin gPackager )
				)
				( attribute "LOCATION" "EU4A2"
					( Origin gFrontEnd )
				)
				( attribute "MATERIAL" "IC"
					( Origin gFrontEnd )
				)
				( attribute "PACK_TYPE" "DFN"
					( Origin gFrontEnd )
				)
				( attribute "PART_NUMBER" "H55101-001"
					( Origin gFrontEnd )
				)
				( attribute "PHYS_PAGE" "230"
					( Origin gFrontEnd )
				)
				( attribute "ROOM" "VTT_KLM_PWR_VR"
					( Origin gFrontEnd )
				)
				( attribute "ROT" "0"
					( Origin gFrontEnd )
				)
				( attribute "SEC" "1"
					( Origin gFrontEnd )
				)
				( attribute "SEC_TYPE" "DFN"
					( Origin gFrontEnd )
				)
				( attribute "VER" "1"
					( Origin gFrontEnd )
				)
				( attribute "XY" "(1575,1075)"
					( Origin gFrontEnd )
				)
				( attribute "CHIPS_PART_NAME" "MIC5166"
					( Origin gPackager )
				)
				( attribute "CDS_PART_NAME" "MIC5166_DFN-IC,H55101-001"
					( Origin gPackager )
				)
				( objectStatus "EU4A2" )
				( pin "agnd"
					( attribute "PN" "3"
						( Origin gPackager )
					)
					( objectStatus "EU4A2.3" )
				)
				( pin "bias"
					( attribute "PN" "2"
						( Origin gPackager )
					)
					( objectStatus "EU4A2.2" )
				)
				( pin "en"
					( attribute "PN" "7"
						( Origin gPackager )
					)
					( objectStatus "EU4A2.7" )
				)
				( pin "pg"
					( attribute "PN" "5"
						( Origin gPackager )
					)
					( objectStatus "EU4A2.5" )
				)
				( pin "pgnd"
					( attribute "PN" "8"
						( Origin gPackager )
					)
					( objectStatus "EU4A2.8" )
				)
				( pin "sns"
					( attribute "PN" "6"
						( Origin gPackager )
					)
					( objectStatus "EU4A2.6" )
				)
				( pin "thpad"
					( attribute "PN" "11"
						( Origin gPackager )
					)
					( objectStatus "EU4A2.11" )
				)
				( pin "vddq"
					( attribute "PN" "4"
						( Origin gPackager )
					)
					( objectStatus "EU4A2.4" )
				)
				( pin "vin"
					( attribute "PN" "10"
						( Origin gPackager )
					)
					( objectStatus "EU4A2.10" )
				)
				( pin "vref"
					( attribute "PN" "1"
						( Origin gPackager )
					)
					( objectStatus "EU4A2.1" )
				)
				( pin "vtt"
					( attribute "PN" "9"
						( Origin gPackager )
					)
					( objectStatus "EU4A2.9" )
				)
			)
			( gate "@baseboard_fab2_lib.baseboard_fab2(sch_1):page230_i34"
				( attribute "BOM_COST" "MEM_VRD_VTT_KLM"
					( Origin gFrontEnd )
				)
				( attribute "CDS_LIB" "mstr_discrete"
					( Origin gPackager )
				)
				( attribute "CDS_LOCATION" "R6L6"
					( Origin gPackager )
				)
				( attribute "CDS_SEC" "1"
					( Origin gPackager )
				)
				( attribute "LOCATION" "R6L6"
					( Origin gFrontEnd )
				)
				( attribute "MATERIAL" "CHIP"
					( Origin gFrontEnd )
				)
				( attribute "NO_XNET_CONNECTION" "1"
					( Origin gFrontEnd )
				)
				( attribute "PACK_TYPE" "0402"
					( Origin gFrontEnd )
				)
				( attribute "PART_NUMBER" "G21497-005"
					( Origin gFrontEnd )
				)
				( attribute "PHYS_PAGE" "230"
					( Origin gFrontEnd )
				)
				( attribute "ROOM" "VTT_KLM_PWR_VR"
					( Origin gFrontEnd )
				)
				( attribute "ROT" "1"
					( Origin gFrontEnd )
				)
				( attribute "SEC" "1"
					( Origin gFrontEnd )
				)
				( attribute "SEC_TYPE" "0402"
					( Origin gFrontEnd )
				)
				( attribute "TOLERANCE" "5%"
					( Origin gFrontEnd )
				)
				( attribute "VALUE" "0.0"
					( Origin gFrontEnd )
				)
				( attribute "VER" "2"
					( Origin gFrontEnd )
				)
				( attribute "WATTAGE" "1/16W"
					( Origin gFrontEnd )
				)
				( attribute "XY" "(-675,1575)"
					( Origin gFrontEnd )
				)
				( attribute "CHIPS_PART_NAME" "RES"
					( Origin gPackager )
				)
				( attribute "CDS_PART_NAME" "RES_0402-0.0,5%,1/16W,CHIP,G21A"
					( Origin gPackager )
				)
				( objectStatus "R6L6" )
				( pin "a"
					( attribute "PN" "1"
						( Origin gPackager )
					)
					( objectStatus "R6L6.1" )
				)
				( pin "b"
					( attribute "PN" "2"
						( Origin gPackager )
					)
					( objectStatus "R6L6.2" )
				)
			)
			( gate "@baseboard_fab2_lib.baseboard_fab2(sch_1):page230_i37"
				( attribute "BOM_COST" "MEM_VRD_VTT_KLM"
					( Origin gFrontEnd )
				)
				( attribute "CDS_LIB" "mstr_discrete"
					( Origin gPackager )
				)
				( attribute "CDS_LOCATION" "R6L5"
					( Origin gPackager )
				)
				( attribute "CDS_SEC" "1"
					( Origin gPackager )
				)
				( attribute "LOCATION" "R6L5"
					( Origin gFrontEnd )
				)
				( attribute "MATERIAL" "EMPTY"
					( Origin gFrontEnd )
				)
				( attribute "PACK_TYPE" "0402"
					( Origin gFrontEnd )
				)
				( attribute "PART_NUMBER" "G21796-021"
					( Origin gFrontEnd )
				)
				( attribute "PHYS_PAGE" "230"
					( Origin gFrontEnd )
				)
				( attribute "ROOM" "VTT_KLM_PWR_VR"
					( Origin gFrontEnd )
				)
				( attribute "ROT" "2"
					( Origin gFrontEnd )
				)
				( attribute "SEC" "1"
					( Origin gFrontEnd )
				)
				( attribute "SEC_TYPE" "0402"
					( Origin gFrontEnd )
				)
				( attribute "TOLERANCE" "1%"
					( Origin gFrontEnd )
				)
				( attribute "VALUE" "1.0M"
					( Origin gFrontEnd )
				)
				( attribute "VER" "2"
					( Origin gFrontEnd )
				)
				( attribute "WATTAGE" "1/16W"
					( Origin gFrontEnd )
				)
				( attribute "XY" "(-300,675)"
					( Origin gFrontEnd )
				)
				( attribute "CHIPS_PART_NAME" "RES"
					( Origin gPackager )
				)
				( attribute "CDS_PART_NAME" "RES_0402-1.0M,1%,1/16W,EMPTY,GA"
					( Origin gPackager )
				)
				( objectStatus "R6L5" )
				( pin "a"
					( attribute "PN" "1"
						( Origin gPackager )
					)
					( objectStatus "R6L5.1" )
				)
				( pin "b"
					( attribute "PN" "2"
						( Origin gPackager )
					)
					( objectStatus "R6L5.2" )
				)
			)
			( gate "@baseboard_fab2_lib.baseboard_fab2(sch_1):page230_i38"
				( attribute "BOM_COST" "MEM_VRD_VTT_KLM"
					( Origin gFrontEnd )
				)
				( attribute "CDS_LIB" "mstr_discrete"
					( Origin gPackager )
				)
				( attribute "CDS_LOCATION" "R4A3"
					( Origin gPackager )
				)
				( attribute "CDS_SEC" "1"
					( Origin gPackager )
				)
				( attribute "LOCATION" "R4A3"
					( Origin gFrontEnd )
				)
				( attribute "MATERIAL" "CHIP"
					( Origin gFrontEnd )
				)
				( attribute "PACK_TYPE" "0402"
					( Origin gFrontEnd )
				)
				( attribute "PART_NUMBER" "G21497-005"
					( Origin gFrontEnd )
				)
				( attribute "PHYS_PAGE" "230"
					( Origin gFrontEnd )
				)
				( attribute "ROOM" "VTT_KLM_PWR_VR"
					( Origin gFrontEnd )
				)
				( attribute "ROT" "0"
					( Origin gFrontEnd )
				)
				( attribute "SEC" "1"
					( Origin gFrontEnd )
				)
				( attribute "SEC_TYPE" "0402"
					( Origin gFrontEnd )
				)
				( attribute "TOLERANCE" "5%"
					( Origin gFrontEnd )
				)
				( attribute "VALUE" "0.0"
					( Origin gFrontEnd )
				)
				( attribute "VER" "1"
					( Origin gFrontEnd )
				)
				( attribute "WATTAGE" "1/16W"
					( Origin gFrontEnd )
				)
				( attribute "XY" "(-500,150)"
					( Origin gFrontEnd )
				)
				( attribute "CHIPS_PART_NAME" "RES"
					( Origin gPackager )
				)
				( attribute "CDS_PART_NAME" "RES_0402-0.0,5%,1/16W,CHIP,G21A"
					( Origin gPackager )
				)
				( objectStatus "R4A3" )
				( pin "a"
					( attribute "PN" "1"
						( Origin gPackager )
					)
					( objectStatus "R4A3.1" )
				)
				( pin "b"
					( attribute "PN" "2"
						( Origin gPackager )
					)
					( objectStatus "R4A3.2" )
				)
			)
			( gate "@baseboard_fab2_lib.baseboard_fab2(sch_1):page230_i39"
				( attribute "BOM_COST" "MEM_VRD_VTT_KLM"
					( Origin gFrontEnd )
				)
				( attribute "CDS_LIB" "mstr_discrete"
					( Origin gPackager )
				)
				( attribute "CDS_LOCATION" "C4A6"
					( Origin gPackager )
				)
				( attribute "CDS_SEC" "1"
					( Origin gPackager )
				)
				( attribute "LOCATION" "C4A6"
					( Origin gFrontEnd )
				)
				( attribute "MATERIAL" "EMPTY"
					( Origin gFrontEnd )
				)
				( attribute "PACK_TYPE" "0402LF"
					( Origin gFrontEnd )
				)
				( attribute "PART_NUMBER" "A36096-046"
					( Origin gFrontEnd )
				)
				( attribute "PHYS_PAGE" "230"
					( Origin gFrontEnd )
				)
				( attribute "ROOM" "VTT_KLM_PWR_VR"
					( Origin gFrontEnd )
				)
				( attribute "ROT" "2"
					( Origin gFrontEnd )
				)
				( attribute "SEC" "1"
					( Origin gFrontEnd )
				)
				( attribute "SEC_TYPE" "0402LF"
					( Origin gFrontEnd )
				)
				( attribute "TOLERANCE" "10%"
					( Origin gFrontEnd )
				)
				( attribute "VALUE" "1000PF"
					( Origin gFrontEnd )
				)
				( attribute "VER" "1"
					( Origin gFrontEnd )
				)
				( attribute "VOLTAGE" "50V"
					( Units "uVoltage" "V" 1.000000)
					( Origin gFrontEnd )
				)
				( attribute "XY" "(-350,-375)"
					( Origin gFrontEnd )
				)
				( attribute "CHIPS_PART_NAME" "CAP"
					( Origin gPackager )
				)
				( attribute "CDS_PART_NAME" "CAP_0402LF-1000PF,50V,10%,EMPTA"
					( Origin gPackager )
				)
				( objectStatus "C4A6" )
				( pin "a"
					( attribute "PN" "1"
						( Origin gPackager )
					)
					( objectStatus "C4A6.1" )
				)
				( pin "b"
					( attribute "PN" "2"
						( Origin gPackager )
					)
					( objectStatus "C4A6.2" )
				)
			)
			( gate "@baseboard_fab2_lib.baseboard_fab2(sch_1):page230_i46"
				( attribute "CDS_LIB" "mstr_discrete"
					( Origin gPackager )
				)
				( attribute "CDS_LOCATION" "C4A7"
					( Origin gPackager )
				)
				( attribute "CDS_SEC" "1"
					( Origin gPackager )
				)
				( attribute "LOCATION" "C4A7"
					( Origin gFrontEnd )
				)
				( attribute "MATERIAL" "X6S"
					( Origin gFrontEnd )
				)
				( attribute "PACK_TYPE" "0603"
					( Origin gFrontEnd )
				)
				( attribute "PART_NUMBER" "E15431-003"
					( Origin gFrontEnd )
				)
				( attribute "PHYS_PAGE" "230"
					( Origin gFrontEnd )
				)
				( attribute "ROOM" "VTT_KLM_PWR_VR"
					( Origin gFrontEnd )
				)
				( attribute "ROT" "0"
					( Origin gFrontEnd )
				)
				( attribute "SEC" "1"
					( Origin gFrontEnd )
				)
				( attribute "SEC_TYPE" "0603"
					( Origin gFrontEnd )
				)
				( attribute "TOLERANCE" "10%"
					( Origin gFrontEnd )
				)
				( attribute "VALUE" "4.7UF"
					( Origin gFrontEnd )
				)
				( attribute "VER" "1"
					( Origin gFrontEnd )
				)
				( attribute "VOLTAGE" "6.3V"
					( Units "uVoltage" "V" 1.000000)
					( Origin gFrontEnd )
				)
				( attribute "XY" "(375,975)"
					( Origin gFrontEnd )
				)
				( attribute "CHIPS_PART_NAME" "CAP"
					( Origin gPackager )
				)
				( attribute "CDS_PART_NAME" "CAP_0603-4.7UF,6.3V,10%,X6S,E1A"
					( Origin gPackager )
				)
				( objectStatus "C4A7" )
				( pin "a"
					( attribute "PN" "1"
						( Origin gPackager )
					)
					( objectStatus "C4A7.1" )
				)
				( pin "b"
					( attribute "PN" "2"
						( Origin gPackager )
					)
					( objectStatus "C4A7.2" )
				)
			)
			( gate "@baseboard_fab2_lib.baseboard_fab2(sch_1):page230_i47"
				( attribute "CDS_LIB" "dev_discrete"
					( Origin gPackager )
				)
				( attribute "CDS_LOCATION" "C8M12"
					( Origin gPackager )
				)
				( attribute "CDS_SEC" "1"
					( Origin gPackager )
				)
				( attribute "LOCATION" "C8M12"
					( Origin gFrontEnd )
				)
				( attribute "MATERIAL" "X5R"
					( Origin gFrontEnd )
				)
				( attribute "PACK_TYPE" "0603V"
					( Origin gFrontEnd )
				)
				( attribute "PART_NUMBER" "602433-106"
					( Origin gFrontEnd )
				)
				( attribute "PHYS_PAGE" "230"
					( Origin gFrontEnd )
				)
				( attribute "ROT" "0"
					( Origin gFrontEnd )
				)
				( attribute "SEC" "1"
					( Origin gFrontEnd )
				)
				( attribute "SEC_TYPE" "0603V"
					( Origin gFrontEnd )
				)
				( attribute "TOLERANCE" "20%"
					( Origin gFrontEnd )
				)
				( attribute "VALUE" "47UF"
					( Origin gFrontEnd )
				)
				( attribute "VER" "1"
					( Origin gFrontEnd )
				)
				( attribute "VOLTAGE" "4V"
					( Units "uVoltage" "V" 1.000000)
					( Origin gFrontEnd )
				)
				( attribute "XY" "(3025,3425)"
					( Origin gFrontEnd )
				)
				( attribute "CHIPS_PART_NAME" "CAP_A"
					( Origin gPackager )
				)
				( attribute "CDS_PART_NAME" "CAP_A_0603V-47UF,4V,20%,X5R,60A"
					( Origin gPackager )
				)
				( objectStatus "C8M12" )
				( pin "a"
					( attribute "PN" "1"
						( Origin gPackager )
					)
					( objectStatus "C8M12.1" )
				)
				( pin "b"
					( attribute "PN" "2"
						( Origin gPackager )
					)
					( objectStatus "C8M12.2" )
				)
			)
			( gate "@baseboard_fab2_lib.baseboard_fab2(sch_1):page230_i48"
				( attribute "CDS_LIB" "dev_discrete"
					( Origin gPackager )
				)
				( attribute "CDS_LOCATION" "C8L3"
					( Origin gPackager )
				)
				( attribute "CDS_SEC" "1"
					( Origin gPackager )
				)
				( attribute "LOCATION" "C8L3"
					( Origin gFrontEnd )
				)
				( attribute "MATERIAL" "X5R"
					( Origin gFrontEnd )
				)
				( attribute "PACK_TYPE" "0603V"
					( Origin gFrontEnd )
				)
				( attribute "PART_NUMBER" "602433-106"
					( Origin gFrontEnd )
				)
				( attribute "PHYS_PAGE" "230"
					( Origin gFrontEnd )
				)
				( attribute "ROT" "0"
					( Origin gFrontEnd )
				)
				( attribute "SEC" "1"
					( Origin gFrontEnd )
				)
				( attribute "SEC_TYPE" "0603V"
					( Origin gFrontEnd )
				)
				( attribute "TOLERANCE" "20%"
					( Origin gFrontEnd )
				)
				( attribute "VALUE" "47UF"
					( Origin gFrontEnd )
				)
				( attribute "VER" "1"
					( Origin gFrontEnd )
				)
				( attribute "VOLTAGE" "4V"
					( Units "uVoltage" "V" 1.000000)
					( Origin gFrontEnd )
				)
				( attribute "XY" "(3375,3425)"
					( Origin gFrontEnd )
				)
				( attribute "CHIPS_PART_NAME" "CAP_A"
					( Origin gPackager )
				)
				( attribute "CDS_PART_NAME" "CAP_A_0603V-47UF,4V,20%,X5R,60A"
					( Origin gPackager )
				)
				( objectStatus "C8L3" )
				( pin "a"
					( attribute "PN" "1"
						( Origin gPackager )
					)
					( objectStatus "C8L3.1" )
				)
				( pin "b"
					( attribute "PN" "2"
						( Origin gPackager )
					)
					( objectStatus "C8L3.2" )
				)
			)
			( gate "@baseboard_fab2_lib.baseboard_fab2(sch_1):page230_i49"
				( attribute "CDS_LIB" "dev_discrete"
					( Origin gPackager )
				)
				( attribute "CDS_LOCATION" "C8L4"
					( Origin gPackager )
				)
				( attribute "CDS_SEC" "1"
					( Origin gPackager )
				)
				( attribute "LOCATION" "C8L4"
					( Origin gFrontEnd )
				)
				( attribute "MATERIAL" "X5R"
					( Origin gFrontEnd )
				)
				( attribute "PACK_TYPE" "0603V"
					( Origin gFrontEnd )
				)
				( attribute "PART_NUMBER" "602433-106"
					( Origin gFrontEnd )
				)
				( attribute "PHYS_PAGE" "230"
					( Origin gFrontEnd )
				)
				( attribute "ROT" "0"
					( Origin gFrontEnd )
				)
				( attribute "SEC" "1"
					( Origin gFrontEnd )
				)
				( attribute "SEC_TYPE" "0603V"
					( Origin gFrontEnd )
				)
				( attribute "TOLERANCE" "20%"
					( Origin gFrontEnd )
				)
				( attribute "VALUE" "47UF"
					( Origin gFrontEnd )
				)
				( attribute "VER" "1"
					( Origin gFrontEnd )
				)
				( attribute "VOLTAGE" "4V"
					( Units "uVoltage" "V" 1.000000)
					( Origin gFrontEnd )
				)
				( attribute "XY" "(3775,3425)"
					( Origin gFrontEnd )
				)
				( attribute "CHIPS_PART_NAME" "CAP_A"
					( Origin gPackager )
				)
				( attribute "CDS_PART_NAME" "CAP_A_0603V-47UF,4V,20%,X5R,60A"
					( Origin gPackager )
				)
				( objectStatus "C8L4" )
				( pin "a"
					( attribute "PN" "1"
						( Origin gPackager )
					)
					( objectStatus "C8L4.1" )
				)
				( pin "b"
					( attribute "PN" "2"
						( Origin gPackager )
					)
					( objectStatus "C8L4.2" )
				)
			)
			( gate "@baseboard_fab2_lib.baseboard_fab2(sch_1):page230_i51"
				( attribute "CDS_LIB" "mstr_discrete"
					( Origin gPackager )
				)
				( attribute "CDS_LOCATION" "R4A4"
					( Origin gPackager )
				)
				( attribute "CDS_SEC" "1"
					( Origin gPackager )
				)
				( attribute "LOCATION" "R4A4"
					( Origin gFrontEnd )
				)
				( attribute "MATERIAL" "CHIP"
					( Origin gFrontEnd )
				)
				( attribute "PACK_TYPE" "0402"
					( Origin gFrontEnd )
				)
				( attribute "PART_NUMBER" "G21796-074"
					( Origin gFrontEnd )
				)
				( attribute "PHYS_PAGE" "230"
					( Origin gFrontEnd )
				)
				( attribute "ROT" "0"
					( Origin gFrontEnd )
				)
				( attribute "SEC" "1"
					( Origin gFrontEnd )
				)
				( attribute "SEC_TYPE" "0402"
					( Origin gFrontEnd )
				)
				( attribute "TOLERANCE" "1%"
					( Origin gFrontEnd )
				)
				( attribute "VALUE" "33.2"
					( Origin gFrontEnd )
				)
				( attribute "VER" "1"
					( Origin gFrontEnd )
				)
				( attribute "WATTAGE" "1/16W"
					( Origin gFrontEnd )
				)
				( attribute "XY" "(4150,1850)"
					( Origin gFrontEnd )
				)
				( attribute "CHIPS_PART_NAME" "RES"
					( Origin gPackager )
				)
				( attribute "CDS_PART_NAME" "RES_0402-33.2,1%,1/16W,CHIP,G2A"
					( Origin gPackager )
				)
				( objectStatus "R4A4" )
				( pin "a"
					( attribute "PN" "1"
						( Origin gPackager )
					)
					( objectStatus "R4A4.1" )
				)
				( pin "b"
					( attribute "PN" "2"
						( Origin gPackager )
					)
					( objectStatus "R4A4.2" )
				)
			)
			( gate "@baseboard_fab2_lib.baseboard_fab2(sch_1):page230_i52"
				( attribute "CDS_LIB" "mstr_discrete"
					( Origin gPackager )
				)
				( attribute "CDS_LOCATION" "R6L7"
					( Origin gPackager )
				)
				( attribute "CDS_SEC" "1"
					( Origin gPackager )
				)
				( attribute "LOCATION" "R6L7"
					( Origin gFrontEnd )
				)
				( attribute "MATERIAL" "CHIP"
					( Origin gFrontEnd )
				)
				( attribute "PACK_TYPE" "0402"
					( Origin gFrontEnd )
				)
				( attribute "PART_NUMBER" "G21796-208"
					( Origin gFrontEnd )
				)
				( attribute "PHYS_PAGE" "230"
					( Origin gFrontEnd )
				)
				( attribute "ROT" "1"
					( Origin gFrontEnd )
				)
				( attribute "SEC" "1"
					( Origin gPackager )
				)
				( attribute "TOLERANCE" "1.0%"
					( Origin gFrontEnd )
				)
				( attribute "VALUE" "51.1"
					( Origin gFrontEnd )
				)
				( attribute "VER" "1"
					( Origin gFrontEnd )
				)
				( attribute "WATTAGE" "1/16W"
					( Origin gFrontEnd )
				)
				( attribute "XY" "(4800,975)"
					( Origin gFrontEnd )
				)
				( attribute "CHIPS_PART_NAME" "RES"
					( Origin gPackager )
				)
				( attribute "CDS_PART_NAME" "RES_0402-51.1,1.0%,1/16W,CHIP,A"
					( Origin gPackager )
				)
				( objectStatus "R6L7" )
				( pin "a"
					( attribute "PN" "1"
						( Origin gPackager )
					)
					( objectStatus "R6L7.1" )
				)
				( pin "b"
					( attribute "PN" "2"
						( Origin gPackager )
					)
					( objectStatus "R6L7.2" )
				)
			)
			( gate "@baseboard_fab2_lib.baseboard_fab2(sch_1):page230_i53"
				( attribute "CDS_LIB" "mstr_misc"
					( Origin gPackager )
				)
				( attribute "CDS_LOCATION" "SH8L1"
					( Origin gPackager )
				)
				( attribute "CDS_SEC" "1"
					( Origin gPackager )
				)
				( attribute "LOCATION" "SH8L1"
					( Origin gFrontEnd )
				)
				( attribute "MATERIAL" "EMPTY"
					( Origin gFrontEnd )
				)
				( attribute "PACK_TYPE" "SH0201"
					( Origin gFrontEnd )
				)
				( attribute "PART_NUMBER" "N_A"
					( Origin gFrontEnd )
				)
				( attribute "PHYS_PAGE" "230"
					( Origin gFrontEnd )
				)
				( attribute "PIN_SHORT" "A:B"
					( Origin gFrontEnd )
				)
				( attribute "ROT" "0"
					( Origin gFrontEnd )
				)
				( attribute "SEC" "1"
					( Origin gFrontEnd )
				)
				( attribute "SEC_TYPE" "SH0201"
					( Origin gFrontEnd )
				)
				( attribute "VER" "1"
					( Origin gFrontEnd )
				)
				( attribute "XY" "(4975,50)"
					( Origin gFrontEnd )
				)
				( attribute "CHIPS_PART_NAME" "SHUNT"
					( Origin gPackager )
				)
				( attribute "CDS_PART_NAME" "SHUNT_SH0201-EMPTY,N_A"
					( Origin gPackager )
				)
				( objectStatus "SH8L1" )
				( pin "a"
					( attribute "PN" "1"
						( Origin gPackager )
					)
					( objectStatus "SH8L1.1" )
				)
				( pin "b"
					( attribute "PN" "2"
						( Origin gPackager )
					)
					( objectStatus "SH8L1.2" )
				)
			)
			( gate "@baseboard_fab2_lib.baseboard_fab2(sch_1):page231_i122"
				( attribute "BOM_COST" "MEM_VRD_PVPP_AB"
					( Origin gFrontEnd )
				)
				( attribute "CDS_LIB" "mstr_discrete"
					( Origin gPackager )
				)
				( attribute "CDS_LOCATION" "C6F6"
					( Origin gPackager )
				)
				( attribute "CDS_SEC" "1"
					( Origin gPackager )
				)
				( attribute "LOCATION" "C6F6"
					( Origin gFrontEnd )
				)
				( attribute "MATERIAL" "X6S"
					( Origin gFrontEnd )
				)
				( attribute "PACK_TYPE" "0603LF"
					( Origin gFrontEnd )
				)
				( attribute "PART_NUMBER" "E15431-001"
					( Origin gFrontEnd )
				)
				( attribute "PHYS_PAGE" "231"
					( Origin gFrontEnd )
				)
				( attribute "ROOM" "PVPP_KLM_VR"
					( Origin gFrontEnd )
				)
				( attribute "ROT" "0"
					( Origin gFrontEnd )
				)
				( attribute "SEC" "1"
					( Origin gPackager )
				)
				( attribute "TOLERANCE" "20%"
					( Origin gFrontEnd )
				)
				( attribute "VALUE" "10UF"
					( Origin gFrontEnd )
				)
				( attribute "VER" "1"
					( Origin gFrontEnd )
				)
				( attribute "VOLTAGE" "4V"
					( Units "uVoltage" "V" 1.000000)
					( Origin gFrontEnd )
				)
				( attribute "XY" "(-7850,1000)"
					( Origin gFrontEnd )
				)
				( attribute "CHIPS_PART_NAME" "CAP"
					( Origin gPackager )
				)
				( attribute "CDS_PART_NAME" "CAP_0603LF-10UF,4V,20%,X6S,E15A"
					( Origin gPackager )
				)
				( objectStatus "C6F6" )
				( pin "a"
					( attribute "PN" "1"
						( Origin gPackager )
					)
					( objectStatus "C6F6.1" )
				)
				( pin "b"
					( attribute "PN" "2"
						( Origin gPackager )
					)
					( objectStatus "C6F6.2" )
				)
			)
			( gate "@baseboard_fab2_lib.baseboard_fab2(sch_1):page231_i124"
				( attribute "BOM_COST" "MEM_VRD_PVPP_AB"
					( Origin gFrontEnd )
				)
				( attribute "CDS_LIB" "mstr_discrete"
					( Origin gPackager )
				)
				( attribute "CDS_LOCATION" "C4T6"
					( Origin gPackager )
				)
				( attribute "CDS_SEC" "1"
					( Origin gPackager )
				)
				( attribute "LOCATION" "C4T6"
					( Origin gFrontEnd )
				)
				( attribute "MATERIAL" "X6S"
					( Origin gFrontEnd )
				)
				( attribute "PACK_TYPE" "0603LF"
					( Origin gFrontEnd )
				)
				( attribute "PART_NUMBER" "E15431-001"
					( Origin gFrontEnd )
				)
				( attribute "PHYS_PAGE" "231"
					( Origin gFrontEnd )
				)
				( attribute "ROOM" "PVPP_KLM_VR"
					( Origin gFrontEnd )
				)
				( attribute "ROT" "0"
					( Origin gFrontEnd )
				)
				( attribute "SEC" "1"
					( Origin gPackager )
				)
				( attribute "TOLERANCE" "20%"
					( Origin gFrontEnd )
				)
				( attribute "VALUE" "10UF"
					( Origin gFrontEnd )
				)
				( attribute "VER" "1"
					( Origin gFrontEnd )
				)
				( attribute "VOLTAGE" "4V"
					( Units "uVoltage" "V" 1.000000)
					( Origin gFrontEnd )
				)
				( attribute "XY" "(-7600,1000)"
					( Origin gFrontEnd )
				)
				( attribute "CHIPS_PART_NAME" "CAP"
					( Origin gPackager )
				)
				( attribute "CDS_PART_NAME" "CAP_0603LF-10UF,4V,20%,X6S,E15A"
					( Origin gPackager )
				)
				( objectStatus "C4T6" )
				( pin "a"
					( attribute "PN" "1"
						( Origin gPackager )
					)
					( objectStatus "C4T6.1" )
				)
				( pin "b"
					( attribute "PN" "2"
						( Origin gPackager )
					)
					( objectStatus "C4T6.2" )
				)
			)
			( gate "@baseboard_fab2_lib.baseboard_fab2(sch_1):page231_i125"
				( attribute "BOM_COST" "MEM_VRD_PVPP_AB"
					( Origin gFrontEnd )
				)
				( attribute "CDS_LIB" "mstr_discrete"
					( Origin gPackager )
				)
				( attribute "CDS_LOCATION" "C4T5"
					( Origin gPackager )
				)
				( attribute "CDS_SEC" "1"
					( Origin gPackager )
				)
				( attribute "LOCATION" "C4T5"
					( Origin gFrontEnd )
				)
				( attribute "MATERIAL" "X6S"
					( Origin gFrontEnd )
				)
				( attribute "PACK_TYPE" "0603LF"
					( Origin gFrontEnd )
				)
				( attribute "PART_NUMBER" "E15431-001"
					( Origin gFrontEnd )
				)
				( attribute "PHYS_PAGE" "231"
					( Origin gFrontEnd )
				)
				( attribute "ROOM" "PVPP_KLM_VR"
					( Origin gFrontEnd )
				)
				( attribute "ROT" "0"
					( Origin gFrontEnd )
				)
				( attribute "SEC" "1"
					( Origin gPackager )
				)
				( attribute "TOLERANCE" "20%"
					( Origin gFrontEnd )
				)
				( attribute "VALUE" "10UF"
					( Origin gFrontEnd )
				)
				( attribute "VER" "1"
					( Origin gFrontEnd )
				)
				( attribute "VOLTAGE" "4V"
					( Units "uVoltage" "V" 1.000000)
					( Origin gFrontEnd )
				)
				( attribute "XY" "(-7325,1000)"
					( Origin gFrontEnd )
				)
				( attribute "CHIPS_PART_NAME" "CAP"
					( Origin gPackager )
				)
				( attribute "CDS_PART_NAME" "CAP_0603LF-10UF,4V,20%,X6S,E15A"
					( Origin gPackager )
				)
				( objectStatus "C4T5" )
				( pin "a"
					( attribute "PN" "1"
						( Origin gPackager )
					)
					( objectStatus "C4T5.1" )
				)
				( pin "b"
					( attribute "PN" "2"
						( Origin gPackager )
					)
					( objectStatus "C4T5.2" )
				)
			)
			( gate "@baseboard_fab2_lib.baseboard_fab2(sch_1):page231_i126"
				( attribute "BOM_COST" "MEM_VRD_PVPP_AB"
					( Origin gFrontEnd )
				)
				( attribute "CDS_LIB" "mstr_discrete"
					( Origin gPackager )
				)
				( attribute "CDS_LOCATION" "C6G1"
					( Origin gPackager )
				)
				( attribute "CDS_SEC" "1"
					( Origin gPackager )
				)
				( attribute "LOCATION" "C6G1"
					( Origin gFrontEnd )
				)
				( attribute "MATERIAL" "X6S"
					( Origin gFrontEnd )
				)
				( attribute "PACK_TYPE" "0603LF"
					( Origin gFrontEnd )
				)
				( attribute "PART_NUMBER" "E15431-001"
					( Origin gFrontEnd )
				)
				( attribute "PHYS_PAGE" "231"
					( Origin gFrontEnd )
				)
				( attribute "ROOM" "PVPP_KLM_VR"
					( Origin gFrontEnd )
				)
				( attribute "ROT" "0"
					( Origin gFrontEnd )
				)
				( attribute "SEC" "1"
					( Origin gPackager )
				)
				( attribute "TOLERANCE" "20%"
					( Origin gFrontEnd )
				)
				( attribute "VALUE" "10UF"
					( Origin gFrontEnd )
				)
				( attribute "VER" "1"
					( Origin gFrontEnd )
				)
				( attribute "VOLTAGE" "4V"
					( Units "uVoltage" "V" 1.000000)
					( Origin gFrontEnd )
				)
				( attribute "XY" "(-7075,975)"
					( Origin gFrontEnd )
				)
				( attribute "CHIPS_PART_NAME" "CAP"
					( Origin gPackager )
				)
				( attribute "CDS_PART_NAME" "CAP_0603LF-10UF,4V,20%,X6S,E15A"
					( Origin gPackager )
				)
				( objectStatus "C6G1" )
				( pin "a"
					( attribute "PN" "1"
						( Origin gPackager )
					)
					( objectStatus "C6G1.1" )
				)
				( pin "b"
					( attribute "PN" "2"
						( Origin gPackager )
					)
					( objectStatus "C6G1.2" )
				)
			)
			( gate "@baseboard_fab2_lib.baseboard_fab2(sch_1):page231_i128"
				( attribute "BOM_COST" "MEM_VRD_PVPP_AB"
					( Origin gFrontEnd )
				)
				( attribute "CDS_LIB" "mstr_discrete"
					( Origin gPackager )
				)
				( attribute "CDS_LOCATION" "C6G2"
					( Origin gPackager )
				)
				( attribute "CDS_SEC" "1"
					( Origin gPackager )
				)
				( attribute "LOCATION" "C6G2"
					( Origin gFrontEnd )
				)
				( attribute "MATERIAL" "X6S"
					( Origin gFrontEnd )
				)
				( attribute "PACK_TYPE" "0603LF"
					( Origin gFrontEnd )
				)
				( attribute "PART_NUMBER" "E15431-001"
					( Origin gFrontEnd )
				)
				( attribute "PHYS_PAGE" "231"
					( Origin gFrontEnd )
				)
				( attribute "ROOM" "PVPP_KLM_VR"
					( Origin gFrontEnd )
				)
				( attribute "ROT" "0"
					( Origin gFrontEnd )
				)
				( attribute "SEC" "1"
					( Origin gPackager )
				)
				( attribute "TOLERANCE" "20%"
					( Origin gFrontEnd )
				)
				( attribute "VALUE" "10UF"
					( Origin gFrontEnd )
				)
				( attribute "VER" "1"
					( Origin gFrontEnd )
				)
				( attribute "VOLTAGE" "4V"
					( Units "uVoltage" "V" 1.000000)
					( Origin gFrontEnd )
				)
				( attribute "XY" "(-6800,1000)"
					( Origin gFrontEnd )
				)
				( attribute "CHIPS_PART_NAME" "CAP"
					( Origin gPackager )
				)
				( attribute "CDS_PART_NAME" "CAP_0603LF-10UF,4V,20%,X6S,E15A"
					( Origin gPackager )
				)
				( objectStatus "C6G2" )
				( pin "a"
					( attribute "PN" "1"
						( Origin gPackager )
					)
					( objectStatus "C6G2.1" )
				)
				( pin "b"
					( attribute "PN" "2"
						( Origin gPackager )
					)
					( objectStatus "C6G2.2" )
				)
			)
			( gate "@baseboard_fab2_lib.baseboard_fab2(sch_1):page231_i129"
				( attribute "BOM_COST" "MEM_VRD_PVPP_AB"
					( Origin gFrontEnd )
				)
				( attribute "CDS_LIB" "mstr_discrete"
					( Origin gPackager )
				)
				( attribute "CDS_LOCATION" "C4U2"
					( Origin gPackager )
				)
				( attribute "CDS_SEC" "1"
					( Origin gPackager )
				)
				( attribute "LOCATION" "C4U2"
					( Origin gFrontEnd )
				)
				( attribute "MATERIAL" "X6S"
					( Origin gFrontEnd )
				)
				( attribute "PACK_TYPE" "0603LF"
					( Origin gFrontEnd )
				)
				( attribute "PART_NUMBER" "E15431-001"
					( Origin gFrontEnd )
				)
				( attribute "PHYS_PAGE" "231"
					( Origin gFrontEnd )
				)
				( attribute "ROOM" "PVPP_KLM_VR"
					( Origin gFrontEnd )
				)
				( attribute "ROT" "0"
					( Origin gFrontEnd )
				)
				( attribute "SEC" "1"
					( Origin gPackager )
				)
				( attribute "TOLERANCE" "20%"
					( Origin gFrontEnd )
				)
				( attribute "VALUE" "10UF"
					( Origin gFrontEnd )
				)
				( attribute "VER" "1"
					( Origin gFrontEnd )
				)
				( attribute "VOLTAGE" "4V"
					( Units "uVoltage" "V" 1.000000)
					( Origin gFrontEnd )
				)
				( attribute "XY" "(-6500,1000)"
					( Origin gFrontEnd )
				)
				( attribute "CHIPS_PART_NAME" "CAP"
					( Origin gPackager )
				)
				( attribute "CDS_PART_NAME" "CAP_0603LF-10UF,4V,20%,X6S,E15A"
					( Origin gPackager )
				)
				( objectStatus "C4U2" )
				( pin "a"
					( attribute "PN" "1"
						( Origin gPackager )
					)
					( objectStatus "C4U2.1" )
				)
				( pin "b"
					( attribute "PN" "2"
						( Origin gPackager )
					)
					( objectStatus "C4U2.2" )
				)
			)
			( gate "@baseboard_fab2_lib.baseboard_fab2(sch_1):page231_i130"
				( attribute "BOM_COST" "MEM_VRD_PVPP_AB"
					( Origin gFrontEnd )
				)
				( attribute "CDS_LIB" "mstr_discrete"
					( Origin gPackager )
				)
				( attribute "CDS_LOCATION" "C4U1"
					( Origin gPackager )
				)
				( attribute "CDS_SEC" "1"
					( Origin gPackager )
				)
				( attribute "LOCATION" "C4U1"
					( Origin gFrontEnd )
				)
				( attribute "MATERIAL" "X6S"
					( Origin gFrontEnd )
				)
				( attribute "PACK_TYPE" "0603LF"
					( Origin gFrontEnd )
				)
				( attribute "PART_NUMBER" "E15431-001"
					( Origin gFrontEnd )
				)
				( attribute "PHYS_PAGE" "231"
					( Origin gFrontEnd )
				)
				( attribute "ROOM" "PVPP_KLM_VR"
					( Origin gFrontEnd )
				)
				( attribute "ROT" "0"
					( Origin gFrontEnd )
				)
				( attribute "SEC" "1"
					( Origin gPackager )
				)
				( attribute "TOLERANCE" "20%"
					( Origin gFrontEnd )
				)
				( attribute "VALUE" "10UF"
					( Origin gFrontEnd )
				)
				( attribute "VER" "1"
					( Origin gFrontEnd )
				)
				( attribute "VOLTAGE" "4V"
					( Units "uVoltage" "V" 1.000000)
					( Origin gFrontEnd )
				)
				( attribute "XY" "(-6225,1000)"
					( Origin gFrontEnd )
				)
				( attribute "CHIPS_PART_NAME" "CAP"
					( Origin gPackager )
				)
				( attribute "CDS_PART_NAME" "CAP_0603LF-10UF,4V,20%,X6S,E15A"
					( Origin gPackager )
				)
				( objectStatus "C4U1" )
				( pin "a"
					( attribute "PN" "1"
						( Origin gPackager )
					)
					( objectStatus "C4U1.1" )
				)
				( pin "b"
					( attribute "PN" "2"
						( Origin gPackager )
					)
					( objectStatus "C4U1.2" )
				)
			)
			( gate "@baseboard_fab2_lib.baseboard_fab2(sch_1):page231_i131"
				( attribute "BOM_COST" "MEM_VRD_PVPP_AB"
					( Origin gFrontEnd )
				)
				( attribute "CDS_LIB" "mstr_discrete"
					( Origin gPackager )
				)
				( attribute "CDS_LOCATION" "C6G4"
					( Origin gPackager )
				)
				( attribute "CDS_SEC" "1"
					( Origin gPackager )
				)
				( attribute "LOCATION" "C6G4"
					( Origin gFrontEnd )
				)
				( attribute "MATERIAL" "X6S"
					( Origin gFrontEnd )
				)
				( attribute "PACK_TYPE" "0603LF"
					( Origin gFrontEnd )
				)
				( attribute "PART_NUMBER" "E15431-001"
					( Origin gFrontEnd )
				)
				( attribute "PHYS_PAGE" "231"
					( Origin gFrontEnd )
				)
				( attribute "ROOM" "PVPP_KLM_VR"
					( Origin gFrontEnd )
				)
				( attribute "ROT" "0"
					( Origin gFrontEnd )
				)
				( attribute "SEC" "1"
					( Origin gPackager )
				)
				( attribute "TOLERANCE" "20%"
					( Origin gFrontEnd )
				)
				( attribute "VALUE" "10UF"
					( Origin gFrontEnd )
				)
				( attribute "VER" "1"
					( Origin gFrontEnd )
				)
				( attribute "VOLTAGE" "4V"
					( Units "uVoltage" "V" 1.000000)
					( Origin gFrontEnd )
				)
				( attribute "XY" "(-5925,1000)"
					( Origin gFrontEnd )
				)
				( attribute "CHIPS_PART_NAME" "CAP"
					( Origin gPackager )
				)
				( attribute "CDS_PART_NAME" "CAP_0603LF-10UF,4V,20%,X6S,E15A"
					( Origin gPackager )
				)
				( objectStatus "C6G4" )
				( pin "a"
					( attribute "PN" "1"
						( Origin gPackager )
					)
					( objectStatus "C6G4.1" )
				)
				( pin "b"
					( attribute "PN" "2"
						( Origin gPackager )
					)
					( objectStatus "C6G4.2" )
				)
			)
			( gate "@baseboard_fab2_lib.baseboard_fab2(sch_1):page231_i134"
				( attribute "BOM_COST" "PVPP_KLM_VR"
					( Origin gFrontEnd )
				)
				( attribute "CDS_LIB" "mstr_discrete"
					( Origin gPackager )
				)
				( attribute "CDS_LOCATION" "R7F15"
					( Origin gPackager )
				)
				( attribute "CDS_SEC" "1"
					( Origin gPackager )
				)
				( attribute "LOCATION" "R7F15"
					( Origin gFrontEnd )
				)
				( attribute "MATERIAL" "CHIP"
					( Origin gFrontEnd )
				)
				( attribute "PACK_TYPE" "0402"
					( Origin gFrontEnd )
				)
				( attribute "PART_NUMBER" "G21796-242"
					( Origin gFrontEnd )
				)
				( attribute "PHYS_PAGE" "231"
					( Origin gFrontEnd )
				)
				( attribute "ROOM" "PVPP_KLM_VR"
					( Origin gFrontEnd )
				)
				( attribute "ROT" "2"
					( Origin gFrontEnd )
				)
				( attribute "SEC" "1"
					( Origin gPackager )
				)
				( attribute "TOLERANCE" "1.0%"
					( Origin gFrontEnd )
				)
				( attribute "VALUE" "7.87K"
					( Origin gFrontEnd )
				)
				( attribute "VER" "2"
					( Origin gFrontEnd )
				)
				( attribute "WATTAGE" "1/16W"
					( Origin gFrontEnd )
				)
				( attribute "XY" "(-4400,1900)"
					( Origin gFrontEnd )
				)
				( attribute "CHIPS_PART_NAME" "RES"
					( Origin gPackager )
				)
				( attribute "CDS_PART_NAME" "RES_0402-7.87K,1.0%,1/16W,CHIPA"
					( Origin gPackager )
				)
				( objectStatus "R7F15" )
				( pin "a"
					( attribute "PN" "1"
						( Origin gPackager )
					)
					( objectStatus "R7F15.1" )
				)
				( pin "b"
					( attribute "PN" "2"
						( Origin gPackager )
					)
					( objectStatus "R7F15.2" )
				)
			)
			( gate "@baseboard_fab2_lib.baseboard_fab2(sch_1):page231_i136"
				( attribute "BOM" "SYSB_CPLD"
					( Origin gFrontEnd )
				)
				( attribute "BOM_COST" "PVPP_KLM_VR"
					( Origin gFrontEnd )
				)
				( attribute "CDS_LIB" "mstr_discrete"
					( Origin gPackager )
				)
				( attribute "CDS_LOCATION" "R7F14"
					( Origin gPackager )
				)
				( attribute "CDS_SEC" "1"
					( Origin gPackager )
				)
				( attribute "LOCATION" "R7F14"
					( Origin gFrontEnd )
				)
				( attribute "MATERIAL" "CHIP"
					( Origin gFrontEnd )
				)
				( attribute "PACK_TYPE" "0402"
					( Origin gFrontEnd )
				)
				( attribute "PART_NUMBER" "G21796-016"
					( Origin gFrontEnd )
				)
				( attribute "PHYS_PAGE" "231"
					( Origin gFrontEnd )
				)
				( attribute "ROOM" "PVPP_KLM_VR"
					( Origin gFrontEnd )
				)
				( attribute "ROT" "0"
					( Origin gFrontEnd )
				)
				( attribute "SEC" "1"
					( Origin gPackager )
				)
				( attribute "TOLERANCE" "1%"
					( Origin gFrontEnd )
				)
				( attribute "VALUE" "10.0K"
					( Origin gFrontEnd )
				)
				( attribute "VER" "2"
					( Origin gFrontEnd )
				)
				( attribute "WATTAGE" "1/16W"
					( Origin gFrontEnd )
				)
				( attribute "XY" "(-6625,2450)"
					( Origin gFrontEnd )
				)
				( attribute "CHIPS_PART_NAME" "RES"
					( Origin gPackager )
				)
				( attribute "CDS_PART_NAME" "RES_0402-10.0K,1%,1/16W,CHIP,GA"
					( Origin gPackager )
				)
				( objectStatus "R7F14" )
				( pin "a"
					( attribute "PN" "1"
						( Origin gPackager )
					)
					( objectStatus "R7F14.1" )
				)
				( pin "b"
					( attribute "PN" "2"
						( Origin gPackager )
					)
					( objectStatus "R7F14.2" )
				)
			)
			( gate "@baseboard_fab2_lib.baseboard_fab2(sch_1):page231_i140"
				( attribute "BOM_COST" "PVPP_KLM_VR"
					( Origin gFrontEnd )
				)
				( attribute "CDS_LIB" "mstr_discrete"
					( Origin gPackager )
				)
				( attribute "CDS_LOCATION" "C7F8"
					( Origin gPackager )
				)
				( attribute "CDS_SEC" "1"
					( Origin gPackager )
				)
				( attribute "FIN" "VR_1P2"
					( Origin gFrontEnd )
				)
				( attribute "LOCATION" "C7F8"
					( Origin gFrontEnd )
				)
				( attribute "MATERIAL" "EMPTY"
					( Origin gFrontEnd )
				)
				( attribute "PACK_TYPE" "0402LF"
					( Origin gFrontEnd )
				)
				( attribute "PART_NUMBER" "A36096-046"
					( Origin gFrontEnd )
				)
				( attribute "PHYS_PAGE" "231"
					( Origin gFrontEnd )
				)
				( attribute "REUSE_ID" "1"
					( Origin gFrontEnd )
				)
				( attribute "ROOM" "PVPP_KLM_VR"
					( Origin gFrontEnd )
				)
				( attribute "ROT" "2"
					( Origin gFrontEnd )
				)
				( attribute "SEC" "1"
					( Origin gPackager )
				)
				( attribute "TOLERANCE" "10%"
					( Origin gFrontEnd )
				)
				( attribute "VALUE" "1000PF"
					( Origin gFrontEnd )
				)
				( attribute "VER" "1"
					( Origin gFrontEnd )
				)
				( attribute "VOLTAGE" "50V"
					( Units "uVoltage" "V" 1.000000)
					( Origin gFrontEnd )
				)
				( attribute "XY" "(-6175,2650)"
					( Origin gFrontEnd )
				)
				( attribute "CHIPS_PART_NAME" "CAP"
					( Origin gPackager )
				)
				( attribute "CDS_PART_NAME" "CAP_0402LF-1000PF,50V,10%,EMPTA"
					( Origin gPackager )
				)
				( objectStatus "C7F8" )
				( pin "a"
					( attribute "PN" "1"
						( Origin gPackager )
					)
					( objectStatus "C7F8.1" )
				)
				( pin "b"
					( attribute "PN" "2"
						( Origin gPackager )
					)
					( objectStatus "C7F8.2" )
				)
			)
			( gate "@baseboard_fab2_lib.baseboard_fab2(sch_1):page231_i142"
				( attribute "BOM_COST" "PVPP_KLM_VR"
					( Origin gFrontEnd )
				)
				( attribute "CDS_LIB" "mstr_discrete"
					( Origin gPackager )
				)
				( attribute "CDS_LOCATION" "C7F11"
					( Origin gPackager )
				)
				( attribute "CDS_SEC" "1"
					( Origin gPackager )
				)
				( attribute "LOCATION" "C7F11"
					( Origin gFrontEnd )
				)
				( attribute "MATERIAL" "X7R"
					( Origin gFrontEnd )
				)
				( attribute "PACK_TYPE" "0402LF"
					( Origin gFrontEnd )
				)
				( attribute "PART_NUMBER" "A36096-046"
					( Origin gFrontEnd )
				)
				( attribute "PHYS_PAGE" "231"
					( Origin gFrontEnd )
				)
				( attribute "REUSE_ID" "17"
					( Origin gFrontEnd )
				)
				( attribute "ROOM" "PVPP_KLM_VR"
					( Origin gFrontEnd )
				)
				( attribute "ROT" "0"
					( Origin gFrontEnd )
				)
				( attribute "SEC" "1"
					( Origin gPackager )
				)
				( attribute "TOLERANCE" "10%"
					( Origin gFrontEnd )
				)
				( attribute "VALUE" "1000PF"
					( Origin gFrontEnd )
				)
				( attribute "VER" "1"
					( Origin gFrontEnd )
				)
				( attribute "VOLTAGE" "50V"
					( Units "uVoltage" "V" 1.000000)
					( Origin gFrontEnd )
				)
				( attribute "XY" "(-3525,975)"
					( Origin gFrontEnd )
				)
				( attribute "CHIPS_PART_NAME" "CAP"
					( Origin gPackager )
				)
				( attribute "CDS_PART_NAME" "CAP_0402LF-1000PF,50V,10%,X7R,A"
					( Origin gPackager )
				)
				( objectStatus "C7F11" )
				( pin "a"
					( attribute "PN" "1"
						( Origin gPackager )
					)
					( objectStatus "C7F11.1" )
				)
				( pin "b"
					( attribute "PN" "2"
						( Origin gPackager )
					)
					( objectStatus "C7F11.2" )
				)
			)
			( gate "@baseboard_fab2_lib.baseboard_fab2(sch_1):page231_i143"
				( attribute "BOM_COST" "PVPP_KLM_VR"
					( Origin gFrontEnd )
				)
				( attribute "CDS_LIB" "mstr_discrete"
					( Origin gPackager )
				)
				( attribute "CDS_LOCATION" "R7F19"
					( Origin gPackager )
				)
				( attribute "CDS_SEC" "1"
					( Origin gPackager )
				)
				( attribute "LOCATION" "R7F19"
					( Origin gFrontEnd )
				)
				( attribute "MATERIAL" "CHIP"
					( Origin gFrontEnd )
				)
				( attribute "PACK_TYPE" "0402"
					( Origin gFrontEnd )
				)
				( attribute "PART_NUMBER" "G21796-026"
					( Origin gFrontEnd )
				)
				( attribute "PHYS_PAGE" "231"
					( Origin gFrontEnd )
				)
				( attribute "REUSE_ID" "21"
					( Origin gFrontEnd )
				)
				( attribute "ROOM" "PVPP_KLM_VR"
					( Origin gFrontEnd )
				)
				( attribute "ROT" "0"
					( Origin gFrontEnd )
				)
				( attribute "SEC" "1"
					( Origin gFrontEnd )
				)
				( attribute "SEC_TYPE" "0402"
					( Origin gFrontEnd )
				)
				( attribute "TOLERANCE" "1%"
					( Origin gFrontEnd )
				)
				( attribute "VALUE" "1.00K"
					( Origin gFrontEnd )
				)
				( attribute "VER" "2"
					( Origin gFrontEnd )
				)
				( attribute "WATTAGE" "1/16W"
					( Origin gFrontEnd )
				)
				( attribute "XY" "(-3875,1500)"
					( Origin gFrontEnd )
				)
				( attribute "CHIPS_PART_NAME" "RES"
					( Origin gPackager )
				)
				( attribute "CDS_PART_NAME" "RES_0402-1.00K,1%,1/16W,CHIP,GA"
					( Origin gPackager )
				)
				( objectStatus "R7F19" )
				( pin "a"
					( attribute "PN" "1"
						( Origin gPackager )
					)
					( objectStatus "R7F19.1" )
				)
				( pin "b"
					( attribute "PN" "2"
						( Origin gPackager )
					)
					( objectStatus "R7F19.2" )
				)
			)
			( gate "@baseboard_fab2_lib.baseboard_fab2(sch_1):page231_i145"
				( attribute "BOM_COST" "MEM_VRD_PVPP_AB"
					( Origin gFrontEnd )
				)
				( attribute "CDS_LIB" "mstr_discrete"
					( Origin gPackager )
				)
				( attribute "CDS_LOCATION" "C6G5"
					( Origin gPackager )
				)
				( attribute "CDS_SEC" "1"
					( Origin gPackager )
				)
				( attribute "LOCATION" "C6G5"
					( Origin gFrontEnd )
				)
				( attribute "MATERIAL" "X6S"
					( Origin gFrontEnd )
				)
				( attribute "PACK_TYPE" "0603LF"
					( Origin gFrontEnd )
				)
				( attribute "PART_NUMBER" "E15431-001"
					( Origin gFrontEnd )
				)
				( attribute "PHYS_PAGE" "231"
					( Origin gFrontEnd )
				)
				( attribute "ROOM" "PVPP_KLM_VR"
					( Origin gFrontEnd )
				)
				( attribute "ROT" "0"
					( Origin gFrontEnd )
				)
				( attribute "SEC" "1"
					( Origin gPackager )
				)
				( attribute "TOLERANCE" "20%"
					( Origin gFrontEnd )
				)
				( attribute "VALUE" "10UF"
					( Origin gFrontEnd )
				)
				( attribute "VER" "1"
					( Origin gFrontEnd )
				)
				( attribute "VOLTAGE" "4V"
					( Units "uVoltage" "V" 1.000000)
					( Origin gFrontEnd )
				)
				( attribute "XY" "(-5625,1000)"
					( Origin gFrontEnd )
				)
				( attribute "CHIPS_PART_NAME" "CAP"
					( Origin gPackager )
				)
				( attribute "CDS_PART_NAME" "CAP_0603LF-10UF,4V,20%,X6S,E15A"
					( Origin gPackager )
				)
				( objectStatus "C6G5" )
				( pin "a"
					( attribute "PN" "1"
						( Origin gPackager )
					)
					( objectStatus "C6G5.1" )
				)
				( pin "b"
					( attribute "PN" "2"
						( Origin gPackager )
					)
					( objectStatus "C6G5.2" )
				)
			)
			( gate "@baseboard_fab2_lib.baseboard_fab2(sch_1):page231_i146"
				( attribute "BOM_COST" "MEM_VRD_PVPP_AB"
					( Origin gFrontEnd )
				)
				( attribute "CDS_LIB" "mstr_discrete"
					( Origin gPackager )
				)
				( attribute "CDS_LOCATION" "C4U4"
					( Origin gPackager )
				)
				( attribute "CDS_SEC" "1"
					( Origin gPackager )
				)
				( attribute "LOCATION" "C4U4"
					( Origin gFrontEnd )
				)
				( attribute "MATERIAL" "X6S"
					( Origin gFrontEnd )
				)
				( attribute "PACK_TYPE" "0603LF"
					( Origin gFrontEnd )
				)
				( attribute "PART_NUMBER" "E15431-001"
					( Origin gFrontEnd )
				)
				( attribute "PHYS_PAGE" "231"
					( Origin gFrontEnd )
				)
				( attribute "ROOM" "PVPP_KLM_VR"
					( Origin gFrontEnd )
				)
				( attribute "ROT" "0"
					( Origin gFrontEnd )
				)
				( attribute "SEC" "1"
					( Origin gPackager )
				)
				( attribute "TOLERANCE" "20%"
					( Origin gFrontEnd )
				)
				( attribute "VALUE" "10UF"
					( Origin gFrontEnd )
				)
				( attribute "VER" "1"
					( Origin gFrontEnd )
				)
				( attribute "VOLTAGE" "4V"
					( Units "uVoltage" "V" 1.000000)
					( Origin gFrontEnd )
				)
				( attribute "XY" "(-5350,975)"
					( Origin gFrontEnd )
				)
				( attribute "CHIPS_PART_NAME" "CAP"
					( Origin gPackager )
				)
				( attribute "CDS_PART_NAME" "CAP_0603LF-10UF,4V,20%,X6S,E15A"
					( Origin gPackager )
				)
				( objectStatus "C4U4" )
				( pin "a"
					( attribute "PN" "1"
						( Origin gPackager )
					)
					( objectStatus "C4U4.1" )
				)
				( pin "b"
					( attribute "PN" "2"
						( Origin gPackager )
					)
					( objectStatus "C4U4.2" )
				)
			)
			( gate "@baseboard_fab2_lib.baseboard_fab2(sch_1):page231_i148"
				( attribute "BOM_COST" "MEM_VRD_PVPP_AB"
					( Origin gFrontEnd )
				)
				( attribute "CDS_LIB" "mstr_discrete"
					( Origin gPackager )
				)
				( attribute "CDS_LOCATION" "C4U3"
					( Origin gPackager )
				)
				( attribute "CDS_SEC" "1"
					( Origin gPackager )
				)
				( attribute "LOCATION" "C4U3"
					( Origin gFrontEnd )
				)
				( attribute "MATERIAL" "X6S"
					( Origin gFrontEnd )
				)
				( attribute "PACK_TYPE" "0603LF"
					( Origin gFrontEnd )
				)
				( attribute "PART_NUMBER" "E15431-001"
					( Origin gFrontEnd )
				)
				( attribute "PHYS_PAGE" "231"
					( Origin gFrontEnd )
				)
				( attribute "ROOM" "PVPP_KLM_VR"
					( Origin gFrontEnd )
				)
				( attribute "ROT" "0"
					( Origin gFrontEnd )
				)
				( attribute "SEC" "1"
					( Origin gPackager )
				)
				( attribute "TOLERANCE" "20%"
					( Origin gFrontEnd )
				)
				( attribute "VALUE" "10UF"
					( Origin gFrontEnd )
				)
				( attribute "VER" "1"
					( Origin gFrontEnd )
				)
				( attribute "VOLTAGE" "4V"
					( Units "uVoltage" "V" 1.000000)
					( Origin gFrontEnd )
				)
				( attribute "XY" "(-5075,975)"
					( Origin gFrontEnd )
				)
				( attribute "CHIPS_PART_NAME" "CAP"
					( Origin gPackager )
				)
				( attribute "CDS_PART_NAME" "CAP_0603LF-10UF,4V,20%,X6S,E15A"
					( Origin gPackager )
				)
				( objectStatus "C4U3" )
				( pin "a"
					( attribute "PN" "1"
						( Origin gPackager )
					)
					( objectStatus "C4U3.1" )
				)
				( pin "b"
					( attribute "PN" "2"
						( Origin gPackager )
					)
					( objectStatus "C4U3.2" )
				)
			)
			( gate "@baseboard_fab2_lib.baseboard_fab2(sch_1):page231_i149"
				( attribute "BOM_COST" "MEM_VRD_PVPP_AB"
					( Origin gFrontEnd )
				)
				( attribute "CDS_LIB" "mstr_discrete"
					( Origin gPackager )
				)
				( attribute "CDS_LOCATION" "C6F5"
					( Origin gPackager )
				)
				( attribute "CDS_SEC" "1"
					( Origin gPackager )
				)
				( attribute "LOCATION" "C6F5"
					( Origin gFrontEnd )
				)
				( attribute "MATERIAL" "X6S"
					( Origin gFrontEnd )
				)
				( attribute "PACK_TYPE" "0603LF"
					( Origin gFrontEnd )
				)
				( attribute "PART_NUMBER" "E15431-001"
					( Origin gFrontEnd )
				)
				( attribute "PHYS_PAGE" "231"
					( Origin gFrontEnd )
				)
				( attribute "ROOM" "PVPP_KLM_VR"
					( Origin gFrontEnd )
				)
				( attribute "ROT" "0"
					( Origin gFrontEnd )
				)
				( attribute "SEC" "1"
					( Origin gFrontEnd )
				)
				( attribute "SEC_TYPE" "0603LF"
					( Origin gFrontEnd )
				)
				( attribute "TOLERANCE" "20%"
					( Origin gFrontEnd )
				)
				( attribute "VALUE" "10UF"
					( Origin gFrontEnd )
				)
				( attribute "VER" "1"
					( Origin gFrontEnd )
				)
				( attribute "VOLTAGE" "4V"
					( Units "uVoltage" "V" 1.000000)
					( Origin gFrontEnd )
				)
				( attribute "XY" "(-4825,1000)"
					( Origin gFrontEnd )
				)
				( attribute "CHIPS_PART_NAME" "CAP"
					( Origin gPackager )
				)
				( attribute "CDS_PART_NAME" "CAP_0603LF-10UF,4V,20%,X6S,E15A"
					( Origin gPackager )
				)
				( objectStatus "C6F5" )
				( pin "a"
					( attribute "PN" "1"
						( Origin gPackager )
					)
					( objectStatus "C6F5.1" )
				)
				( pin "b"
					( attribute "PN" "2"
						( Origin gPackager )
					)
					( objectStatus "C6F5.2" )
				)
			)
			( gate "@baseboard_fab2_lib.baseboard_fab2(sch_1):page231_i151"
				( attribute "BOM_COST" "PVPP_KLM_VR"
					( Origin gFrontEnd )
				)
				( attribute "CDS_LIB" "mstr_discrete"
					( Origin gPackager )
				)
				( attribute "CDS_LOCATION" "C7F7"
					( Origin gPackager )
				)
				( attribute "CDS_SEC" "1"
					( Origin gPackager )
				)
				( attribute "LOCATION" "C7F7"
					( Origin gFrontEnd )
				)
				( attribute "MATERIAL" "X6S"
					( Origin gFrontEnd )
				)
				( attribute "PACK_TYPE" "1210"
					( Origin gFrontEnd )
				)
				( attribute "PART_NUMBER" "D38464-007"
					( Origin gFrontEnd )
				)
				( attribute "PHYS_PAGE" "231"
					( Origin gFrontEnd )
				)
				( attribute "ROOM" "PVPP_KLM_VR"
					( Origin gFrontEnd )
				)
				( attribute "ROT" "0"
					( Origin gFrontEnd )
				)
				( attribute "SEC" "1"
					( Origin gPackager )
				)
				( attribute "TOLERANCE" "20%"
					( Origin gFrontEnd )
				)
				( attribute "VALUE" "47UF"
					( Origin gFrontEnd )
				)
				( attribute "VER" "1"
					( Origin gFrontEnd )
				)
				( attribute "VOLTAGE" "16V"
					( Units "uVoltage" "V" 1.000000)
					( Origin gFrontEnd )
				)
				( attribute "XY" "(-6600,4375)"
					( Origin gFrontEnd )
				)
				( attribute "CHIPS_PART_NAME" "CAP"
					( Origin gPackager )
				)
				( attribute "CDS_PART_NAME" "CAP_1210-47UF,16V,20%,X6S,D384A"
					( Origin gPackager )
				)
				( objectStatus "C7F7" )
				( pin "a"
					( attribute "PN" "1"
						( Origin gPackager )
					)
					( objectStatus "C7F7.1" )
				)
				( pin "b"
					( attribute "PN" "2"
						( Origin gPackager )
					)
					( objectStatus "C7F7.2" )
				)
			)
			( gate "@baseboard_fab2_lib.baseboard_fab2(sch_1):page231_i154"
				( attribute "BOM_COST" "PVPP_ABC_VR"
					( Origin gFrontEnd )
				)
				( attribute "CDS_LIB" "mstr_discrete"
					( Origin gPackager )
				)
				( attribute "CDS_LOCATION" "R7F8"
					( Origin gPackager )
				)
				( attribute "CDS_SEC" "1"
					( Origin gPackager )
				)
				( attribute "LOCATION" "R7F8"
					( Origin gFrontEnd )
				)
				( attribute "MATERIAL" "CHIP"
					( Origin gFrontEnd )
				)
				( attribute "PACK_TYPE" "0402"
					( Origin gFrontEnd )
				)
				( attribute "PART_NUMBER" "G21497-005"
					( Origin gFrontEnd )
				)
				( attribute "PHYS_PAGE" "231"
					( Origin gFrontEnd )
				)
				( attribute "REUSE_ID" "13"
					( Origin gFrontEnd )
				)
				( attribute "ROOM" "PVPP_ABC_VR"
					( Origin gFrontEnd )
				)
				( attribute "ROT" "0"
					( Origin gFrontEnd )
				)
				( attribute "SEC" "1"
					( Origin gPackager )
				)
				( attribute "SPOF" "TRUE"
					( Origin gFrontEnd )
				)
				( attribute "TOLERANCE" "5%"
					( Origin gFrontEnd )
				)
				( attribute "VALUE" "0.0"
					( Origin gFrontEnd )
				)
				( attribute "VER" "1"
					( Origin gFrontEnd )
				)
				( attribute "WATTAGE" "1/16W"
					( Origin gFrontEnd )
				)
				( attribute "XY" "(-3725,4450)"
					( Origin gFrontEnd )
				)
				( attribute "CHIPS_PART_NAME" "RES"
					( Origin gPackager )
				)
				( attribute "CDS_PART_NAME" "RES_0402-0.0,5%,1/16W,CHIP,G21A"
					( Origin gPackager )
				)
				( objectStatus "R7F8" )
				( pin "a"
					( attribute "PN" "1"
						( Origin gPackager )
					)
					( objectStatus "R7F8.1" )
				)
				( pin "b"
					( attribute "PN" "2"
						( Origin gPackager )
					)
					( objectStatus "R7F8.2" )
				)
			)
			( gate "@baseboard_fab2_lib.baseboard_fab2(sch_1):page231_i159"
				( attribute "BOM_COST" "PVPP_KLM_VR"
					( Origin gFrontEnd )
				)
				( attribute "CDS_LIB" "mstr_discrete"
					( Origin gPackager )
				)
				( attribute "CDS_LOCATION" "C7F4"
					( Origin gPackager )
				)
				( attribute "CDS_SEC" "1"
					( Origin gPackager )
				)
				( attribute "LOCATION" "C7F4"
					( Origin gFrontEnd )
				)
				( attribute "MATERIAL" "X7R"
					( Origin gFrontEnd )
				)
				( attribute "PACK_TYPE" "0603LF"
					( Origin gFrontEnd )
				)
				( attribute "PART_NUMBER" "602433-020"
					( Origin gFrontEnd )
				)
				( attribute "PHYS_PAGE" "231"
					( Origin gFrontEnd )
				)
				( attribute "REUSE_ID" "27"
					( Origin gFrontEnd )
				)
				( attribute "ROOM" "PVPP_KLM_VR"
					( Origin gFrontEnd )
				)
				( attribute "ROT" "2"
					( Origin gFrontEnd )
				)
				( attribute "SEC" "1"
					( Origin gPackager )
				)
				( attribute "SPOF" "TRUE"
					( Origin gFrontEnd )
				)
				( attribute "TOLERANCE" "10%"
					( Origin gFrontEnd )
				)
				( attribute "VALUE" "0.1UF"
					( Origin gFrontEnd )
				)
				( attribute "VER" "2"
					( Origin gFrontEnd )
				)
				( attribute "VOLTAGE" "25V"
					( Units "uVoltage" "V" 1.000000)
					( Origin gFrontEnd )
				)
				( attribute "XY" "(-3025,4450)"
					( Origin gFrontEnd )
				)
				( attribute "CHIPS_PART_NAME" "CAP"
					( Origin gPackager )
				)
				( attribute "CDS_PART_NAME" "CAP_0603LF-0.1UF,25V,10%,X7R,6A"
					( Origin gPackager )
				)
				( objectStatus "C7F4" )
				( pin "a"
					( attribute "PN" "1"
						( Origin gPackager )
					)
					( objectStatus "C7F4.1" )
				)
				( pin "b"
					( attribute "PN" "2"
						( Origin gPackager )
					)
					( objectStatus "C7F4.2" )
				)
			)
			( gate "@baseboard_fab2_lib.baseboard_fab2(sch_1):page231_i161"
				( attribute "BOM_COST" "PVPP_KLM_VR"
					( Origin gFrontEnd )
				)
				( attribute "CDS_LIB" "mstr_discrete"
					( Origin gPackager )
				)
				( attribute "CDS_LOCATION" "C3T10"
					( Origin gPackager )
				)
				( attribute "CDS_SEC" "1"
					( Origin gPackager )
				)
				( attribute "FIN" "VR_1P2"
					( Origin gFrontEnd )
				)
				( attribute "LOCATION" "C3T10"
					( Origin gFrontEnd )
				)
				( attribute "MATERIAL" "X6S"
					( Origin gFrontEnd )
				)
				( attribute "PACK_TYPE" "0402"
					( Origin gFrontEnd )
				)
				( attribute "PART_NUMBER" "D97712-011"
					( Origin gFrontEnd )
				)
				( attribute "PHYS_PAGE" "231"
					( Origin gFrontEnd )
				)
				( attribute "REUSE_ID" "1"
					( Origin gFrontEnd )
				)
				( attribute "ROOM" "PVPP_KLM_VR"
					( Origin gFrontEnd )
				)
				( attribute "ROT" "0"
					( Origin gFrontEnd )
				)
				( attribute "SEC" "1"
					( Origin gPackager )
				)
				( attribute "TOLERANCE" "10%"
					( Origin gFrontEnd )
				)
				( attribute "VALUE" "1.0UF"
					( Origin gFrontEnd )
				)
				( attribute "VER" "1"
					( Origin gFrontEnd )
				)
				( attribute "VOLTAGE" "16V"
					( Units "uVoltage" "V" 1.000000)
					( Origin gFrontEnd )
				)
				( attribute "XY" "(-4600,4400)"
					( Origin gFrontEnd )
				)
				( attribute "CHIPS_PART_NAME" "CAP"
					( Origin gPackager )
				)
				( attribute "CDS_PART_NAME" "CAP_0402-1.0UF,16V,10%,X6S,D97A"
					( Origin gPackager )
				)
				( objectStatus "C3T10" )
				( pin "a"
					( attribute "PN" "1"
						( Origin gPackager )
					)
					( objectStatus "C3T10.1" )
				)
				( pin "b"
					( attribute "PN" "2"
						( Origin gPackager )
					)
					( objectStatus "C3T10.2" )
				)
			)
			( gate "@baseboard_fab2_lib.baseboard_fab2(sch_1):page231_i162"
				( attribute "CDS_LIB" "mstr_discrete"
					( Origin gPackager )
				)
				( attribute "CDS_LOCATION" "FB7F1"
					( Origin gPackager )
				)
				( attribute "CDS_SEC" "1"
					( Origin gPackager )
				)
				( attribute "LOCATION" "FB7F1"
					( Origin gFrontEnd )
				)
				( attribute "MATERIAL" "FB"
					( Origin gFrontEnd )
				)
				( attribute "PACK_TYPE" "SM"
					( Origin gFrontEnd )
				)
				( attribute "PART_NUMBER" "656554-051"
					( Origin gFrontEnd )
				)
				( attribute "PHYS_PAGE" "231"
					( Origin gFrontEnd )
				)
				( attribute "ROOM" "PVPP_KLM_VR"
					( Origin gFrontEnd )
				)
				( attribute "ROT" "0"
					( Origin gFrontEnd )
				)
				( attribute "SEC" "1"
					( Origin gFrontEnd )
				)
				( attribute "SEC_TYPE" "SM"
					( Origin gFrontEnd )
				)
				( attribute "TOLERANCE" "1%"
					( Origin gFrontEnd )
				)
				( attribute "VALUE" "22"
					( Origin gFrontEnd )
				)
				( attribute "VER" "1"
					( Origin gFrontEnd )
				)
				( attribute "XY" "(-6950,4550)"
					( Origin gFrontEnd )
				)
				( attribute "CHIPS_PART_NAME" "FERRITE"
					( Origin gPackager )
				)
				( attribute "CDS_PART_NAME" "FERRITE_SM-22,FB,656554-051"
					( Origin gPackager )
				)
				( objectStatus "FB7F1" )
				( pin "a"
					( attribute "PN" "1"
						( Origin gPackager )
					)
					( objectStatus "FB7F1.1" )
				)
				( pin "b"
					( attribute "PN" "2"
						( Origin gPackager )
					)
					( objectStatus "FB7F1.2" )
				)
			)
			( gate "@baseboard_fab2_lib.baseboard_fab2(sch_1):page231_i166"
				( attribute "BOM_COST" "PVPP_KLM_VR"
					( Origin gFrontEnd )
				)
				( attribute "CDS_LIB" "mstr_discrete"
					( Origin gPackager )
				)
				( attribute "CDS_LOCATION" "R7F11"
					( Origin gPackager )
				)
				( attribute "CDS_SEC" "1"
					( Origin gPackager )
				)
				( attribute "LOCATION" "R7F11"
					( Origin gFrontEnd )
				)
				( attribute "MATERIAL" "CHIP"
					( Origin gFrontEnd )
				)
				( attribute "PACK_TYPE" "0402"
					( Origin gFrontEnd )
				)
				( attribute "PART_NUMBER" "G21796-146"
					( Origin gFrontEnd )
				)
				( attribute "PHYS_PAGE" "231"
					( Origin gFrontEnd )
				)
				( attribute "REUSE_ID" "7"
					( Origin gFrontEnd )
				)
				( attribute "ROOM" "PVPP_KLM_VR"
					( Origin gFrontEnd )
				)
				( attribute "ROT" "0"
					( Origin gFrontEnd )
				)
				( attribute "SEC" "1"
					( Origin gPackager )
				)
				( attribute "SPOF" "TRUE"
					( Origin gFrontEnd )
				)
				( attribute "TOLERANCE" "1%"
					( Origin gFrontEnd )
				)
				( attribute "VALUE" "6.34K"
					( Origin gFrontEnd )
				)
				( attribute "VER" "2"
					( Origin gFrontEnd )
				)
				( attribute "WATTAGE" "1/16W"
					( Origin gFrontEnd )
				)
				( attribute "XY" "(-1000,1800)"
					( Origin gFrontEnd )
				)
				( attribute "CHIPS_PART_NAME" "RES"
					( Origin gPackager )
				)
				( attribute "CDS_PART_NAME" "RES_0402-6.34K,1%,1/16W,CHIP,GA"
					( Origin gPackager )
				)
				( objectStatus "R7F11" )
				( pin "a"
					( attribute "PN" "1"
						( Origin gPackager )
					)
					( objectStatus "R7F11.1" )
				)
				( pin "b"
					( attribute "PN" "2"
						( Origin gPackager )
					)
					( objectStatus "R7F11.2" )
				)
			)
			( gate "@baseboard_fab2_lib.baseboard_fab2(sch_1):page231_i167"
				( attribute "BOM_COST" "PVPP_KLM_VR"
					( Origin gFrontEnd )
				)
				( attribute "CDS_LIB" "mstr_discrete"
					( Origin gPackager )
				)
				( attribute "CDS_LOCATION" "R7F13"
					( Origin gPackager )
				)
				( attribute "CDS_SEC" "1"
					( Origin gPackager )
				)
				( attribute "LOCATION" "R7F13"
					( Origin gFrontEnd )
				)
				( attribute "MATERIAL" "CHIP"
					( Origin gFrontEnd )
				)
				( attribute "PACK_TYPE" "0402"
					( Origin gFrontEnd )
				)
				( attribute "PART_NUMBER" "G21796-040"
					( Origin gFrontEnd )
				)
				( attribute "PHYS_PAGE" "231"
					( Origin gFrontEnd )
				)
				( attribute "REUSE_ID" "9"
					( Origin gFrontEnd )
				)
				( attribute "ROOM" "PVPP_KLM_VR"
					( Origin gFrontEnd )
				)
				( attribute "ROT" "0"
					( Origin gFrontEnd )
				)
				( attribute "SEC" "1"
					( Origin gPackager )
				)
				( attribute "SPOF" "TRUE"
					( Origin gFrontEnd )
				)
				( attribute "TOLERANCE" "1%"
					( Origin gFrontEnd )
				)
				( attribute "VALUE" "20.0K"
					( Origin gFrontEnd )
				)
				( attribute "VER" "2"
					( Origin gFrontEnd )
				)
				( attribute "WATTAGE" "1/16W"
					( Origin gFrontEnd )
				)
				( attribute "XY" "(-1000,2425)"
					( Origin gFrontEnd )
				)
				( attribute "CHIPS_PART_NAME" "RES"
					( Origin gPackager )
				)
				( attribute "CDS_PART_NAME" "RES_0402-20.0K,1%,1/16W,CHIP,GA"
					( Origin gPackager )
				)
				( objectStatus "R7F13" )
				( pin "a"
					( attribute "PN" "1"
						( Origin gPackager )
					)
					( objectStatus "R7F13.1" )
				)
				( pin "b"
					( attribute "PN" "2"
						( Origin gPackager )
					)
					( objectStatus "R7F13.2" )
				)
			)
			( gate "@baseboard_fab2_lib.baseboard_fab2(sch_1):page231_i168"
				( attribute "CDS_LIB" "mstr_discrete"
					( Origin gPackager )
				)
				( attribute "CDS_LOCATION" "R7F12"
					( Origin gPackager )
				)
				( attribute "CDS_SEC" "1"
					( Origin gPackager )
				)
				( attribute "LOCATION" "R7F12"
					( Origin gFrontEnd )
				)
				( attribute "MATERIAL" "CHIP"
					( Origin gFrontEnd )
				)
				( attribute "PACK_TYPE" "0402"
					( Origin gFrontEnd )
				)
				( attribute "PART_NUMBER" "G21497-005"
					( Origin gFrontEnd )
				)
				( attribute "PHYS_PAGE" "231"
					( Origin gFrontEnd )
				)
				( attribute "ROOM" "PVPP_KLM_VR"
					( Origin gFrontEnd )
				)
				( attribute "ROT" "5"
					( Origin gFrontEnd )
				)
				( attribute "SEC" "1"
					( Origin gFrontEnd )
				)
				( attribute "SEC_TYPE" "0402"
					( Origin gFrontEnd )
				)
				( attribute "SPOF" "TRUE"
					( Origin gFrontEnd )
				)
				( attribute "TOLERANCE" "5%"
					( Origin gFrontEnd )
				)
				( attribute "VALUE" "0.0"
					( Origin gFrontEnd )
				)
				( attribute "VER" "1"
					( Origin gFrontEnd )
				)
				( attribute "WATTAGE" "1/16W"
					( Origin gFrontEnd )
				)
				( attribute "XY" "(-1000,3175)"
					( Origin gFrontEnd )
				)
				( attribute "CHIPS_PART_NAME" "RES"
					( Origin gPackager )
				)
				( attribute "CDS_PART_NAME" "RES_0402-0.0,5%,1/16W,CHIP,G21A"
					( Origin gPackager )
				)
				( objectStatus "R7F12" )
				( pin "a"
					( attribute "PN" "1"
						( Origin gPackager )
					)
					( objectStatus "R7F12.1" )
				)
				( pin "b"
					( attribute "PN" "2"
						( Origin gPackager )
					)
					( objectStatus "R7F12.2" )
				)
			)
			( gate "@baseboard_fab2_lib.baseboard_fab2(sch_1):page231_i170"
				( attribute "CDS_LIB" "mstr_discrete"
					( Origin gPackager )
				)
				( attribute "CDS_LOCATION" "R7F35"
					( Origin gPackager )
				)
				( attribute "CDS_SEC" "1"
					( Origin gPackager )
				)
				( attribute "LOCATION" "R7F35"
					( Origin gFrontEnd )
				)
				( attribute "MATERIAL" "CHIP"
					( Origin gFrontEnd )
				)
				( attribute "PACK_TYPE" "0402"
					( Origin gFrontEnd )
				)
				( attribute "PART_NUMBER" "G21497-005"
					( Origin gFrontEnd )
				)
				( attribute "PHYS_PAGE" "231"
					( Origin gFrontEnd )
				)
				( attribute "ROOM" "PVPP_KLM_VR"
					( Origin gFrontEnd )
				)
				( attribute "ROT" "0"
					( Origin gFrontEnd )
				)
				( attribute "SEC" "1"
					( Origin gPackager )
				)
				( attribute "TOLERANCE" "5%"
					( Origin gFrontEnd )
				)
				( attribute "VALUE" "0.0"
					( Origin gFrontEnd )
				)
				( attribute "VER" "1"
					( Origin gFrontEnd )
				)
				( attribute "WATTAGE" "1/16W"
					( Origin gFrontEnd )
				)
				( attribute "XY" "(-950,725)"
					( Origin gFrontEnd )
				)
				( attribute "CHIPS_PART_NAME" "RES"
					( Origin gPackager )
				)
				( attribute "CDS_PART_NAME" "RES_0402-0.0,5%,1/16W,CHIP,G21A"
					( Origin gPackager )
				)
				( objectStatus "R7F35" )
				( pin "a"
					( attribute "PN" "1"
						( Origin gPackager )
					)
					( objectStatus "R7F35.1" )
				)
				( pin "b"
					( attribute "PN" "2"
						( Origin gPackager )
					)
					( objectStatus "R7F35.2" )
				)
			)
			( gate "@baseboard_fab2_lib.baseboard_fab2(sch_1):page231_i174"
				( attribute "BOM_COST" "PVPP_KLM_VR"
					( Origin gFrontEnd )
				)
				( attribute "CDS_LIB" "mstr_discrete"
					( Origin gPackager )
				)
				( attribute "CDS_LOCATION" "R7F7"
					( Origin gPackager )
				)
				( attribute "CDS_SEC" "1"
					( Origin gPackager )
				)
				( attribute "LOCATION" "R7F7"
					( Origin gFrontEnd )
				)
				( attribute "MATERIAL" "EMPTY"
					( Origin gFrontEnd )
				)
				( attribute "PACK_TYPE" "0402"
					( Origin gFrontEnd )
				)
				( attribute "PART_NUMBER" "G21497-016"
					( Origin gFrontEnd )
				)
				( attribute "PHYS_PAGE" "231"
					( Origin gFrontEnd )
				)
				( attribute "REUSE_ID" "29"
					( Origin gFrontEnd )
				)
				( attribute "ROOM" "PVPP_KLM_VR"
					( Origin gFrontEnd )
				)
				( attribute "ROT" "0"
					( Origin gFrontEnd )
				)
				( attribute "SEC" "1"
					( Origin gPackager )
				)
				( attribute "TOLERANCE" "5%"
					( Origin gFrontEnd )
				)
				( attribute "VALUE" "2.2"
					( Origin gFrontEnd )
				)
				( attribute "VER" "2"
					( Origin gFrontEnd )
				)
				( attribute "WATTAGE" "1/16W"
					( Origin gFrontEnd )
				)
				( attribute "XY" "(-2300,3600)"
					( Origin gFrontEnd )
				)
				( attribute "CHIPS_PART_NAME" "RES"
					( Origin gPackager )
				)
				( attribute "CDS_PART_NAME" "RES_0402-2.2,5%,1/16W,EMPTY,G2A"
					( Origin gPackager )
				)
				( objectStatus "R7F7" )
				( pin "a"
					( attribute "PN" "1"
						( Origin gPackager )
					)
					( objectStatus "R7F7.1" )
				)
				( pin "b"
					( attribute "PN" "2"
						( Origin gPackager )
					)
					( objectStatus "R7F7.2" )
				)
			)
			( gate "@baseboard_fab2_lib.baseboard_fab2(sch_1):page231_i175"
				( attribute "BOM_COST" "PVPP_KLM_VR"
					( Origin gFrontEnd )
				)
				( attribute "CDS_LIB" "mstr_discrete"
					( Origin gPackager )
				)
				( attribute "CDS_LOCATION" "C7F3"
					( Origin gPackager )
				)
				( attribute "CDS_SEC" "1"
					( Origin gPackager )
				)
				( attribute "LOCATION" "C7F3"
					( Origin gFrontEnd )
				)
				( attribute "MATERIAL" "EMPTY"
					( Origin gFrontEnd )
				)
				( attribute "PACK_TYPE" "0402LF"
					( Origin gFrontEnd )
				)
				( attribute "PART_NUMBER" "A36096-091"
					( Origin gFrontEnd )
				)
				( attribute "PHYS_PAGE" "231"
					( Origin gFrontEnd )
				)
				( attribute "REUSE_ID" "26"
					( Origin gFrontEnd )
				)
				( attribute "ROOM" "PVPP_KLM_VR"
					( Origin gFrontEnd )
				)
				( attribute "ROT" "0"
					( Origin gFrontEnd )
				)
				( attribute "SEC" "1"
					( Origin gPackager )
				)
				( attribute "TOLERANCE" "10%"
					( Origin gFrontEnd )
				)
				( attribute "VALUE" "3300PF"
					( Origin gFrontEnd )
				)
				( attribute "VER" "1"
					( Origin gFrontEnd )
				)
				( attribute "VOLTAGE" "50V"
					( Units "uVoltage" "V" 1.000000)
					( Origin gFrontEnd )
				)
				( attribute "XY" "(-2300,3950)"
					( Origin gFrontEnd )
				)
				( attribute "CHIPS_PART_NAME" "CAP"
					( Origin gPackager )
				)
				( attribute "CDS_PART_NAME" "CAP_0402LF-3300PF,50V,10%,EMPTA"
					( Origin gPackager )
				)
				( objectStatus "C7F3" )
				( pin "a"
					( attribute "PN" "1"
						( Origin gPackager )
					)
					( objectStatus "C7F3.1" )
				)
				( pin "b"
					( attribute "PN" "2"
						( Origin gPackager )
					)
					( objectStatus "C7F3.2" )
				)
			)
			( gate "@baseboard_fab2_lib.baseboard_fab2(sch_1):page231_i177"
				( attribute "BOM_COST" "PVPP_KLM_VR"
					( Origin gFrontEnd )
				)
				( attribute "CDS_LIB" "mstr_discrete"
					( Origin gPackager )
				)
				( attribute "CDS_LOCATION" "R7F10"
					( Origin gPackager )
				)
				( attribute "CDS_SEC" "1"
					( Origin gPackager )
				)
				( attribute "LOCATION" "R7F10"
					( Origin gFrontEnd )
				)
				( attribute "MATERIAL" "CHIP"
					( Origin gFrontEnd )
				)
				( attribute "PACK_TYPE" "0603"
					( Origin gFrontEnd )
				)
				( attribute "PART_NUMBER" "G22026-003"
					( Origin gFrontEnd )
				)
				( attribute "PHYS_PAGE" "231"
					( Origin gFrontEnd )
				)
				( attribute "REUSE_ID" "34"
					( Origin gFrontEnd )
				)
				( attribute "ROOM" "PVPP_KLM_VR"
					( Origin gFrontEnd )
				)
				( attribute "ROT" "0"
					( Origin gFrontEnd )
				)
				( attribute "SEC" "1"
					( Origin gFrontEnd )
				)
				( attribute "SEC_TYPE" "0603"
					( Origin gFrontEnd )
				)
				( attribute "TOLERANCE" "1%"
					( Origin gFrontEnd )
				)
				( attribute "VALUE" "120.0"
					( Origin gFrontEnd )
				)
				( attribute "VER" "2"
					( Origin gFrontEnd )
				)
				( attribute "WATTAGE" "1/10W"
					( Origin gFrontEnd )
				)
				( attribute "XY" "(-1725,3925)"
					( Origin gFrontEnd )
				)
				( attribute "CHIPS_PART_NAME" "RES"
					( Origin gPackager )
				)
				( attribute "CDS_PART_NAME" "RES_0603-120.0,1%,1/10W,CHIP,GA"
					( Origin gPackager )
				)
				( objectStatus "R7F10" )
				( pin "a"
					( attribute "PN" "1"
						( Origin gPackager )
					)
					( objectStatus "R7F10.1" )
				)
				( pin "b"
					( attribute "PN" "2"
						( Origin gPackager )
					)
					( objectStatus "R7F10.2" )
				)
			)
			( gate "@baseboard_fab2_lib.baseboard_fab2(sch_1):page231_i178"
				( attribute "BOM_COST" "PVPP_KLM_VR"
					( Origin gFrontEnd )
				)
				( attribute "CDS_LIB" "mstr_discrete"
					( Origin gPackager )
				)
				( attribute "CDS_LOCATION" "L7F1"
					( Origin gPackager )
				)
				( attribute "CDS_SEC" "1"
					( Origin gPackager )
				)
				( attribute "LOCATION" "L7F1"
					( Origin gFrontEnd )
				)
				( attribute "MATERIAL" "IND"
					( Origin gFrontEnd )
				)
				( attribute "PACK_TYPE" "SM"
					( Origin gFrontEnd )
				)
				( attribute "PART_NUMBER" "E13358-018"
					( Origin gFrontEnd )
				)
				( attribute "PHYS_PAGE" "231"
					( Origin gFrontEnd )
				)
				( attribute "REUSE_ID" "30"
					( Origin gFrontEnd )
				)
				( attribute "ROOM" "PVPP_KLM_VR"
					( Origin gFrontEnd )
				)
				( attribute "ROT" "0"
					( Origin gFrontEnd )
				)
				( attribute "SEC" "1"
					( Origin gPackager )
				)
				( attribute "TOLERANCE" "1%"
					( Origin gFrontEnd )
				)
				( attribute "VALUE" "0.47UH"
					( Origin gFrontEnd )
				)
				( attribute "VER" "1"
					( Origin gFrontEnd )
				)
				( attribute "XY" "(-1950,4100)"
					( Origin gFrontEnd )
				)
				( attribute "CHIPS_PART_NAME" "INDUCTOR"
					( Origin gPackager )
				)
				( attribute "CDS_PART_NAME" "INDUCTOR_SM-0.47UH,IND,E13358-A"
					( Origin gPackager )
				)
				( objectStatus "L7F1" )
				( pin "ina"
					( attribute "PN" "1"
						( Origin gPackager )
					)
					( objectStatus "L7F1.1" )
				)
				( pin "inb"
					( attribute "PN" "2"
						( Origin gPackager )
					)
					( objectStatus "L7F1.2" )
				)
			)
			( gate "@baseboard_fab2_lib.baseboard_fab2(sch_1):page231_i180"
				( attribute "BOM_COST" "PVPP_KLM_VR"
					( Origin gFrontEnd )
				)
				( attribute "CDS_LIB" "mstr_discrete"
					( Origin gPackager )
				)
				( attribute "CDS_LOCATION" "C6F4"
					( Origin gPackager )
				)
				( attribute "CDS_SEC" "1"
					( Origin gPackager )
				)
				( attribute "LOCATION" "C6F4"
					( Origin gFrontEnd )
				)
				( attribute "MATERIAL" "POSCAP"
					( Origin gFrontEnd )
				)
				( attribute "PACK_TYPE" "7343LF"
					( Origin gFrontEnd )
				)
				( attribute "PART_NUMBER" "724613-042"
					( Origin gFrontEnd )
				)
				( attribute "PHYS_PAGE" "231"
					( Origin gFrontEnd )
				)
				( attribute "REUSE_ID" "28"
					( Origin gFrontEnd )
				)
				( attribute "ROOM" "PVPP_KLM_VR"
					( Origin gFrontEnd )
				)
				( attribute "ROT" "0"
					( Origin gFrontEnd )
				)
				( attribute "SEC" "1"
					( Origin gPackager )
				)
				( attribute "TOLERANCE" "20%"
					( Origin gFrontEnd )
				)
				( attribute "VALUE" "330UF"
					( Origin gFrontEnd )
				)
				( attribute "VER" "1"
					( Origin gFrontEnd )
				)
				( attribute "VOLTAGE" "6.3V"
					( Units "uVoltage" "V" 1.000000)
					( Origin gFrontEnd )
				)
				( attribute "XY" "(-1400,3925)"
					( Origin gFrontEnd )
				)
				( attribute "CHIPS_PART_NAME" "CAPP"
					( Origin gPackager )
				)
				( attribute "CDS_PART_NAME" "CAPP_7343LF-330UF,6.3V,20%,POSA"
					( Origin gPackager )
				)
				( objectStatus "C6F4" )
				( pin "a"
					( attribute "PN" "1"
						( Origin gPackager )
					)
					( objectStatus "C6F4.1" )
				)
				( pin "b"
					( attribute "PN" "2"
						( Origin gPackager )
					)
					( objectStatus "C6F4.2" )
				)
			)
			( gate "@baseboard_fab2_lib.baseboard_fab2(sch_1):page231_i184"
				( attribute "BOM_COST" "PVPP_KLM_VR"
					( Origin gFrontEnd )
				)
				( attribute "CDS_LIB" "mstr_discrete"
					( Origin gPackager )
				)
				( attribute "CDS_LOCATION" "C3T7"
					( Origin gPackager )
				)
				( attribute "CDS_SEC" "1"
					( Origin gPackager )
				)
				( attribute "LOCATION" "C3T7"
					( Origin gFrontEnd )
				)
				( attribute "MATERIAL" "X6S"
					( Origin gFrontEnd )
				)
				( attribute "PACK_TYPE" "0805"
					( Origin gFrontEnd )
				)
				( attribute "PART_NUMBER" "C95333-006"
					( Origin gFrontEnd )
				)
				( attribute "PHYS_PAGE" "231"
					( Origin gFrontEnd )
				)
				( attribute "REUSE_ID" "33"
					( Origin gFrontEnd )
				)
				( attribute "ROOM" "PVPP_KLM_VR"
					( Origin gFrontEnd )
				)
				( attribute "ROT" "0"
					( Origin gFrontEnd )
				)
				( attribute "SEC" "1"
					( Origin gPackager )
				)
				( attribute "TOLERANCE" "20%"
					( Origin gFrontEnd )
				)
				( attribute "VALUE" "47UF"
					( Origin gFrontEnd )
				)
				( attribute "VER" "1"
					( Origin gFrontEnd )
				)
				( attribute "VOLTAGE" "4V"
					( Units "uVoltage" "V" 1.000000)
					( Origin gFrontEnd )
				)
				( attribute "XY" "(-825,3925)"
					( Origin gFrontEnd )
				)
				( attribute "CHIPS_PART_NAME" "CAP"
					( Origin gPackager )
				)
				( attribute "CDS_PART_NAME" "CAP_0805-47UF,4V,20%,X6S,C9533A"
					( Origin gPackager )
				)
				( objectStatus "C3T7" )
				( pin "a"
					( attribute "PN" "1"
						( Origin gPackager )
					)
					( objectStatus "C3T7.1" )
				)
				( pin "b"
					( attribute "PN" "2"
						( Origin gPackager )
					)
					( objectStatus "C3T7.2" )
				)
			)
			( gate "@baseboard_fab2_lib.baseboard_fab2(sch_1):page231_i186"
				( attribute "BOM_COST" "PVPP_KLM_VR"
					( Origin gFrontEnd )
				)
				( attribute "CDS_LIB" "mstr_discrete"
					( Origin gPackager )
				)
				( attribute "CDS_LOCATION" "C3T9"
					( Origin gPackager )
				)
				( attribute "CDS_SEC" "1"
					( Origin gPackager )
				)
				( attribute "LOCATION" "C3T9"
					( Origin gFrontEnd )
				)
				( attribute "MATERIAL" "X6S"
					( Origin gFrontEnd )
				)
				( attribute "PACK_TYPE" "0805"
					( Origin gFrontEnd )
				)
				( attribute "PART_NUMBER" "C95333-006"
					( Origin gFrontEnd )
				)
				( attribute "PHYS_PAGE" "231"
					( Origin gFrontEnd )
				)
				( attribute "REUSE_ID" "33"
					( Origin gFrontEnd )
				)
				( attribute "ROOM" "PVPP_KLM_VR"
					( Origin gFrontEnd )
				)
				( attribute "ROT" "0"
					( Origin gFrontEnd )
				)
				( attribute "SEC" "1"
					( Origin gPackager )
				)
				( attribute "TOLERANCE" "20%"
					( Origin gFrontEnd )
				)
				( attribute "VALUE" "47UF"
					( Origin gFrontEnd )
				)
				( attribute "VER" "1"
					( Origin gFrontEnd )
				)
				( attribute "VOLTAGE" "4V"
					( Units "uVoltage" "V" 1.000000)
					( Origin gFrontEnd )
				)
				( attribute "XY" "(-525,3925)"
					( Origin gFrontEnd )
				)
				( attribute "CHIPS_PART_NAME" "CAP"
					( Origin gPackager )
				)
				( attribute "CDS_PART_NAME" "CAP_0805-47UF,4V,20%,X6S,C9533A"
					( Origin gPackager )
				)
				( objectStatus "C3T9" )
				( pin "a"
					( attribute "PN" "1"
						( Origin gPackager )
					)
					( objectStatus "C3T9.1" )
				)
				( pin "b"
					( attribute "PN" "2"
						( Origin gPackager )
					)
					( objectStatus "C3T9.2" )
				)
			)
			( gate "@baseboard_fab2_lib.baseboard_fab2(sch_1):page231_i193"
				( attribute "CDS_LIB" "mstr_vreg"
					( Origin gPackager )
				)
				( attribute "CDS_LMAN_SYM_OUTLINE" "-450,850,450,-900"
					( Origin gPackager )
				)
				( attribute "CDS_LOCATION" "EU7F1"
					( Origin gPackager )
				)
				( attribute "CDS_SEC" "1"
					( Origin gPackager )
				)
				( attribute "LOCATION" "EU7F1"
					( Origin gFrontEnd )
				)
				( attribute "MATERIAL" "IC"
					( Origin gFrontEnd )
				)
				( attribute "PACK_TYPE" "SM"
					( Origin gFrontEnd )
				)
				( attribute "PART_NUMBER" "H86355-001"
					( Origin gFrontEnd )
				)
				( attribute "PHYS_PAGE" "231"
					( Origin gFrontEnd )
				)
				( attribute "ROT" "0"
					( Origin gFrontEnd )
				)
				( attribute "SEC" "1"
					( Origin gFrontEnd )
				)
				( attribute "SEC_TYPE" "SM"
					( Origin gFrontEnd )
				)
				( attribute "VER" "1"
					( Origin gFrontEnd )
				)
				( attribute "XY" "(-3450,3125)"
					( Origin gFrontEnd )
				)
				( attribute "CHIPS_PART_NAME" "NCP3232L"
					( Origin gPackager )
				)
				( attribute "CDS_PART_NAME" "NCP3232L_SM-IC,H86355-001"
					( Origin gPackager )
				)
				( objectStatus "EU7F1" )
				( pin "agnd"
					( attribute "PN" "5"
						( Origin gPackager )
					)
					( objectStatus "EU7F1.5" )
				)
				( pin "bst"
					( attribute "PN" "36"
						( Origin gPackager )
					)
					( objectStatus "EU7F1.36" )
				)
				( pin "comp"
					( attribute "PN" "3"
						( Origin gPackager )
					)
					( objectStatus "EU7F1.3" )
				)
				( pin "en"
					( attribute "PN" "40"
						( Origin gPackager )
					)
					( objectStatus "EU7F1.40" )
				)
				( pin "fb"
					( attribute "PN" "2"
						( Origin gPackager )
					)
					( objectStatus "EU7F1.2" )
				)
				( pin "gnd"
					( attribute "PN" "41"
						( Origin gPackager )
					)
					( objectStatus "EU7F1.41" )
				)
				( pin "iset"
					( attribute "PN" "4"
						( Origin gPackager )
					)
					( objectStatus "EU7F1.4" )
				)
				( pin "ots"
					( attribute "PN" "6"
						( Origin gPackager )
					)
					( objectStatus "EU7F1.6" )
				)
				( pin "pg"
					( attribute "PN" "7"
						( Origin gPackager )
					)
					( objectStatus "EU7F1.7" )
				)
				( pin "pgnd(0)"
					( attribute "PN" "16"
						( Origin gPackager )
					)
					( objectStatus "EU7F1.16" )
				)
				( pin "pgnd(1)"
					( attribute "PN" "17"
						( Origin gPackager )
					)
					( objectStatus "EU7F1.17" )
				)
				( pin "pgnd(2)"
					( attribute "PN" "18"
						( Origin gPackager )
					)
					( objectStatus "EU7F1.18" )
				)
				( pin "pgnd(3)"
					( attribute "PN" "19"
						( Origin gPackager )
					)
					( objectStatus "EU7F1.19" )
				)
				( pin "pgnd(4)"
					( attribute "PN" "20"
						( Origin gPackager )
					)
					( objectStatus "EU7F1.20" )
				)
				( pin "pgnd(5)"
					( attribute "PN" "21"
						( Origin gPackager )
					)
					( objectStatus "EU7F1.21" )
				)
				( pin "pgnd(6)"
					( attribute "PN" "22"
						( Origin gPackager )
					)
					( objectStatus "EU7F1.22" )
				)
				( pin "pgnd(7)"
					( attribute "PN" "23"
						( Origin gPackager )
					)
					( objectStatus "EU7F1.23" )
				)
				( pin "pgnd(8)"
					( attribute "PN" "24"
						( Origin gPackager )
					)
					( objectStatus "EU7F1.24" )
				)
				( pin "pgnd(9)"
					( attribute "PN" "25"
						( Origin gPackager )
					)
					( objectStatus "EU7F1.25" )
				)
				( pin "pgnd(10)"
					( attribute "PN" "26"
						( Origin gPackager )
					)
					( objectStatus "EU7F1.26" )
				)
				( pin "pgnd(11)"
					( attribute "PN" "27"
						( Origin gPackager )
					)
					( objectStatus "EU7F1.27" )
				)
				( pin "pgnd(12)"
					( attribute "PN" "28"
						( Origin gPackager )
					)
					( objectStatus "EU7F1.28" )
				)
				( pin "pgnd(13)"
					( attribute "PN" "37"
						( Origin gPackager )
					)
					( objectStatus "EU7F1.37" )
				)
				( pin "ss"
					( attribute "PN" "1"
						( Origin gPackager )
					)
					( objectStatus "EU7F1.1" )
				)
				( pin "vb"
					( attribute "PN" "38"
						( Origin gPackager )
					)
					( objectStatus "EU7F1.38" )
				)
				( pin "vcc"
					( attribute "PN" "39"
						( Origin gPackager )
					)
					( objectStatus "EU7F1.39" )
				)
				( pin "vin(0)"
					( attribute "PN" "8"
						( Origin gPackager )
					)
					( objectStatus "EU7F1.8" )
				)
				( pin "vin(1)"
					( attribute "PN" "9"
						( Origin gPackager )
					)
					( objectStatus "EU7F1.9" )
				)
				( pin "vin(2)"
					( attribute "PN" "10"
						( Origin gPackager )
					)
					( objectStatus "EU7F1.10" )
				)
				( pin "vin(3)"
					( attribute "PN" "11"
						( Origin gPackager )
					)
					( objectStatus "EU7F1.11" )
				)
				( pin "vin(4)"
					( attribute "PN" "12"
						( Origin gPackager )
					)
					( objectStatus "EU7F1.12" )
				)
				( pin "vin(5)"
					( attribute "PN" "13"
						( Origin gPackager )
					)
					( objectStatus "EU7F1.13" )
				)
				( pin "vin(6)"
					( attribute "PN" "14"
						( Origin gPackager )
					)
					( objectStatus "EU7F1.14" )
				)
				( pin "vin(7)"
					( attribute "PN" "42"
						( Origin gPackager )
					)
					( objectStatus "EU7F1.42" )
				)
				( pin "vsw"
					( attribute "PN" "35"
						( Origin gPackager )
					)
					( objectStatus "EU7F1.35" )
				)
				( pin "vswh(0)"
					( attribute "PN" "15"
						( Origin gPackager )
					)
					( objectStatus "EU7F1.15" )
				)
				( pin "vswh(1)"
					( attribute "PN" "29"
						( Origin gPackager )
					)
					( objectStatus "EU7F1.29" )
				)
				( pin "vswh(2)"
					( attribute "PN" "30"
						( Origin gPackager )
					)
					( objectStatus "EU7F1.30" )
				)
				( pin "vswh(3)"
					( attribute "PN" "31"
						( Origin gPackager )
					)
					( objectStatus "EU7F1.31" )
				)
				( pin "vswh(4)"
					( attribute "PN" "32"
						( Origin gPackager )
					)
					( objectStatus "EU7F1.32" )
				)
				( pin "vswh(5)"
					( attribute "PN" "33"
						( Origin gPackager )
					)
					( objectStatus "EU7F1.33" )
				)
				( pin "vswh(6)"
					( attribute "PN" "34"
						( Origin gPackager )
					)
					( objectStatus "EU7F1.34" )
				)
				( pin "vswh(7)"
					( attribute "PN" "43"
						( Origin gPackager )
					)
					( objectStatus "EU7F1.43" )
				)
			)
			( gate "@baseboard_fab2_lib.baseboard_fab2(sch_1):page231_i194"
				( attribute "BOM_COST" "PVPP_KLM_VR"
					( Origin gFrontEnd )
				)
				( attribute "CDS_LIB" "mstr_discrete"
					( Origin gPackager )
				)
				( attribute "CDS_LOCATION" "C7F10"
					( Origin gPackager )
				)
				( attribute "CDS_SEC" "1"
					( Origin gPackager )
				)
				( attribute "LOCATION" "C7F10"
					( Origin gFrontEnd )
				)
				( attribute "MATERIAL" "X7R"
					( Origin gFrontEnd )
				)
				( attribute "PACK_TYPE" "0402"
					( Origin gFrontEnd )
				)
				( attribute "PART_NUMBER" "A36096-129"
					( Origin gFrontEnd )
				)
				( attribute "PHYS_PAGE" "231"
					( Origin gFrontEnd )
				)
				( attribute "REUSE_ID" "26"
					( Origin gFrontEnd )
				)
				( attribute "ROOM" "PVPP_KLM_VR"
					( Origin gFrontEnd )
				)
				( attribute "ROT" "0"
					( Origin gFrontEnd )
				)
				( attribute "SEC" "1"
					( Origin gFrontEnd )
				)
				( attribute "SEC_TYPE" "0402"
					( Origin gFrontEnd )
				)
				( attribute "TOLERANCE" "10%"
					( Origin gFrontEnd )
				)
				( attribute "VALUE" "0.027UF"
					( Origin gFrontEnd )
				)
				( attribute "VER" "1"
					( Origin gFrontEnd )
				)
				( attribute "VOLTAGE" "16V"
					( Units "uVoltage" "V" 1.000000)
					( Origin gFrontEnd )
				)
				( attribute "XY" "(-4725,2425)"
					( Origin gFrontEnd )
				)
				( attribute "CHIPS_PART_NAME" "CAP"
					( Origin gPackager )
				)
				( attribute "CDS_PART_NAME" "CAP_0402-0.027UF,16V,10%,X7R,AA"
					( Origin gPackager )
				)
				( objectStatus "C7F10" )
				( pin "a"
					( attribute "PN" "1"
						( Origin gPackager )
					)
					( objectStatus "C7F10.1" )
				)
				( pin "b"
					( attribute "PN" "2"
						( Origin gPackager )
					)
					( objectStatus "C7F10.2" )
				)
			)
			( gate "@baseboard_fab2_lib.baseboard_fab2(sch_1):page231_i199"
				( attribute "BOM_COST" "PVPP_KLM_VR"
					( Origin gFrontEnd )
				)
				( attribute "CDS_LIB" "mstr_discrete"
					( Origin gPackager )
				)
				( attribute "CDS_LOCATION" "C7F9"
					( Origin gPackager )
				)
				( attribute "CDS_SEC" "1"
					( Origin gPackager )
				)
				( attribute "LOCATION" "C7F9"
					( Origin gFrontEnd )
				)
				( attribute "MATERIAL" "COG"
					( Origin gFrontEnd )
				)
				( attribute "PACK_TYPE" "0402LF"
					( Origin gFrontEnd )
				)
				( attribute "PART_NUMBER" "A36095-026"
					( Origin gFrontEnd )
				)
				( attribute "PHYS_PAGE" "231"
					( Origin gFrontEnd )
				)
				( attribute "REUSE_ID" "27"
					( Origin gFrontEnd )
				)
				( attribute "ROOM" "PVPP_KLM_VR"
					( Origin gFrontEnd )
				)
				( attribute "ROT" "2"
					( Origin gFrontEnd )
				)
				( attribute "SEC" "1"
					( Origin gFrontEnd )
				)
				( attribute "SEC_TYPE" "0402LF"
					( Origin gFrontEnd )
				)
				( attribute "TOLERANCE" "5%"
					( Origin gFrontEnd )
				)
				( attribute "VALUE" "100.0PF"
					( Origin gFrontEnd )
				)
				( attribute "VER" "2"
					( Origin gFrontEnd )
				)
				( attribute "VOLTAGE" "50V"
					( Units "uVoltage" "V" 1.000000)
					( Origin gFrontEnd )
				)
				( attribute "XY" "(-2075,3075)"
					( Origin gFrontEnd )
				)
				( attribute "CHIPS_PART_NAME" "CAP"
					( Origin gPackager )
				)
				( attribute "CDS_PART_NAME" "CAP_0402LF-100.0PF,50V,5%,COG,A"
					( Origin gPackager )
				)
				( objectStatus "C7F9" )
				( pin "a"
					( attribute "PN" "1"
						( Origin gPackager )
					)
					( objectStatus "C7F9.1" )
				)
				( pin "b"
					( attribute "PN" "2"
						( Origin gPackager )
					)
					( objectStatus "C7F9.2" )
				)
			)
			( gate "@baseboard_fab2_lib.baseboard_fab2(sch_1):page231_i200"
				( attribute "BOM_COST" "PVPP_KLM_VR"
					( Origin gFrontEnd )
				)
				( attribute "CDS_LIB" "mstr_discrete"
					( Origin gPackager )
				)
				( attribute "CDS_LOCATION" "C7F12"
					( Origin gPackager )
				)
				( attribute "CDS_SEC" "1"
					( Origin gPackager )
				)
				( attribute "LOCATION" "C7F12"
					( Origin gFrontEnd )
				)
				( attribute "MATERIAL" "X7R"
					( Origin gFrontEnd )
				)
				( attribute "PACK_TYPE" "0402LF"
					( Origin gFrontEnd )
				)
				( attribute "PART_NUMBER" "A36096-075"
					( Origin gFrontEnd )
				)
				( attribute "PHYS_PAGE" "231"
					( Origin gFrontEnd )
				)
				( attribute "REUSE_ID" "27"
					( Origin gFrontEnd )
				)
				( attribute "ROOM" "PVPP_KLM_VR"
					( Origin gFrontEnd )
				)
				( attribute "ROT" "2"
					( Origin gFrontEnd )
				)
				( attribute "SEC" "1"
					( Origin gFrontEnd )
				)
				( attribute "SEC_TYPE" "0402LF"
					( Origin gFrontEnd )
				)
				( attribute "TOLERANCE" "10%"
					( Origin gFrontEnd )
				)
				( attribute "VALUE" "2200PF"
					( Origin gFrontEnd )
				)
				( attribute "VER" "2"
					( Origin gFrontEnd )
				)
				( attribute "VOLTAGE" "50V"
					( Units "uVoltage" "V" 1.000000)
					( Origin gFrontEnd )
				)
				( attribute "XY" "(-2500,2700)"
					( Origin gFrontEnd )
				)
				( attribute "CHIPS_PART_NAME" "CAP"
					( Origin gPackager )
				)
				( attribute "CDS_PART_NAME" "CAP_0402LF-2200PF,50V,10%,X7R,A"
					( Origin gPackager )
				)
				( objectStatus "C7F12" )
				( pin "a"
					( attribute "PN" "1"
						( Origin gPackager )
					)
					( objectStatus "C7F12.1" )
				)
				( pin "b"
					( attribute "PN" "2"
						( Origin gPackager )
					)
					( objectStatus "C7F12.2" )
				)
			)
			( gate "@baseboard_fab2_lib.baseboard_fab2(sch_1):page231_i201"
				( attribute "BOM_COST" "PVPP_KLM_VR"
					( Origin gFrontEnd )
				)
				( attribute "CDS_LIB" "mstr_discrete"
					( Origin gPackager )
				)
				( attribute "CDS_LOCATION" "R7F18"
					( Origin gPackager )
				)
				( attribute "CDS_SEC" "1"
					( Origin gPackager )
				)
				( attribute "LOCATION" "R7F18"
					( Origin gFrontEnd )
				)
				( attribute "MATERIAL" "CHIP"
					( Origin gFrontEnd )
				)
				( attribute "PACK_TYPE" "0402"
					( Origin gFrontEnd )
				)
				( attribute "PART_NUMBER" "G21796-242"
					( Origin gFrontEnd )
				)
				( attribute "PHYS_PAGE" "231"
					( Origin gFrontEnd )
				)
				( attribute "REUSE_ID" "13"
					( Origin gFrontEnd )
				)
				( attribute "ROOM" "PVPP_KLM_VR"
					( Origin gFrontEnd )
				)
				( attribute "ROT" "0"
					( Origin gFrontEnd )
				)
				( attribute "SEC" "1"
					( Origin gFrontEnd )
				)
				( attribute "SEC_TYPE" "0402"
					( Origin gFrontEnd )
				)
				( attribute "TOLERANCE" "1.0%"
					( Origin gFrontEnd )
				)
				( attribute "VALUE" "7.87K"
					( Origin gFrontEnd )
				)
				( attribute "VER" "1"
					( Origin gFrontEnd )
				)
				( attribute "WATTAGE" "1/16W"
					( Origin gFrontEnd )
				)
				( attribute "XY" "(-1800,2700)"
					( Origin gFrontEnd )
				)
				( attribute "CHIPS_PART_NAME" "RES"
					( Origin gPackager )
				)
				( attribute "CDS_PART_NAME" "RES_0402-7.87K,1.0%,1/16W,CHIPA"
					( Origin gPackager )
				)
				( objectStatus "R7F18" )
				( pin "a"
					( attribute "PN" "1"
						( Origin gPackager )
					)
					( objectStatus "R7F18.1" )
				)
				( pin "b"
					( attribute "PN" "2"
						( Origin gPackager )
					)
					( objectStatus "R7F18.2" )
				)
			)
			( gate "@baseboard_fab2_lib.baseboard_fab2(sch_1):page231_i202"
				( attribute "BOM_COST" "PVPP_KLM_VR"
					( Origin gFrontEnd )
				)
				( attribute "CDS_LIB" "mstr_discrete"
					( Origin gPackager )
				)
				( attribute "CDS_LOCATION" "C3T11"
					( Origin gPackager )
				)
				( attribute "CDS_SEC" "1"
					( Origin gPackager )
				)
				( attribute "LOCATION" "C3T11"
					( Origin gFrontEnd )
				)
				( attribute "MATERIAL" "X6S"
					( Origin gFrontEnd )
				)
				( attribute "PACK_TYPE" "0603"
					( Origin gFrontEnd )
				)
				( attribute "PART_NUMBER" "E15431-003"
					( Origin gFrontEnd )
				)
				( attribute "PHYS_PAGE" "231"
					( Origin gFrontEnd )
				)
				( attribute "REUSE_ID" "26"
					( Origin gFrontEnd )
				)
				( attribute "ROOM" "PVPP_KLM_VR"
					( Origin gFrontEnd )
				)
				( attribute "ROT" "0"
					( Origin gFrontEnd )
				)
				( attribute "SEC" "1"
					( Origin gFrontEnd )
				)
				( attribute "SEC_TYPE" "0603"
					( Origin gFrontEnd )
				)
				( attribute "TOLERANCE" "10%"
					( Origin gFrontEnd )
				)
				( attribute "VALUE" "4.7UF"
					( Origin gFrontEnd )
				)
				( attribute "VER" "1"
					( Origin gFrontEnd )
				)
				( attribute "VOLTAGE" "6.3V"
					( Units "uVoltage" "V" 1.000000)
					( Origin gFrontEnd )
				)
				( attribute "XY" "(-5375,2625)"
					( Origin gFrontEnd )
				)
				( attribute "CHIPS_PART_NAME" "CAP"
					( Origin gPackager )
				)
				( attribute "CDS_PART_NAME" "CAP_0603-4.7UF,6.3V,10%,X6S,E1A"
					( Origin gPackager )
				)
				( objectStatus "C3T11" )
				( pin "a"
					( attribute "PN" "1"
						( Origin gPackager )
					)
					( objectStatus "C3T11.1" )
				)
				( pin "b"
					( attribute "PN" "2"
						( Origin gPackager )
					)
					( objectStatus "C3T11.2" )
				)
			)
			( gate "@baseboard_fab2_lib.baseboard_fab2(sch_1):page231_i205"
				( attribute "CDS_LIB" "dev_discrete"
					( Origin gPackager )
				)
				( attribute "CDS_LOCATION" "C7F6"
					( Origin gPackager )
				)
				( attribute "CDS_SEC" "1"
					( Origin gPackager )
				)
				( attribute "LOCATION" "C7F6"
					( Origin gFrontEnd )
				)
				( attribute "MATERIAL" "X7R"
					( Origin gFrontEnd )
				)
				( attribute "PACK_TYPE" "0402V"
					( Origin gFrontEnd )
				)
				( attribute "PART_NUMBER" "A36096-030"
					( Origin gFrontEnd )
				)
				( attribute "PHYS_PAGE" "231"
					( Origin gFrontEnd )
				)
				( attribute "ROT" "0"
					( Origin gFrontEnd )
				)
				( attribute "SEC" "1"
					( Origin gFrontEnd )
				)
				( attribute "SEC_TYPE" "0402V"
					( Origin gFrontEnd )
				)
				( attribute "TOLERANCE" "10%"
					( Origin gFrontEnd )
				)
				( attribute "VALUE" "0.1UF"
					( Origin gFrontEnd )
				)
				( attribute "VER" "1"
					( Origin gFrontEnd )
				)
				( attribute "VOLTAGE" "16V"
					( Units "uVoltage" "V" 1.000000)
					( Origin gFrontEnd )
				)
				( attribute "XY" "(-4775,3750)"
					( Origin gFrontEnd )
				)
				( attribute "CHIPS_PART_NAME" "CAP_A"
					( Origin gPackager )
				)
				( attribute "CDS_PART_NAME" "CAP_A_0402V-0.1UF,16V,10%,X7R,A"
					( Origin gPackager )
				)
				( objectStatus "C7F6" )
				( pin "a"
					( attribute "PN" "1"
						( Origin gPackager )
					)
					( objectStatus "C7F6.1" )
				)
				( pin "b"
					( attribute "PN" "2"
						( Origin gPackager )
					)
					( objectStatus "C7F6.2" )
				)
			)
			( gate "@baseboard_fab2_lib.baseboard_fab2(sch_1):page231_i208"
				( attribute "CDS_LIB" "mstr_discrete"
					( Origin gPackager )
				)
				( attribute "CDS_LOCATION" "R7F16"
					( Origin gPackager )
				)
				( attribute "CDS_SEC" "1"
					( Origin gPackager )
				)
				( attribute "LOCATION" "R7F16"
					( Origin gFrontEnd )
				)
				( attribute "MATERIAL" "CHIP"
					( Origin gFrontEnd )
				)
				( attribute "PACK_TYPE" "0402"
					( Origin gFrontEnd )
				)
				( attribute "PART_NUMBER" "G21796-250"
					( Origin gFrontEnd )
				)
				( attribute "PHYS_PAGE" "231"
					( Origin gFrontEnd )
				)
				( attribute "ROOM" "PVPP_KLM_VR"
					( Origin gFrontEnd )
				)
				( attribute "ROT" "0"
					( Origin gFrontEnd )
				)
				( attribute "SEC" "1"
					( Origin gFrontEnd )
				)
				( attribute "SEC_TYPE" "0402"
					( Origin gFrontEnd )
				)
				( attribute "TOLERANCE" "1.0%"
					( Origin gFrontEnd )
				)
				( attribute "VALUE" "22.1"
					( Origin gFrontEnd )
				)
				( attribute "VER" "1"
					( Origin gFrontEnd )
				)
				( attribute "WATTAGE" "1/16W"
					( Origin gFrontEnd )
				)
				( attribute "XY" "(-3000,1225)"
					( Origin gFrontEnd )
				)
				( attribute "CHIPS_PART_NAME" "RES"
					( Origin gPackager )
				)
				( attribute "CDS_PART_NAME" "RES_0402-22.1,1.0%,1/16W,CHIP,A"
					( Origin gPackager )
				)
				( objectStatus "R7F16" )
				( pin "a"
					( attribute "PN" "1"
						( Origin gPackager )
					)
					( objectStatus "R7F16.1" )
				)
				( pin "b"
					( attribute "PN" "2"
						( Origin gPackager )
					)
					( objectStatus "R7F16.2" )
				)
			)
			( gate "@baseboard_fab2_lib.baseboard_fab2(sch_1):page231_i209"
				( attribute "CDS_LIB" "mstr_discrete"
					( Origin gPackager )
				)
				( attribute "CDS_LOCATION" "C7F5"
					( Origin gPackager )
				)
				( attribute "CDS_SEC" "1"
					( Origin gPackager )
				)
				( attribute "LOCATION" "C7F5"
					( Origin gFrontEnd )
				)
				( attribute "MATERIAL" "X6S"
					( Origin gFrontEnd )
				)
				( attribute "PACK_TYPE" "0805"
					( Origin gFrontEnd )
				)
				( attribute "PART_NUMBER" "C95333-007"
					( Origin gFrontEnd )
				)
				( attribute "PHYS_PAGE" "231"
					( Origin gFrontEnd )
				)
				( attribute "ROT" "0"
					( Origin gFrontEnd )
				)
				( attribute "SEC" "1"
					( Origin gFrontEnd )
				)
				( attribute "SEC_TYPE" "0805"
					( Origin gFrontEnd )
				)
				( attribute "TOLERANCE" "10%"
					( Origin gFrontEnd )
				)
				( attribute "VALUE" "10UF"
					( Origin gFrontEnd )
				)
				( attribute "VER" "1"
					( Origin gFrontEnd )
				)
				( attribute "VOLTAGE" "16V"
					( Units "uVoltage" "V" 1.000000)
					( Origin gFrontEnd )
				)
				( attribute "XY" "(-6300,4375)"
					( Origin gFrontEnd )
				)
				( attribute "CHIPS_PART_NAME" "CAP"
					( Origin gPackager )
				)
				( attribute "CDS_PART_NAME" "CAP_0805-10UF,16V,10%,X6S,C953A"
					( Origin gPackager )
				)
				( objectStatus "C7F5" )
				( pin "a"
					( attribute "PN" "1"
						( Origin gPackager )
					)
					( objectStatus "C7F5.1" )
				)
				( pin "b"
					( attribute "PN" "2"
						( Origin gPackager )
					)
					( objectStatus "C7F5.2" )
				)
			)
			( gate "@baseboard_fab2_lib.baseboard_fab2(sch_1):page231_i210"
				( attribute "CDS_LIB" "mstr_discrete"
					( Origin gPackager )
				)
				( attribute "CDS_LOCATION" "C3T8"
					( Origin gPackager )
				)
				( attribute "CDS_SEC" "1"
					( Origin gPackager )
				)
				( attribute "LOCATION" "C3T8"
					( Origin gFrontEnd )
				)
				( attribute "MATERIAL" "X6S"
					( Origin gFrontEnd )
				)
				( attribute "PACK_TYPE" "0805"
					( Origin gFrontEnd )
				)
				( attribute "PART_NUMBER" "C95333-007"
					( Origin gFrontEnd )
				)
				( attribute "PHYS_PAGE" "231"
					( Origin gFrontEnd )
				)
				( attribute "ROT" "0"
					( Origin gFrontEnd )
				)
				( attribute "SEC" "1"
					( Origin gFrontEnd )
				)
				( attribute "SEC_TYPE" "0805"
					( Origin gFrontEnd )
				)
				( attribute "TOLERANCE" "10%"
					( Origin gFrontEnd )
				)
				( attribute "VALUE" "10UF"
					( Origin gFrontEnd )
				)
				( attribute "VER" "1"
					( Origin gFrontEnd )
				)
				( attribute "VOLTAGE" "16V"
					( Units "uVoltage" "V" 1.000000)
					( Origin gFrontEnd )
				)
				( attribute "XY" "(-5900,4375)"
					( Origin gFrontEnd )
				)
				( attribute "CHIPS_PART_NAME" "CAP"
					( Origin gPackager )
				)
				( attribute "CDS_PART_NAME" "CAP_0805-10UF,16V,10%,X6S,C953A"
					( Origin gPackager )
				)
				( objectStatus "C3T8" )
				( pin "a"
					( attribute "PN" "1"
						( Origin gPackager )
					)
					( objectStatus "C3T8.1" )
				)
				( pin "b"
					( attribute "PN" "2"
						( Origin gPackager )
					)
					( objectStatus "C3T8.2" )
				)
			)
			( gate "@baseboard_fab2_lib.baseboard_fab2(sch_1):page231_i211"
				( attribute "CDS_LIB" "mstr_discrete"
					( Origin gPackager )
				)
				( attribute "CDS_LOCATION" "C3T14"
					( Origin gPackager )
				)
				( attribute "CDS_SEC" "1"
					( Origin gPackager )
				)
				( attribute "LOCATION" "C3T14"
					( Origin gFrontEnd )
				)
				( attribute "MATERIAL" "X6S"
					( Origin gFrontEnd )
				)
				( attribute "PACK_TYPE" "0805"
					( Origin gFrontEnd )
				)
				( attribute "PART_NUMBER" "C95333-007"
					( Origin gFrontEnd )
				)
				( attribute "PHYS_PAGE" "231"
					( Origin gFrontEnd )
				)
				( attribute "ROT" "0"
					( Origin gFrontEnd )
				)
				( attribute "SEC" "1"
					( Origin gFrontEnd )
				)
				( attribute "SEC_TYPE" "0805"
					( Origin gFrontEnd )
				)
				( attribute "TOLERANCE" "10%"
					( Origin gFrontEnd )
				)
				( attribute "VALUE" "10UF"
					( Origin gFrontEnd )
				)
				( attribute "VER" "1"
					( Origin gFrontEnd )
				)
				( attribute "VOLTAGE" "16V"
					( Units "uVoltage" "V" 1.000000)
					( Origin gFrontEnd )
				)
				( attribute "XY" "(-5500,4375)"
					( Origin gFrontEnd )
				)
				( attribute "CHIPS_PART_NAME" "CAP"
					( Origin gPackager )
				)
				( attribute "CDS_PART_NAME" "CAP_0805-10UF,16V,10%,X6S,C953A"
					( Origin gPackager )
				)
				( objectStatus "C3T14" )
				( pin "a"
					( attribute "PN" "1"
						( Origin gPackager )
					)
					( objectStatus "C3T14.1" )
				)
				( pin "b"
					( attribute "PN" "2"
						( Origin gPackager )
					)
					( objectStatus "C3T14.2" )
				)
			)
			( gate "@baseboard_fab2_lib.baseboard_fab2(sch_1):page231_i215"
				( attribute "CDS_LIB" "mstr_discrete"
					( Origin gPackager )
				)
				( attribute "CDS_LOCATION" "C3T12"
					( Origin gPackager )
				)
				( attribute "CDS_SEC" "1"
					( Origin gPackager )
				)
				( attribute "LOCATION" "C3T12"
					( Origin gFrontEnd )
				)
				( attribute "MATERIAL" "X6S"
					( Origin gFrontEnd )
				)
				( attribute "PACK_TYPE" "0805"
					( Origin gFrontEnd )
				)
				( attribute "PART_NUMBER" "C95333-007"
					( Origin gFrontEnd )
				)
				( attribute "PHYS_PAGE" "231"
					( Origin gFrontEnd )
				)
				( attribute "ROT" "0"
					( Origin gFrontEnd )
				)
				( attribute "SEC" "1"
					( Origin gFrontEnd )
				)
				( attribute "SEC_TYPE" "0805"
					( Origin gFrontEnd )
				)
				( attribute "TOLERANCE" "10%"
					( Origin gFrontEnd )
				)
				( attribute "VALUE" "10UF"
					( Origin gFrontEnd )
				)
				( attribute "VER" "1"
					( Origin gFrontEnd )
				)
				( attribute "VOLTAGE" "16V"
					( Units "uVoltage" "V" 1.000000)
					( Origin gFrontEnd )
				)
				( attribute "XY" "(-5075,4375)"
					( Origin gFrontEnd )
				)
				( attribute "CHIPS_PART_NAME" "CAP"
					( Origin gPackager )
				)
				( attribute "CDS_PART_NAME" "CAP_0805-10UF,16V,10%,X6S,C953A"
					( Origin gPackager )
				)
				( objectStatus "C3T12" )
				( pin "a"
					( attribute "PN" "1"
						( Origin gPackager )
					)
					( objectStatus "C3T12.1" )
				)
				( pin "b"
					( attribute "PN" "2"
						( Origin gPackager )
					)
					( objectStatus "C3T12.2" )
				)
			)
			( gate "@baseboard_fab2_lib.baseboard_fab2(sch_1):page231_i217"
				( attribute "CDS_LIB" "mstr_discrete"
					( Origin gPackager )
				)
				( attribute "CDS_LOCATION" "C4T3"
					( Origin gPackager )
				)
				( attribute "CDS_SEC" "1"
					( Origin gPackager )
				)
				( attribute "LOCATION" "C4T3"
					( Origin gFrontEnd )
				)
				( attribute "MATERIAL" "POSCAP"
					( Origin gFrontEnd )
				)
				( attribute "PACK_TYPE" "7343"
					( Origin gFrontEnd )
				)
				( attribute "PART_NUMBER" "724613-067"
					( Origin gFrontEnd )
				)
				( attribute "PHYS_PAGE" "231"
					( Origin gFrontEnd )
				)
				( attribute "ROT" "0"
					( Origin gFrontEnd )
				)
				( attribute "SEC" "1"
					( Origin gFrontEnd )
				)
				( attribute "SEC_TYPE" "7343"
					( Origin gFrontEnd )
				)
				( attribute "TOLERANCE" "20%"
					( Origin gFrontEnd )
				)
				( attribute "VALUE" "220UF"
					( Origin gFrontEnd )
				)
				( attribute "VER" "1"
					( Origin gFrontEnd )
				)
				( attribute "VOLTAGE" "4V"
					( Units "uVoltage" "V" 1.000000)
					( Origin gFrontEnd )
				)
				( attribute "XY" "(-1075,3875)"
					( Origin gFrontEnd )
				)
				( attribute "CHIPS_PART_NAME" "CAPP"
					( Origin gPackager )
				)
				( attribute "CDS_PART_NAME" "CAPP_7343-220UF,4V,20%,POSCAP,A"
					( Origin gPackager )
				)
				( objectStatus "C4T3" )
				( pin "a"
					( attribute "PN" "1"
						( Origin gPackager )
					)
					( objectStatus "C4T3.1" )
				)
				( pin "b"
					( attribute "PN" "2"
						( Origin gPackager )
					)
					( objectStatus "C4T3.2" )
				)
			)
			( gate "@baseboard_fab2_lib.baseboard_fab2(sch_1):page231_i218"
				( attribute "BOM_COST" "PVPP_KLM_VR"
					( Origin gFrontEnd )
				)
				( attribute "CDS_LIB" "mstr_discrete"
					( Origin gPackager )
				)
				( attribute "CDS_LOCATION" "R7F17"
					( Origin gPackager )
				)
				( attribute "CDS_SEC" "1"
					( Origin gPackager )
				)
				( attribute "LOCATION" "R7F17"
					( Origin gFrontEnd )
				)
				( attribute "MATERIAL" "CHIP"
					( Origin gFrontEnd )
				)
				( attribute "PACK_TYPE" "0402"
					( Origin gFrontEnd )
				)
				( attribute "PART_NUMBER" "G85996-004"
					( Origin gFrontEnd )
				)
				( attribute "PHYS_PAGE" "231"
					( Origin gFrontEnd )
				)
				( attribute "REUSE_ID" "9"
					( Origin gFrontEnd )
				)
				( attribute "ROOM" "PVPP_KLM_VR"
					( Origin gFrontEnd )
				)
				( attribute "ROT" "0"
					( Origin gFrontEnd )
				)
				( attribute "SEC" "1"
					( Origin gFrontEnd )
				)
				( attribute "SEC_TYPE" "0402"
					( Origin gFrontEnd )
				)
				( attribute "SPOF" "TRUE"
					( Origin gFrontEnd )
				)
				( attribute "TOLERANCE" "0.1%"
					( Origin gFrontEnd )
				)
				( attribute "VALUE" "1.0K"
					( Origin gFrontEnd )
				)
				( attribute "VER" "2"
					( Origin gFrontEnd )
				)
				( attribute "WATTAGE" "1/16W"
					( Origin gFrontEnd )
				)
				( attribute "XY" "(-675,2875)"
					( Origin gFrontEnd )
				)
				( attribute "CHIPS_PART_NAME" "RES"
					( Origin gPackager )
				)
				( attribute "CDS_PART_NAME" "RES_0402-1.0K,0.1%,1/16W,CHIP,A"
					( Origin gPackager )
				)
				( objectStatus "R7F17" )
				( pin "a"
					( attribute "PN" "1"
						( Origin gPackager )
					)
					( objectStatus "R7F17.1" )
				)
				( pin "b"
					( attribute "PN" "2"
						( Origin gPackager )
					)
					( objectStatus "R7F17.2" )
				)
			)
			( gate "@baseboard_fab2_lib.baseboard_fab2(sch_1):page231_i219"
				( attribute "BOM_COST" "PVPP_KLM_VR"
					( Origin gFrontEnd )
				)
				( attribute "CDS_LIB" "mstr_discrete"
					( Origin gPackager )
				)
				( attribute "CDS_LOCATION" "C7F13"
					( Origin gPackager )
				)
				( attribute "CDS_SEC" "1"
					( Origin gPackager )
				)
				( attribute "LOCATION" "C7F13"
					( Origin gFrontEnd )
				)
				( attribute "MATERIAL" "X7R"
					( Origin gFrontEnd )
				)
				( attribute "PACK_TYPE" "0402LF"
					( Origin gFrontEnd )
				)
				( attribute "PART_NUMBER" "A36096-075"
					( Origin gFrontEnd )
				)
				( attribute "PHYS_PAGE" "231"
					( Origin gFrontEnd )
				)
				( attribute "REUSE_ID" "26"
					( Origin gFrontEnd )
				)
				( attribute "ROOM" "PVPP_KLM_VR"
					( Origin gFrontEnd )
				)
				( attribute "ROT" "0"
					( Origin gFrontEnd )
				)
				( attribute "SEC" "1"
					( Origin gFrontEnd )
				)
				( attribute "SEC_TYPE" "0402LF"
					( Origin gFrontEnd )
				)
				( attribute "SPOF" "TRUE"
					( Origin gFrontEnd )
				)
				( attribute "TOLERANCE" "10%"
					( Origin gFrontEnd )
				)
				( attribute "VALUE" "2200PF"
					( Origin gFrontEnd )
				)
				( attribute "VER" "1"
					( Origin gFrontEnd )
				)
				( attribute "VOLTAGE" "50V"
					( Units "uVoltage" "V" 1.000000)
					( Origin gFrontEnd )
				)
				( attribute "XY" "(-675,2325)"
					( Origin gFrontEnd )
				)
				( attribute "CHIPS_PART_NAME" "CAP"
					( Origin gPackager )
				)
				( attribute "CDS_PART_NAME" "CAP_0402LF-2200PF,50V,10%,X7R,A"
					( Origin gPackager )
				)
				( objectStatus "C7F13" )
				( pin "a"
					( attribute "PN" "1"
						( Origin gPackager )
					)
					( objectStatus "C7F13.1" )
				)
				( pin "b"
					( attribute "PN" "2"
						( Origin gPackager )
					)
					( objectStatus "C7F13.2" )
				)
			)
			( gate "@baseboard_fab2_lib.baseboard_fab2(sch_1):page231_i220"
				( attribute "CDS_LIB" "mstr_discrete"
					( Origin gPackager )
				)
				( attribute "CDS_LOCATION" "R7F9"
					( Origin gPackager )
				)
				( attribute "CDS_SEC" "1"
					( Origin gPackager )
				)
				( attribute "LOCATION" "R7F9"
					( Origin gFrontEnd )
				)
				( attribute "MATERIAL" "CHIP"
					( Origin gFrontEnd )
				)
				( attribute "PACK_TYPE" "0402"
					( Origin gFrontEnd )
				)
				( attribute "PART_NUMBER" "G21497-005"
					( Origin gFrontEnd )
				)
				( attribute "PHYS_PAGE" "231"
					( Origin gFrontEnd )
				)
				( attribute "ROOM" "PVCCIN_CPU0_VR"
					( Origin gFrontEnd )
				)
				( attribute "ROT" "0"
					( Origin gFrontEnd )
				)
				( attribute "SEC" "1"
					( Origin gFrontEnd )
				)
				( attribute "SEC_TYPE" "0402"
					( Origin gFrontEnd )
				)
				( attribute "TOLERANCE" "5%"
					( Origin gFrontEnd )
				)
				( attribute "VALUE" "0.0"
					( Origin gFrontEnd )
				)
				( attribute "VER" "1"
					( Origin gFrontEnd )
				)
				( attribute "WATTAGE" "1/16W"
					( Origin gFrontEnd )
				)
				( attribute "XY" "(-5775,3075)"
					( Origin gFrontEnd )
				)
				( attribute "CHIPS_PART_NAME" "RES"
					( Origin gPackager )
				)
				( attribute "CDS_PART_NAME" "RES_0402-0.0,5%,1/16W,CHIP,G21A"
					( Origin gPackager )
				)
				( objectStatus "R7F9" )
				( pin "a"
					( attribute "PN" "1"
						( Origin gPackager )
					)
					( objectStatus "R7F9.1" )
				)
				( pin "b"
					( attribute "PN" "2"
						( Origin gPackager )
					)
					( objectStatus "R7F9.2" )
				)
			)
			( gate "@baseboard_fab2_lib.baseboard_fab2(sch_1):page232_i102"
				( attribute "BOM_COST" "MEM_VRD_PVPP_AB"
					( Origin gFrontEnd )
				)
				( attribute "CDS_LIB" "mstr_discrete"
					( Origin gPackager )
				)
				( attribute "CDS_LOCATION" "C4L2"
					( Origin gPackager )
				)
				( attribute "CDS_SEC" "1"
					( Origin gPackager )
				)
				( attribute "LOCATION" "C4L2"
					( Origin gFrontEnd )
				)
				( attribute "MATERIAL" "X6S"
					( Origin gFrontEnd )
				)
				( attribute "PACK_TYPE" "0603LF"
					( Origin gFrontEnd )
				)
				( attribute "PART_NUMBER" "E15431-001"
					( Origin gFrontEnd )
				)
				( attribute "PHYS_PAGE" "232"
					( Origin gFrontEnd )
				)
				( attribute "ROOM" "PVPP_KLM_VR"
					( Origin gFrontEnd )
				)
				( attribute "ROT" "0"
					( Origin gFrontEnd )
				)
				( attribute "SEC" "1"
					( Origin gPackager )
				)
				( attribute "TOLERANCE" "20%"
					( Origin gFrontEnd )
				)
				( attribute "VALUE" "10UF"
					( Origin gFrontEnd )
				)
				( attribute "VER" "1"
					( Origin gFrontEnd )
				)
				( attribute "VOLTAGE" "4V"
					( Units "uVoltage" "V" 1.000000)
					( Origin gFrontEnd )
				)
				( attribute "XY" "(-8550,875)"
					( Origin gFrontEnd )
				)
				( attribute "CHIPS_PART_NAME" "CAP"
					( Origin gPackager )
				)
				( attribute "CDS_PART_NAME" "CAP_0603LF-10UF,4V,20%,X6S,E15A"
					( Origin gPackager )
				)
				( objectStatus "C4L2" )
				( pin "a"
					( attribute "PN" "1"
						( Origin gPackager )
					)
					( objectStatus "C4L2.1" )
				)
				( pin "b"
					( attribute "PN" "2"
						( Origin gPackager )
					)
					( objectStatus "C4L2.2" )
				)
			)
			( gate "@baseboard_fab2_lib.baseboard_fab2(sch_1):page232_i104"
				( attribute "BOM_COST" "MEM_VRD_PVPP_AB"
					( Origin gFrontEnd )
				)
				( attribute "CDS_LIB" "mstr_discrete"
					( Origin gPackager )
				)
				( attribute "CDS_LOCATION" "C6A3"
					( Origin gPackager )
				)
				( attribute "CDS_SEC" "1"
					( Origin gPackager )
				)
				( attribute "LOCATION" "C6A3"
					( Origin gFrontEnd )
				)
				( attribute "MATERIAL" "X6S"
					( Origin gFrontEnd )
				)
				( attribute "PACK_TYPE" "0603LF"
					( Origin gFrontEnd )
				)
				( attribute "PART_NUMBER" "E15431-001"
					( Origin gFrontEnd )
				)
				( attribute "PHYS_PAGE" "232"
					( Origin gFrontEnd )
				)
				( attribute "ROOM" "PVPP_KLM_VR"
					( Origin gFrontEnd )
				)
				( attribute "ROT" "0"
					( Origin gFrontEnd )
				)
				( attribute "SEC" "1"
					( Origin gPackager )
				)
				( attribute "TOLERANCE" "20%"
					( Origin gFrontEnd )
				)
				( attribute "VALUE" "10UF"
					( Origin gFrontEnd )
				)
				( attribute "VER" "1"
					( Origin gFrontEnd )
				)
				( attribute "VOLTAGE" "4V"
					( Units "uVoltage" "V" 1.000000)
					( Origin gFrontEnd )
				)
				( attribute "XY" "(-8300,875)"
					( Origin gFrontEnd )
				)
				( attribute "CHIPS_PART_NAME" "CAP"
					( Origin gPackager )
				)
				( attribute "CDS_PART_NAME" "CAP_0603LF-10UF,4V,20%,X6S,E15A"
					( Origin gPackager )
				)
				( objectStatus "C6A3" )
				( pin "a"
					( attribute "PN" "1"
						( Origin gPackager )
					)
					( objectStatus "C6A3.1" )
				)
				( pin "b"
					( attribute "PN" "2"
						( Origin gPackager )
					)
					( objectStatus "C6A3.2" )
				)
			)
			( gate "@baseboard_fab2_lib.baseboard_fab2(sch_1):page232_i105"
				( attribute "BOM_COST" "MEM_VRD_PVPP_AB"
					( Origin gFrontEnd )
				)
				( attribute "CDS_LIB" "mstr_discrete"
					( Origin gPackager )
				)
				( attribute "CDS_LOCATION" "C6A2"
					( Origin gPackager )
				)
				( attribute "CDS_SEC" "1"
					( Origin gPackager )
				)
				( attribute "LOCATION" "C6A2"
					( Origin gFrontEnd )
				)
				( attribute "MATERIAL" "X6S"
					( Origin gFrontEnd )
				)
				( attribute "PACK_TYPE" "0603LF"
					( Origin gFrontEnd )
				)
				( attribute "PART_NUMBER" "E15431-001"
					( Origin gFrontEnd )
				)
				( attribute "PHYS_PAGE" "232"
					( Origin gFrontEnd )
				)
				( attribute "ROOM" "PVPP_KLM_VR"
					( Origin gFrontEnd )
				)
				( attribute "ROT" "0"
					( Origin gFrontEnd )
				)
				( attribute "SEC" "1"
					( Origin gPackager )
				)
				( attribute "TOLERANCE" "20%"
					( Origin gFrontEnd )
				)
				( attribute "VALUE" "10UF"
					( Origin gFrontEnd )
				)
				( attribute "VER" "1"
					( Origin gFrontEnd )
				)
				( attribute "VOLTAGE" "4V"
					( Units "uVoltage" "V" 1.000000)
					( Origin gFrontEnd )
				)
				( attribute "XY" "(-8025,875)"
					( Origin gFrontEnd )
				)
				( attribute "CHIPS_PART_NAME" "CAP"
					( Origin gPackager )
				)
				( attribute "CDS_PART_NAME" "CAP_0603LF-10UF,4V,20%,X6S,E15A"
					( Origin gPackager )
				)
				( objectStatus "C6A2" )
				( pin "a"
					( attribute "PN" "1"
						( Origin gPackager )
					)
					( objectStatus "C6A2.1" )
				)
				( pin "b"
					( attribute "PN" "2"
						( Origin gPackager )
					)
					( objectStatus "C6A2.2" )
				)
			)
			( gate "@baseboard_fab2_lib.baseboard_fab2(sch_1):page232_i106"
				( attribute "BOM_COST" "MEM_VRD_PVPP_AB"
					( Origin gFrontEnd )
				)
				( attribute "CDS_LIB" "mstr_discrete"
					( Origin gPackager )
				)
				( attribute "CDS_LOCATION" "C4L3"
					( Origin gPackager )
				)
				( attribute "CDS_SEC" "1"
					( Origin gPackager )
				)
				( attribute "LOCATION" "C4L3"
					( Origin gFrontEnd )
				)
				( attribute "MATERIAL" "X6S"
					( Origin gFrontEnd )
				)
				( attribute "PACK_TYPE" "0603LF"
					( Origin gFrontEnd )
				)
				( attribute "PART_NUMBER" "E15431-001"
					( Origin gFrontEnd )
				)
				( attribute "PHYS_PAGE" "232"
					( Origin gFrontEnd )
				)
				( attribute "ROOM" "PVPP_KLM_VR"
					( Origin gFrontEnd )
				)
				( attribute "ROT" "0"
					( Origin gFrontEnd )
				)
				( attribute "SEC" "1"
					( Origin gPackager )
				)
				( attribute "TOLERANCE" "20%"
					( Origin gFrontEnd )
				)
				( attribute "VALUE" "10UF"
					( Origin gFrontEnd )
				)
				( attribute "VER" "1"
					( Origin gFrontEnd )
				)
				( attribute "VOLTAGE" "4V"
					( Units "uVoltage" "V" 1.000000)
					( Origin gFrontEnd )
				)
				( attribute "XY" "(-7775,850)"
					( Origin gFrontEnd )
				)
				( attribute "CHIPS_PART_NAME" "CAP"
					( Origin gPackager )
				)
				( attribute "CDS_PART_NAME" "CAP_0603LF-10UF,4V,20%,X6S,E15A"
					( Origin gPackager )
				)
				( objectStatus "C4L3" )
				( pin "a"
					( attribute "PN" "1"
						( Origin gPackager )
					)
					( objectStatus "C4L3.1" )
				)
				( pin "b"
					( attribute "PN" "2"
						( Origin gPackager )
					)
					( objectStatus "C4L3.2" )
				)
			)
			( gate "@baseboard_fab2_lib.baseboard_fab2(sch_1):page232_i108"
				( attribute "BOM_COST" "MEM_VRD_PVPP_AB"
					( Origin gFrontEnd )
				)
				( attribute "CDS_LIB" "mstr_discrete"
					( Origin gPackager )
				)
				( attribute "CDS_LOCATION" "C4L4"
					( Origin gPackager )
				)
				( attribute "CDS_SEC" "1"
					( Origin gPackager )
				)
				( attribute "LOCATION" "C4L4"
					( Origin gFrontEnd )
				)
				( attribute "MATERIAL" "X6S"
					( Origin gFrontEnd )
				)
				( attribute "PACK_TYPE" "0603LF"
					( Origin gFrontEnd )
				)
				( attribute "PART_NUMBER" "E15431-001"
					( Origin gFrontEnd )
				)
				( attribute "PHYS_PAGE" "232"
					( Origin gFrontEnd )
				)
				( attribute "ROOM" "PVPP_KLM_VR"
					( Origin gFrontEnd )
				)
				( attribute "ROT" "0"
					( Origin gFrontEnd )
				)
				( attribute "SEC" "1"
					( Origin gPackager )
				)
				( attribute "TOLERANCE" "20%"
					( Origin gFrontEnd )
				)
				( attribute "VALUE" "10UF"
					( Origin gFrontEnd )
				)
				( attribute "VER" "1"
					( Origin gFrontEnd )
				)
				( attribute "VOLTAGE" "4V"
					( Units "uVoltage" "V" 1.000000)
					( Origin gFrontEnd )
				)
				( attribute "XY" "(-7500,875)"
					( Origin gFrontEnd )
				)
				( attribute "CHIPS_PART_NAME" "CAP"
					( Origin gPackager )
				)
				( attribute "CDS_PART_NAME" "CAP_0603LF-10UF,4V,20%,X6S,E15A"
					( Origin gPackager )
				)
				( objectStatus "C4L4" )
				( pin "a"
					( attribute "PN" "1"
						( Origin gPackager )
					)
					( objectStatus "C4L4.1" )
				)
				( pin "b"
					( attribute "PN" "2"
						( Origin gPackager )
					)
					( objectStatus "C4L4.2" )
				)
			)
			( gate "@baseboard_fab2_lib.baseboard_fab2(sch_1):page232_i109"
				( attribute "BOM_COST" "MEM_VRD_PVPP_AB"
					( Origin gFrontEnd )
				)
				( attribute "CDS_LIB" "mstr_discrete"
					( Origin gPackager )
				)
				( attribute "CDS_LOCATION" "C6A7"
					( Origin gPackager )
				)
				( attribute "CDS_SEC" "1"
					( Origin gPackager )
				)
				( attribute "LOCATION" "C6A7"
					( Origin gFrontEnd )
				)
				( attribute "MATERIAL" "X6S"
					( Origin gFrontEnd )
				)
				( attribute "PACK_TYPE" "0603LF"
					( Origin gFrontEnd )
				)
				( attribute "PART_NUMBER" "E15431-001"
					( Origin gFrontEnd )
				)
				( attribute "PHYS_PAGE" "232"
					( Origin gFrontEnd )
				)
				( attribute "ROOM" "PVPP_KLM_VR"
					( Origin gFrontEnd )
				)
				( attribute "ROT" "0"
					( Origin gFrontEnd )
				)
				( attribute "SEC" "1"
					( Origin gPackager )
				)
				( attribute "TOLERANCE" "20%"
					( Origin gFrontEnd )
				)
				( attribute "VALUE" "10UF"
					( Origin gFrontEnd )
				)
				( attribute "VER" "1"
					( Origin gFrontEnd )
				)
				( attribute "VOLTAGE" "4V"
					( Units "uVoltage" "V" 1.000000)
					( Origin gFrontEnd )
				)
				( attribute "XY" "(-7200,875)"
					( Origin gFrontEnd )
				)
				( attribute "CHIPS_PART_NAME" "CAP"
					( Origin gPackager )
				)
				( attribute "CDS_PART_NAME" "CAP_0603LF-10UF,4V,20%,X6S,E15A"
					( Origin gPackager )
				)
				( objectStatus "C6A7" )
				( pin "a"
					( attribute "PN" "1"
						( Origin gPackager )
					)
					( objectStatus "C6A7.1" )
				)
				( pin "b"
					( attribute "PN" "2"
						( Origin gPackager )
					)
					( objectStatus "C6A7.2" )
				)
			)
			( gate "@baseboard_fab2_lib.baseboard_fab2(sch_1):page232_i110"
				( attribute "BOM_COST" "MEM_VRD_PVPP_AB"
					( Origin gFrontEnd )
				)
				( attribute "CDS_LIB" "mstr_discrete"
					( Origin gPackager )
				)
				( attribute "CDS_LOCATION" "C6A6"
					( Origin gPackager )
				)
				( attribute "CDS_SEC" "1"
					( Origin gPackager )
				)
				( attribute "LOCATION" "C6A6"
					( Origin gFrontEnd )
				)
				( attribute "MATERIAL" "X6S"
					( Origin gFrontEnd )
				)
				( attribute "PACK_TYPE" "0603LF"
					( Origin gFrontEnd )
				)
				( attribute "PART_NUMBER" "E15431-001"
					( Origin gFrontEnd )
				)
				( attribute "PHYS_PAGE" "232"
					( Origin gFrontEnd )
				)
				( attribute "ROOM" "PVPP_KLM_VR"
					( Origin gFrontEnd )
				)
				( attribute "ROT" "0"
					( Origin gFrontEnd )
				)
				( attribute "SEC" "1"
					( Origin gPackager )
				)
				( attribute "TOLERANCE" "20%"
					( Origin gFrontEnd )
				)
				( attribute "VALUE" "10UF"
					( Origin gFrontEnd )
				)
				( attribute "VER" "1"
					( Origin gFrontEnd )
				)
				( attribute "VOLTAGE" "4V"
					( Units "uVoltage" "V" 1.000000)
					( Origin gFrontEnd )
				)
				( attribute "XY" "(-6925,875)"
					( Origin gFrontEnd )
				)
				( attribute "CHIPS_PART_NAME" "CAP"
					( Origin gPackager )
				)
				( attribute "CDS_PART_NAME" "CAP_0603LF-10UF,4V,20%,X6S,E15A"
					( Origin gPackager )
				)
				( objectStatus "C6A6" )
				( pin "a"
					( attribute "PN" "1"
						( Origin gPackager )
					)
					( objectStatus "C6A6.1" )
				)
				( pin "b"
					( attribute "PN" "2"
						( Origin gPackager )
					)
					( objectStatus "C6A6.2" )
				)
			)
			( gate "@baseboard_fab2_lib.baseboard_fab2(sch_1):page232_i111"
				( attribute "BOM_COST" "MEM_VRD_PVPP_AB"
					( Origin gFrontEnd )
				)
				( attribute "CDS_LIB" "mstr_discrete"
					( Origin gPackager )
				)
				( attribute "CDS_LOCATION" "C4M3"
					( Origin gPackager )
				)
				( attribute "CDS_SEC" "1"
					( Origin gPackager )
				)
				( attribute "LOCATION" "C4M3"
					( Origin gFrontEnd )
				)
				( attribute "MATERIAL" "X6S"
					( Origin gFrontEnd )
				)
				( attribute "PACK_TYPE" "0603LF"
					( Origin gFrontEnd )
				)
				( attribute "PART_NUMBER" "E15431-001"
					( Origin gFrontEnd )
				)
				( attribute "PHYS_PAGE" "232"
					( Origin gFrontEnd )
				)
				( attribute "ROOM" "PVPP_KLM_VR"
					( Origin gFrontEnd )
				)
				( attribute "ROT" "0"
					( Origin gFrontEnd )
				)
				( attribute "SEC" "1"
					( Origin gPackager )
				)
				( attribute "TOLERANCE" "20%"
					( Origin gFrontEnd )
				)
				( attribute "VALUE" "10UF"
					( Origin gFrontEnd )
				)
				( attribute "VER" "1"
					( Origin gFrontEnd )
				)
				( attribute "VOLTAGE" "4V"
					( Units "uVoltage" "V" 1.000000)
					( Origin gFrontEnd )
				)
				( attribute "XY" "(-6625,875)"
					( Origin gFrontEnd )
				)
				( attribute "CHIPS_PART_NAME" "CAP"
					( Origin gPackager )
				)
				( attribute "CDS_PART_NAME" "CAP_0603LF-10UF,4V,20%,X6S,E15A"
					( Origin gPackager )
				)
				( objectStatus "C4M3" )
				( pin "a"
					( attribute "PN" "1"
						( Origin gPackager )
					)
					( objectStatus "C4M3.1" )
				)
				( pin "b"
					( attribute "PN" "2"
						( Origin gPackager )
					)
					( objectStatus "C4M3.2" )
				)
			)
			( gate "@baseboard_fab2_lib.baseboard_fab2(sch_1):page232_i125"
				( attribute "BOM_COST" "MEM_VRD_PVPP_AB"
					( Origin gFrontEnd )
				)
				( attribute "CDS_LIB" "mstr_discrete"
					( Origin gPackager )
				)
				( attribute "CDS_LOCATION" "C4M4"
					( Origin gPackager )
				)
				( attribute "CDS_SEC" "1"
					( Origin gPackager )
				)
				( attribute "LOCATION" "C4M4"
					( Origin gFrontEnd )
				)
				( attribute "MATERIAL" "X6S"
					( Origin gFrontEnd )
				)
				( attribute "PACK_TYPE" "0603LF"
					( Origin gFrontEnd )
				)
				( attribute "PART_NUMBER" "E15431-001"
					( Origin gFrontEnd )
				)
				( attribute "PHYS_PAGE" "232"
					( Origin gFrontEnd )
				)
				( attribute "ROOM" "PVPP_KLM_VR"
					( Origin gFrontEnd )
				)
				( attribute "ROT" "0"
					( Origin gFrontEnd )
				)
				( attribute "SEC" "1"
					( Origin gPackager )
				)
				( attribute "TOLERANCE" "20%"
					( Origin gFrontEnd )
				)
				( attribute "VALUE" "10UF"
					( Origin gFrontEnd )
				)
				( attribute "VER" "1"
					( Origin gFrontEnd )
				)
				( attribute "VOLTAGE" "4V"
					( Units "uVoltage" "V" 1.000000)
					( Origin gFrontEnd )
				)
				( attribute "XY" "(-6325,875)"
					( Origin gFrontEnd )
				)
				( attribute "CHIPS_PART_NAME" "CAP"
					( Origin gPackager )
				)
				( attribute "CDS_PART_NAME" "CAP_0603LF-10UF,4V,20%,X6S,E15A"
					( Origin gPackager )
				)
				( objectStatus "C4M4" )
				( pin "a"
					( attribute "PN" "1"
						( Origin gPackager )
					)
					( objectStatus "C4M4.1" )
				)
				( pin "b"
					( attribute "PN" "2"
						( Origin gPackager )
					)
					( objectStatus "C4M4.2" )
				)
			)
			( gate "@baseboard_fab2_lib.baseboard_fab2(sch_1):page232_i126"
				( attribute "BOM_COST" "MEM_VRD_PVPP_AB"
					( Origin gFrontEnd )
				)
				( attribute "CDS_LIB" "mstr_discrete"
					( Origin gPackager )
				)
				( attribute "CDS_LOCATION" "C6B2"
					( Origin gPackager )
				)
				( attribute "CDS_SEC" "1"
					( Origin gPackager )
				)
				( attribute "LOCATION" "C6B2"
					( Origin gFrontEnd )
				)
				( attribute "MATERIAL" "X6S"
					( Origin gFrontEnd )
				)
				( attribute "PACK_TYPE" "0603LF"
					( Origin gFrontEnd )
				)
				( attribute "PART_NUMBER" "E15431-001"
					( Origin gFrontEnd )
				)
				( attribute "PHYS_PAGE" "232"
					( Origin gFrontEnd )
				)
				( attribute "ROOM" "PVPP_KLM_VR"
					( Origin gFrontEnd )
				)
				( attribute "ROT" "0"
					( Origin gFrontEnd )
				)
				( attribute "SEC" "1"
					( Origin gPackager )
				)
				( attribute "TOLERANCE" "20%"
					( Origin gFrontEnd )
				)
				( attribute "VALUE" "10UF"
					( Origin gFrontEnd )
				)
				( attribute "VER" "1"
					( Origin gFrontEnd )
				)
				( attribute "VOLTAGE" "4V"
					( Units "uVoltage" "V" 1.000000)
					( Origin gFrontEnd )
				)
				( attribute "XY" "(-6050,850)"
					( Origin gFrontEnd )
				)
				( attribute "CHIPS_PART_NAME" "CAP"
					( Origin gPackager )
				)
				( attribute "CDS_PART_NAME" "CAP_0603LF-10UF,4V,20%,X6S,E15A"
					( Origin gPackager )
				)
				( objectStatus "C6B2" )
				( pin "a"
					( attribute "PN" "1"
						( Origin gPackager )
					)
					( objectStatus "C6B2.1" )
				)
				( pin "b"
					( attribute "PN" "2"
						( Origin gPackager )
					)
					( objectStatus "C6B2.2" )
				)
			)
			( gate "@baseboard_fab2_lib.baseboard_fab2(sch_1):page232_i128"
				( attribute "BOM_COST" "MEM_VRD_PVPP_AB"
					( Origin gFrontEnd )
				)
				( attribute "CDS_LIB" "mstr_discrete"
					( Origin gPackager )
				)
				( attribute "CDS_LOCATION" "C6B1"
					( Origin gPackager )
				)
				( attribute "CDS_SEC" "1"
					( Origin gPackager )
				)
				( attribute "LOCATION" "C6B1"
					( Origin gFrontEnd )
				)
				( attribute "MATERIAL" "X6S"
					( Origin gFrontEnd )
				)
				( attribute "PACK_TYPE" "0603LF"
					( Origin gFrontEnd )
				)
				( attribute "PART_NUMBER" "E15431-001"
					( Origin gFrontEnd )
				)
				( attribute "PHYS_PAGE" "232"
					( Origin gFrontEnd )
				)
				( attribute "ROOM" "PVPP_KLM_VR"
					( Origin gFrontEnd )
				)
				( attribute "ROT" "0"
					( Origin gFrontEnd )
				)
				( attribute "SEC" "1"
					( Origin gPackager )
				)
				( attribute "TOLERANCE" "20%"
					( Origin gFrontEnd )
				)
				( attribute "VALUE" "10UF"
					( Origin gFrontEnd )
				)
				( attribute "VER" "1"
					( Origin gFrontEnd )
				)
				( attribute "VOLTAGE" "4V"
					( Units "uVoltage" "V" 1.000000)
					( Origin gFrontEnd )
				)
				( attribute "XY" "(-5775,850)"
					( Origin gFrontEnd )
				)
				( attribute "CHIPS_PART_NAME" "CAP"
					( Origin gPackager )
				)
				( attribute "CDS_PART_NAME" "CAP_0603LF-10UF,4V,20%,X6S,E15A"
					( Origin gPackager )
				)
				( objectStatus "C6B1" )
				( pin "a"
					( attribute "PN" "1"
						( Origin gPackager )
					)
					( objectStatus "C6B1.1" )
				)
				( pin "b"
					( attribute "PN" "2"
						( Origin gPackager )
					)
					( objectStatus "C6B1.2" )
				)
			)
			( gate "@baseboard_fab2_lib.baseboard_fab2(sch_1):page232_i129"
				( attribute "BOM_COST" "MEM_VRD_PVPP_AB"
					( Origin gFrontEnd )
				)
				( attribute "CDS_LIB" "mstr_discrete"
					( Origin gPackager )
				)
				( attribute "CDS_LOCATION" "C4L1"
					( Origin gPackager )
				)
				( attribute "CDS_SEC" "1"
					( Origin gPackager )
				)
				( attribute "LOCATION" "C4L1"
					( Origin gFrontEnd )
				)
				( attribute "MATERIAL" "X6S"
					( Origin gFrontEnd )
				)
				( attribute "PACK_TYPE" "0603LF"
					( Origin gFrontEnd )
				)
				( attribute "PART_NUMBER" "E15431-001"
					( Origin gFrontEnd )
				)
				( attribute "PHYS_PAGE" "232"
					( Origin gFrontEnd )
				)
				( attribute "ROOM" "PVPP_KLM_VR"
					( Origin gFrontEnd )
				)
				( attribute "ROT" "0"
					( Origin gFrontEnd )
				)
				( attribute "SEC" "1"
					( Origin gFrontEnd )
				)
				( attribute "SEC_TYPE" "0603LF"
					( Origin gFrontEnd )
				)
				( attribute "TOLERANCE" "20%"
					( Origin gFrontEnd )
				)
				( attribute "VALUE" "10UF"
					( Origin gFrontEnd )
				)
				( attribute "VER" "1"
					( Origin gFrontEnd )
				)
				( attribute "VOLTAGE" "4V"
					( Units "uVoltage" "V" 1.000000)
					( Origin gFrontEnd )
				)
				( attribute "XY" "(-5525,875)"
					( Origin gFrontEnd )
				)
				( attribute "CHIPS_PART_NAME" "CAP"
					( Origin gPackager )
				)
				( attribute "CDS_PART_NAME" "CAP_0603LF-10UF,4V,20%,X6S,E15A"
					( Origin gPackager )
				)
				( objectStatus "C4L1" )
				( pin "a"
					( attribute "PN" "1"
						( Origin gPackager )
					)
					( objectStatus "C4L1.1" )
				)
				( pin "b"
					( attribute "PN" "2"
						( Origin gPackager )
					)
					( objectStatus "C4L1.2" )
				)
			)
			( gate "@baseboard_fab2_lib.baseboard_fab2(sch_1):page232_i150"
				( attribute "CDS_LIB" "mstr_discrete"
					( Origin gPackager )
				)
				( attribute "CDS_LOCATION" "R7B20"
					( Origin gPackager )
				)
				( attribute "CDS_SEC" "1"
					( Origin gPackager )
				)
				( attribute "LOCATION" "R7B20"
					( Origin gFrontEnd )
				)
				( attribute "MATERIAL" "CHIP"
					( Origin gFrontEnd )
				)
				( attribute "PACK_TYPE" "0402"
					( Origin gFrontEnd )
				)
				( attribute "PART_NUMBER" "G21497-005"
					( Origin gFrontEnd )
				)
				( attribute "PHYS_PAGE" "232"
					( Origin gFrontEnd )
				)
				( attribute "ROOM" "PVPP_KLM_VR"
					( Origin gFrontEnd )
				)
				( attribute "ROT" "0"
					( Origin gFrontEnd )
				)
				( attribute "SEC" "1"
					( Origin gPackager )
				)
				( attribute "TOLERANCE" "5%"
					( Origin gFrontEnd )
				)
				( attribute "VALUE" "0.0"
					( Origin gFrontEnd )
				)
				( attribute "VER" "1"
					( Origin gFrontEnd )
				)
				( attribute "WATTAGE" "1/16W"
					( Origin gFrontEnd )
				)
				( attribute "XY" "(-1575,775)"
					( Origin gFrontEnd )
				)
				( attribute "CHIPS_PART_NAME" "RES"
					( Origin gPackager )
				)
				( attribute "CDS_PART_NAME" "RES_0402-0.0,5%,1/16W,CHIP,G21A"
					( Origin gPackager )
				)
				( objectStatus "R7B20" )
				( pin "a"
					( attribute "PN" "1"
						( Origin gPackager )
					)
					( objectStatus "R7B20.1" )
				)
				( pin "b"
					( attribute "PN" "2"
						( Origin gPackager )
					)
					( objectStatus "R7B20.2" )
				)
			)
			( gate "@baseboard_fab2_lib.baseboard_fab2(sch_1):page232_i185"
				( attribute "BOM_COST" "PVPP_KLM_VR"
					( Origin gFrontEnd )
				)
				( attribute "CDS_LIB" "mstr_discrete"
					( Origin gPackager )
				)
				( attribute "CDS_LOCATION" "C7B9"
					( Origin gPackager )
				)
				( attribute "CDS_SEC" "1"
					( Origin gPackager )
				)
				( attribute "FIN" "VR_1P2"
					( Origin gFrontEnd )
				)
				( attribute "LOCATION" "C7B9"
					( Origin gFrontEnd )
				)
				( attribute "MATERIAL" "EMPTY"
					( Origin gFrontEnd )
				)
				( attribute "PACK_TYPE" "0402LF"
					( Origin gFrontEnd )
				)
				( attribute "PART_NUMBER" "A36096-046"
					( Origin gFrontEnd )
				)
				( attribute "PHYS_PAGE" "232"
					( Origin gFrontEnd )
				)
				( attribute "REUSE_ID" "1"
					( Origin gFrontEnd )
				)
				( attribute "ROOM" "PVPP_KLM_VR"
					( Origin gFrontEnd )
				)
				( attribute "ROT" "2"
					( Origin gFrontEnd )
				)
				( attribute "SEC" "1"
					( Origin gPackager )
				)
				( attribute "TOLERANCE" "10%"
					( Origin gFrontEnd )
				)
				( attribute "VALUE" "1000PF"
					( Origin gFrontEnd )
				)
				( attribute "VER" "1"
					( Origin gFrontEnd )
				)
				( attribute "VOLTAGE" "50V"
					( Units "uVoltage" "V" 1.000000)
					( Origin gFrontEnd )
				)
				( attribute "XY" "(-6825,2500)"
					( Origin gFrontEnd )
				)
				( attribute "CHIPS_PART_NAME" "CAP"
					( Origin gPackager )
				)
				( attribute "CDS_PART_NAME" "CAP_0402LF-1000PF,50V,10%,EMPTA"
					( Origin gPackager )
				)
				( objectStatus "C7B9" )
				( pin "a"
					( attribute "PN" "1"
						( Origin gPackager )
					)
					( objectStatus "C7B9.1" )
				)
				( pin "b"
					( attribute "PN" "2"
						( Origin gPackager )
					)
					( objectStatus "C7B9.2" )
				)
			)
			( gate "@baseboard_fab2_lib.baseboard_fab2(sch_1):page232_i193"
				( attribute "BOM_COST" "PVPP_KLM_VR"
					( Origin gFrontEnd )
				)
				( attribute "CDS_LIB" "mstr_discrete"
					( Origin gPackager )
				)
				( attribute "CDS_LOCATION" "R7B14"
					( Origin gPackager )
				)
				( attribute "CDS_SEC" "1"
					( Origin gPackager )
				)
				( attribute "LOCATION" "R7B14"
					( Origin gFrontEnd )
				)
				( attribute "MATERIAL" "CHIP"
					( Origin gFrontEnd )
				)
				( attribute "PACK_TYPE" "0402"
					( Origin gFrontEnd )
				)
				( attribute "PART_NUMBER" "G21796-242"
					( Origin gFrontEnd )
				)
				( attribute "PHYS_PAGE" "232"
					( Origin gFrontEnd )
				)
				( attribute "ROOM" "PVPP_KLM_VR"
					( Origin gFrontEnd )
				)
				( attribute "ROT" "2"
					( Origin gFrontEnd )
				)
				( attribute "SEC" "1"
					( Origin gPackager )
				)
				( attribute "TOLERANCE" "1.0%"
					( Origin gFrontEnd )
				)
				( attribute "VALUE" "7.87K"
					( Origin gFrontEnd )
				)
				( attribute "VER" "2"
					( Origin gFrontEnd )
				)
				( attribute "WATTAGE" "1/16W"
					( Origin gFrontEnd )
				)
				( attribute "XY" "(-5100,1650)"
					( Origin gFrontEnd )
				)
				( attribute "CHIPS_PART_NAME" "RES"
					( Origin gPackager )
				)
				( attribute "CDS_PART_NAME" "RES_0402-7.87K,1.0%,1/16W,CHIPA"
					( Origin gPackager )
				)
				( objectStatus "R7B14" )
				( pin "a"
					( attribute "PN" "1"
						( Origin gPackager )
					)
					( objectStatus "R7B14.1" )
				)
				( pin "b"
					( attribute "PN" "2"
						( Origin gPackager )
					)
					( objectStatus "R7B14.2" )
				)
			)
			( gate "@baseboard_fab2_lib.baseboard_fab2(sch_1):page232_i197"
				( attribute "BOM_COST" "PVPP_KLM_VR"
					( Origin gFrontEnd )
				)
				( attribute "CDS_LIB" "mstr_discrete"
					( Origin gPackager )
				)
				( attribute "CDS_LOCATION" "C7B11"
					( Origin gPackager )
				)
				( attribute "CDS_SEC" "1"
					( Origin gPackager )
				)
				( attribute "LOCATION" "C7B11"
					( Origin gFrontEnd )
				)
				( attribute "MATERIAL" "X7R"
					( Origin gFrontEnd )
				)
				( attribute "PACK_TYPE" "0402"
					( Origin gFrontEnd )
				)
				( attribute "PART_NUMBER" "A36096-129"
					( Origin gFrontEnd )
				)
				( attribute "PHYS_PAGE" "232"
					( Origin gFrontEnd )
				)
				( attribute "REUSE_ID" "26"
					( Origin gFrontEnd )
				)
				( attribute "ROOM" "PVPP_KLM_VR"
					( Origin gFrontEnd )
				)
				( attribute "ROT" "0"
					( Origin gFrontEnd )
				)
				( attribute "SEC" "1"
					( Origin gFrontEnd )
				)
				( attribute "SEC_TYPE" "0402"
					( Origin gFrontEnd )
				)
				( attribute "TOLERANCE" "10%"
					( Origin gFrontEnd )
				)
				( attribute "VALUE" "0.027UF"
					( Origin gFrontEnd )
				)
				( attribute "VER" "1"
					( Origin gFrontEnd )
				)
				( attribute "VOLTAGE" "16V"
					( Units "uVoltage" "V" 1.000000)
					( Origin gFrontEnd )
				)
				( attribute "XY" "(-5425,2175)"
					( Origin gFrontEnd )
				)
				( attribute "CHIPS_PART_NAME" "CAP"
					( Origin gPackager )
				)
				( attribute "CDS_PART_NAME" "CAP_0402-0.027UF,16V,10%,X7R,AA"
					( Origin gPackager )
				)
				( objectStatus "C7B11" )
				( pin "a"
					( attribute "PN" "1"
						( Origin gPackager )
					)
					( objectStatus "C7B11.1" )
				)
				( pin "b"
					( attribute "PN" "2"
						( Origin gPackager )
					)
					( objectStatus "C7B11.2" )
				)
			)
			( gate "@baseboard_fab2_lib.baseboard_fab2(sch_1):page232_i200"
				( attribute "CDS_LIB" "mstr_discrete"
					( Origin gPackager )
				)
				( attribute "CDS_LOCATION" "FB7B1"
					( Origin gPackager )
				)
				( attribute "CDS_SEC" "1"
					( Origin gPackager )
				)
				( attribute "LOCATION" "FB7B1"
					( Origin gFrontEnd )
				)
				( attribute "MATERIAL" "FB"
					( Origin gFrontEnd )
				)
				( attribute "PACK_TYPE" "SM"
					( Origin gFrontEnd )
				)
				( attribute "PART_NUMBER" "656554-051"
					( Origin gFrontEnd )
				)
				( attribute "PHYS_PAGE" "232"
					( Origin gFrontEnd )
				)
				( attribute "ROOM" "PVPP_KLM_VR"
					( Origin gFrontEnd )
				)
				( attribute "ROT" "0"
					( Origin gFrontEnd )
				)
				( attribute "SEC" "1"
					( Origin gFrontEnd )
				)
				( attribute "SEC_TYPE" "SM"
					( Origin gFrontEnd )
				)
				( attribute "TOLERANCE" "1%"
					( Origin gFrontEnd )
				)
				( attribute "VALUE" "22"
					( Origin gFrontEnd )
				)
				( attribute "VER" "1"
					( Origin gFrontEnd )
				)
				( attribute "XY" "(-7725,4300)"
					( Origin gFrontEnd )
				)
				( attribute "CHIPS_PART_NAME" "FERRITE"
					( Origin gPackager )
				)
				( attribute "CDS_PART_NAME" "FERRITE_SM-22,FB,656554-051"
					( Origin gPackager )
				)
				( objectStatus "FB7B1" )
				( pin "a"
					( attribute "PN" "1"
						( Origin gPackager )
					)
					( objectStatus "FB7B1.1" )
				)
				( pin "b"
					( attribute "PN" "2"
						( Origin gPackager )
					)
					( objectStatus "FB7B1.2" )
				)
			)
			( gate "@baseboard_fab2_lib.baseboard_fab2(sch_1):page232_i202"
				( attribute "BOM_COST" "PVPP_KLM_VR"
					( Origin gFrontEnd )
				)
				( attribute "CDS_LIB" "mstr_discrete"
					( Origin gPackager )
				)
				( attribute "CDS_LOCATION" "C7B8"
					( Origin gPackager )
				)
				( attribute "CDS_SEC" "1"
					( Origin gPackager )
				)
				( attribute "LOCATION" "C7B8"
					( Origin gFrontEnd )
				)
				( attribute "MATERIAL" "X6S"
					( Origin gFrontEnd )
				)
				( attribute "PACK_TYPE" "1210"
					( Origin gFrontEnd )
				)
				( attribute "PART_NUMBER" "D38464-007"
					( Origin gFrontEnd )
				)
				( attribute "PHYS_PAGE" "232"
					( Origin gFrontEnd )
				)
				( attribute "ROOM" "PVPP_KLM_VR"
					( Origin gFrontEnd )
				)
				( attribute "ROT" "0"
					( Origin gFrontEnd )
				)
				( attribute "SEC" "1"
					( Origin gPackager )
				)
				( attribute "TOLERANCE" "20%"
					( Origin gFrontEnd )
				)
				( attribute "VALUE" "47UF"
					( Origin gFrontEnd )
				)
				( attribute "VER" "1"
					( Origin gFrontEnd )
				)
				( attribute "VOLTAGE" "16V"
					( Units "uVoltage" "V" 1.000000)
					( Origin gFrontEnd )
				)
				( attribute "XY" "(-7375,4125)"
					( Origin gFrontEnd )
				)
				( attribute "CHIPS_PART_NAME" "CAP"
					( Origin gPackager )
				)
				( attribute "CDS_PART_NAME" "CAP_1210-47UF,16V,20%,X6S,D384A"
					( Origin gPackager )
				)
				( objectStatus "C7B8" )
				( pin "a"
					( attribute "PN" "1"
						( Origin gPackager )
					)
					( objectStatus "C7B8.1" )
				)
				( pin "b"
					( attribute "PN" "2"
						( Origin gPackager )
					)
					( objectStatus "C7B8.2" )
				)
			)
			( gate "@baseboard_fab2_lib.baseboard_fab2(sch_1):page232_i207"
				( attribute "BOM_COST" "PVPP_KLM_VR"
					( Origin gFrontEnd )
				)
				( attribute "CDS_LIB" "mstr_discrete"
					( Origin gPackager )
				)
				( attribute "CDS_LOCATION" "C3M9"
					( Origin gPackager )
				)
				( attribute "CDS_SEC" "1"
					( Origin gPackager )
				)
				( attribute "FIN" "VR_1P2"
					( Origin gFrontEnd )
				)
				( attribute "LOCATION" "C3M9"
					( Origin gFrontEnd )
				)
				( attribute "MATERIAL" "X6S"
					( Origin gFrontEnd )
				)
				( attribute "PACK_TYPE" "0402"
					( Origin gFrontEnd )
				)
				( attribute "PART_NUMBER" "D97712-011"
					( Origin gFrontEnd )
				)
				( attribute "PHYS_PAGE" "232"
					( Origin gFrontEnd )
				)
				( attribute "REUSE_ID" "1"
					( Origin gFrontEnd )
				)
				( attribute "ROOM" "PVPP_KLM_VR"
					( Origin gFrontEnd )
				)
				( attribute "ROT" "0"
					( Origin gFrontEnd )
				)
				( attribute "SEC" "1"
					( Origin gPackager )
				)
				( attribute "TOLERANCE" "10%"
					( Origin gFrontEnd )
				)
				( attribute "VALUE" "1.0UF"
					( Origin gFrontEnd )
				)
				( attribute "VER" "1"
					( Origin gFrontEnd )
				)
				( attribute "VOLTAGE" "16V"
					( Units "uVoltage" "V" 1.000000)
					( Origin gFrontEnd )
				)
				( attribute "XY" "(-5300,4150)"
					( Origin gFrontEnd )
				)
				( attribute "CHIPS_PART_NAME" "CAP"
					( Origin gPackager )
				)
				( attribute "CDS_PART_NAME" "CAP_0402-1.0UF,16V,10%,X6S,D97A"
					( Origin gPackager )
				)
				( objectStatus "C3M9" )
				( pin "a"
					( attribute "PN" "1"
						( Origin gPackager )
					)
					( objectStatus "C3M9.1" )
				)
				( pin "b"
					( attribute "PN" "2"
						( Origin gPackager )
					)
					( objectStatus "C3M9.2" )
				)
			)
			( gate "@baseboard_fab2_lib.baseboard_fab2(sch_1):page232_i209"
				( attribute "BOM_COST" "PVPP_KLM_VR"
					( Origin gFrontEnd )
				)
				( attribute "CDS_LIB" "mstr_discrete"
					( Origin gPackager )
				)
				( attribute "CDS_LOCATION" "C7B12"
					( Origin gPackager )
				)
				( attribute "CDS_SEC" "1"
					( Origin gPackager )
				)
				( attribute "LOCATION" "C7B12"
					( Origin gFrontEnd )
				)
				( attribute "MATERIAL" "X7R"
					( Origin gFrontEnd )
				)
				( attribute "PACK_TYPE" "0402LF"
					( Origin gFrontEnd )
				)
				( attribute "PART_NUMBER" "A36096-046"
					( Origin gFrontEnd )
				)
				( attribute "PHYS_PAGE" "232"
					( Origin gFrontEnd )
				)
				( attribute "REUSE_ID" "17"
					( Origin gFrontEnd )
				)
				( attribute "ROOM" "PVPP_KLM_VR"
					( Origin gFrontEnd )
				)
				( attribute "ROT" "0"
					( Origin gFrontEnd )
				)
				( attribute "SEC" "1"
					( Origin gPackager )
				)
				( attribute "TOLERANCE" "10%"
					( Origin gFrontEnd )
				)
				( attribute "VALUE" "1000PF"
					( Origin gFrontEnd )
				)
				( attribute "VER" "1"
					( Origin gFrontEnd )
				)
				( attribute "VOLTAGE" "50V"
					( Units "uVoltage" "V" 1.000000)
					( Origin gFrontEnd )
				)
				( attribute "XY" "(-4225,725)"
					( Origin gFrontEnd )
				)
				( attribute "CHIPS_PART_NAME" "CAP"
					( Origin gPackager )
				)
				( attribute "CDS_PART_NAME" "CAP_0402LF-1000PF,50V,10%,X7R,A"
					( Origin gPackager )
				)
				( objectStatus "C7B12" )
				( pin "a"
					( attribute "PN" "1"
						( Origin gPackager )
					)
					( objectStatus "C7B12.1" )
				)
				( pin "b"
					( attribute "PN" "2"
						( Origin gPackager )
					)
					( objectStatus "C7B12.2" )
				)
			)
			( gate "@baseboard_fab2_lib.baseboard_fab2(sch_1):page232_i210"
				( attribute "BOM_COST" "PVPP_KLM_VR"
					( Origin gFrontEnd )
				)
				( attribute "CDS_LIB" "mstr_discrete"
					( Origin gPackager )
				)
				( attribute "CDS_LOCATION" "R7B17"
					( Origin gPackager )
				)
				( attribute "CDS_SEC" "1"
					( Origin gPackager )
				)
				( attribute "LOCATION" "R7B17"
					( Origin gFrontEnd )
				)
				( attribute "MATERIAL" "CHIP"
					( Origin gFrontEnd )
				)
				( attribute "PACK_TYPE" "0402"
					( Origin gFrontEnd )
				)
				( attribute "PART_NUMBER" "G21796-026"
					( Origin gFrontEnd )
				)
				( attribute "PHYS_PAGE" "232"
					( Origin gFrontEnd )
				)
				( attribute "REUSE_ID" "21"
					( Origin gFrontEnd )
				)
				( attribute "ROOM" "PVPP_KLM_VR"
					( Origin gFrontEnd )
				)
				( attribute "ROT" "0"
					( Origin gFrontEnd )
				)
				( attribute "SEC" "1"
					( Origin gFrontEnd )
				)
				( attribute "SEC_TYPE" "0402"
					( Origin gFrontEnd )
				)
				( attribute "TOLERANCE" "1%"
					( Origin gFrontEnd )
				)
				( attribute "VALUE" "1.00K"
					( Origin gFrontEnd )
				)
				( attribute "VER" "2"
					( Origin gFrontEnd )
				)
				( attribute "WATTAGE" "1/16W"
					( Origin gFrontEnd )
				)
				( attribute "XY" "(-4575,1250)"
					( Origin gFrontEnd )
				)
				( attribute "CHIPS_PART_NAME" "RES"
					( Origin gPackager )
				)
				( attribute "CDS_PART_NAME" "RES_0402-1.00K,1%,1/16W,CHIP,GA"
					( Origin gPackager )
				)
				( objectStatus "R7B17" )
				( pin "a"
					( attribute "PN" "1"
						( Origin gPackager )
					)
					( objectStatus "R7B17.1" )
				)
				( pin "b"
					( attribute "PN" "2"
						( Origin gPackager )
					)
					( objectStatus "R7B17.2" )
				)
			)
			( gate "@baseboard_fab2_lib.baseboard_fab2(sch_1):page232_i214"
				( attribute "CDS_LIB" "mstr_vreg"
					( Origin gPackager )
				)
				( attribute "CDS_LMAN_SYM_OUTLINE" "-450,850,450,-900"
					( Origin gPackager )
				)
				( attribute "CDS_LOCATION" "EU7B1"
					( Origin gPackager )
				)
				( attribute "CDS_SEC" "1"
					( Origin gPackager )
				)
				( attribute "LOCATION" "EU7B1"
					( Origin gFrontEnd )
				)
				( attribute "MATERIAL" "IC"
					( Origin gFrontEnd )
				)
				( attribute "PACK_TYPE" "SM"
					( Origin gFrontEnd )
				)
				( attribute "PART_NUMBER" "H86355-001"
					( Origin gFrontEnd )
				)
				( attribute "PHYS_PAGE" "232"
					( Origin gFrontEnd )
				)
				( attribute "ROT" "0"
					( Origin gFrontEnd )
				)
				( attribute "SEC" "1"
					( Origin gFrontEnd )
				)
				( attribute "SEC_TYPE" "SM"
					( Origin gFrontEnd )
				)
				( attribute "VER" "1"
					( Origin gFrontEnd )
				)
				( attribute "XY" "(-4150,2875)"
					( Origin gFrontEnd )
				)
				( attribute "CHIPS_PART_NAME" "NCP3232L"
					( Origin gPackager )
				)
				( attribute "CDS_PART_NAME" "NCP3232L_SM-IC,H86355-001"
					( Origin gPackager )
				)
				( objectStatus "EU7B1" )
				( pin "agnd"
					( attribute "PN" "5"
						( Origin gPackager )
					)
					( objectStatus "EU7B1.5" )
				)
				( pin "bst"
					( attribute "PN" "36"
						( Origin gPackager )
					)
					( objectStatus "EU7B1.36" )
				)
				( pin "comp"
					( attribute "PN" "3"
						( Origin gPackager )
					)
					( objectStatus "EU7B1.3" )
				)
				( pin "en"
					( attribute "PN" "40"
						( Origin gPackager )
					)
					( objectStatus "EU7B1.40" )
				)
				( pin "fb"
					( attribute "PN" "2"
						( Origin gPackager )
					)
					( objectStatus "EU7B1.2" )
				)
				( pin "gnd"
					( attribute "PN" "41"
						( Origin gPackager )
					)
					( objectStatus "EU7B1.41" )
				)
				( pin "iset"
					( attribute "PN" "4"
						( Origin gPackager )
					)
					( objectStatus "EU7B1.4" )
				)
				( pin "ots"
					( attribute "PN" "6"
						( Origin gPackager )
					)
					( objectStatus "EU7B1.6" )
				)
				( pin "pg"
					( attribute "PN" "7"
						( Origin gPackager )
					)
					( objectStatus "EU7B1.7" )
				)
				( pin "pgnd(0)"
					( attribute "PN" "16"
						( Origin gPackager )
					)
					( objectStatus "EU7B1.16" )
				)
				( pin "pgnd(1)"
					( attribute "PN" "17"
						( Origin gPackager )
					)
					( objectStatus "EU7B1.17" )
				)
				( pin "pgnd(2)"
					( attribute "PN" "18"
						( Origin gPackager )
					)
					( objectStatus "EU7B1.18" )
				)
				( pin "pgnd(3)"
					( attribute "PN" "19"
						( Origin gPackager )
					)
					( objectStatus "EU7B1.19" )
				)
				( pin "pgnd(4)"
					( attribute "PN" "20"
						( Origin gPackager )
					)
					( objectStatus "EU7B1.20" )
				)
				( pin "pgnd(5)"
					( attribute "PN" "21"
						( Origin gPackager )
					)
					( objectStatus "EU7B1.21" )
				)
				( pin "pgnd(6)"
					( attribute "PN" "22"
						( Origin gPackager )
					)
					( objectStatus "EU7B1.22" )
				)
				( pin "pgnd(7)"
					( attribute "PN" "23"
						( Origin gPackager )
					)
					( objectStatus "EU7B1.23" )
				)
				( pin "pgnd(8)"
					( attribute "PN" "24"
						( Origin gPackager )
					)
					( objectStatus "EU7B1.24" )
				)
				( pin "pgnd(9)"
					( attribute "PN" "25"
						( Origin gPackager )
					)
					( objectStatus "EU7B1.25" )
				)
				( pin "pgnd(10)"
					( attribute "PN" "26"
						( Origin gPackager )
					)
					( objectStatus "EU7B1.26" )
				)
				( pin "pgnd(11)"
					( attribute "PN" "27"
						( Origin gPackager )
					)
					( objectStatus "EU7B1.27" )
				)
				( pin "pgnd(12)"
					( attribute "PN" "28"
						( Origin gPackager )
					)
					( objectStatus "EU7B1.28" )
				)
				( pin "pgnd(13)"
					( attribute "PN" "37"
						( Origin gPackager )
					)
					( objectStatus "EU7B1.37" )
				)
				( pin "ss"
					( attribute "PN" "1"
						( Origin gPackager )
					)
					( objectStatus "EU7B1.1" )
				)
				( pin "vb"
					( attribute "PN" "38"
						( Origin gPackager )
					)
					( objectStatus "EU7B1.38" )
				)
				( pin "vcc"
					( attribute "PN" "39"
						( Origin gPackager )
					)
					( objectStatus "EU7B1.39" )
				)
				( pin "vin(0)"
					( attribute "PN" "8"
						( Origin gPackager )
					)
					( objectStatus "EU7B1.8" )
				)
				( pin "vin(1)"
					( attribute "PN" "9"
						( Origin gPackager )
					)
					( objectStatus "EU7B1.9" )
				)
				( pin "vin(2)"
					( attribute "PN" "10"
						( Origin gPackager )
					)
					( objectStatus "EU7B1.10" )
				)
				( pin "vin(3)"
					( attribute "PN" "11"
						( Origin gPackager )
					)
					( objectStatus "EU7B1.11" )
				)
				( pin "vin(4)"
					( attribute "PN" "12"
						( Origin gPackager )
					)
					( objectStatus "EU7B1.12" )
				)
				( pin "vin(5)"
					( attribute "PN" "13"
						( Origin gPackager )
					)
					( objectStatus "EU7B1.13" )
				)
				( pin "vin(6)"
					( attribute "PN" "14"
						( Origin gPackager )
					)
					( objectStatus "EU7B1.14" )
				)
				( pin "vin(7)"
					( attribute "PN" "42"
						( Origin gPackager )
					)
					( objectStatus "EU7B1.42" )
				)
				( pin "vsw"
					( attribute "PN" "35"
						( Origin gPackager )
					)
					( objectStatus "EU7B1.35" )
				)
				( pin "vswh(0)"
					( attribute "PN" "15"
						( Origin gPackager )
					)
					( objectStatus "EU7B1.15" )
				)
				( pin "vswh(1)"
					( attribute "PN" "29"
						( Origin gPackager )
					)
					( objectStatus "EU7B1.29" )
				)
				( pin "vswh(2)"
					( attribute "PN" "30"
						( Origin gPackager )
					)
					( objectStatus "EU7B1.30" )
				)
				( pin "vswh(3)"
					( attribute "PN" "31"
						( Origin gPackager )
					)
					( objectStatus "EU7B1.31" )
				)
				( pin "vswh(4)"
					( attribute "PN" "32"
						( Origin gPackager )
					)
					( objectStatus "EU7B1.32" )
				)
				( pin "vswh(5)"
					( attribute "PN" "33"
						( Origin gPackager )
					)
					( objectStatus "EU7B1.33" )
				)
				( pin "vswh(6)"
					( attribute "PN" "34"
						( Origin gPackager )
					)
					( objectStatus "EU7B1.34" )
				)
				( pin "vswh(7)"
					( attribute "PN" "43"
						( Origin gPackager )
					)
					( objectStatus "EU7B1.43" )
				)
			)
			( gate "@baseboard_fab2_lib.baseboard_fab2(sch_1):page232_i218"
				( attribute "BOM_COST" "PVPP_KLM_VR"
					( Origin gFrontEnd )
				)
				( attribute "CDS_LIB" "mstr_discrete"
					( Origin gPackager )
				)
				( attribute "CDS_LOCATION" "R7A15"
					( Origin gPackager )
				)
				( attribute "CDS_SEC" "1"
					( Origin gPackager )
				)
				( attribute "LOCATION" "R7A15"
					( Origin gFrontEnd )
				)
				( attribute "MATERIAL" "EMPTY"
					( Origin gFrontEnd )
				)
				( attribute "PACK_TYPE" "0402"
					( Origin gFrontEnd )
				)
				( attribute "PART_NUMBER" "G21497-016"
					( Origin gFrontEnd )
				)
				( attribute "PHYS_PAGE" "232"
					( Origin gFrontEnd )
				)
				( attribute "REUSE_ID" "29"
					( Origin gFrontEnd )
				)
				( attribute "ROOM" "PVPP_KLM_VR"
					( Origin gFrontEnd )
				)
				( attribute "ROT" "0"
					( Origin gFrontEnd )
				)
				( attribute "SEC" "1"
					( Origin gFrontEnd )
				)
				( attribute "SEC_TYPE" "0402"
					( Origin gFrontEnd )
				)
				( attribute "TOLERANCE" "5%"
					( Origin gFrontEnd )
				)
				( attribute "VALUE" "2.2"
					( Origin gFrontEnd )
				)
				( attribute "VER" "2"
					( Origin gFrontEnd )
				)
				( attribute "WATTAGE" "1/16W"
					( Origin gFrontEnd )
				)
				( attribute "XY" "(-3000,3350)"
					( Origin gFrontEnd )
				)
				( attribute "CHIPS_PART_NAME" "RES"
					( Origin gPackager )
				)
				( attribute "CDS_PART_NAME" "RES_0402-2.2,5%,1/16W,EMPTY,G2A"
					( Origin gPackager )
				)
				( objectStatus "R7A15" )
				( pin "a"
					( attribute "PN" "1"
						( Origin gPackager )
					)
					( objectStatus "R7A15.1" )
				)
				( pin "b"
					( attribute "PN" "2"
						( Origin gPackager )
					)
					( objectStatus "R7A15.2" )
				)
			)
			( gate "@baseboard_fab2_lib.baseboard_fab2(sch_1):page232_i220"
				( attribute "BOM_COST" "PVPP_KLM_VR"
					( Origin gFrontEnd )
				)
				( attribute "CDS_LIB" "mstr_discrete"
					( Origin gPackager )
				)
				( attribute "CDS_LOCATION" "C7A34"
					( Origin gPackager )
				)
				( attribute "CDS_SEC" "1"
					( Origin gPackager )
				)
				( attribute "LOCATION" "C7A34"
					( Origin gFrontEnd )
				)
				( attribute "MATERIAL" "EMPTY"
					( Origin gFrontEnd )
				)
				( attribute "PACK_TYPE" "0402LF"
					( Origin gFrontEnd )
				)
				( attribute "PART_NUMBER" "A36096-091"
					( Origin gFrontEnd )
				)
				( attribute "PHYS_PAGE" "232"
					( Origin gFrontEnd )
				)
				( attribute "REUSE_ID" "26"
					( Origin gFrontEnd )
				)
				( attribute "ROOM" "PVPP_KLM_VR"
					( Origin gFrontEnd )
				)
				( attribute "ROT" "0"
					( Origin gFrontEnd )
				)
				( attribute "SEC" "1"
					( Origin gFrontEnd )
				)
				( attribute "SEC_TYPE" "0402LF"
					( Origin gFrontEnd )
				)
				( attribute "TOLERANCE" "10%"
					( Origin gFrontEnd )
				)
				( attribute "VALUE" "3300PF"
					( Origin gFrontEnd )
				)
				( attribute "VER" "1"
					( Origin gFrontEnd )
				)
				( attribute "VOLTAGE" "50V"
					( Units "uVoltage" "V" 1.000000)
					( Origin gFrontEnd )
				)
				( attribute "XY" "(-3000,3700)"
					( Origin gFrontEnd )
				)
				( attribute "CHIPS_PART_NAME" "CAP"
					( Origin gPackager )
				)
				( attribute "CDS_PART_NAME" "CAP_0402LF-3300PF,50V,10%,EMPTA"
					( Origin gPackager )
				)
				( objectStatus "C7A34" )
				( pin "a"
					( attribute "PN" "1"
						( Origin gPackager )
					)
					( objectStatus "C7A34.1" )
				)
				( pin "b"
					( attribute "PN" "2"
						( Origin gPackager )
					)
					( objectStatus "C7A34.2" )
				)
			)
			( gate "@baseboard_fab2_lib.baseboard_fab2(sch_1):page232_i227"
				( attribute "BOM_COST" "PVPP_KLM_VR"
					( Origin gFrontEnd )
				)
				( attribute "CDS_LIB" "mstr_discrete"
					( Origin gPackager )
				)
				( attribute "CDS_LOCATION" "R7B10"
					( Origin gPackager )
				)
				( attribute "CDS_SEC" "1"
					( Origin gPackager )
				)
				( attribute "LOCATION" "R7B10"
					( Origin gFrontEnd )
				)
				( attribute "MATERIAL" "CHIP"
					( Origin gFrontEnd )
				)
				( attribute "PACK_TYPE" "0603"
					( Origin gFrontEnd )
				)
				( attribute "PART_NUMBER" "G22026-003"
					( Origin gFrontEnd )
				)
				( attribute "PHYS_PAGE" "232"
					( Origin gFrontEnd )
				)
				( attribute "REUSE_ID" "34"
					( Origin gFrontEnd )
				)
				( attribute "ROOM" "PVPP_KLM_VR"
					( Origin gFrontEnd )
				)
				( attribute "ROT" "0"
					( Origin gFrontEnd )
				)
				( attribute "SEC" "1"
					( Origin gFrontEnd )
				)
				( attribute "SEC_TYPE" "0603"
					( Origin gFrontEnd )
				)
				( attribute "TOLERANCE" "1%"
					( Origin gFrontEnd )
				)
				( attribute "VALUE" "120.0"
					( Origin gFrontEnd )
				)
				( attribute "VER" "2"
					( Origin gFrontEnd )
				)
				( attribute "WATTAGE" "1/10W"
					( Origin gFrontEnd )
				)
				( attribute "XY" "(-2425,3675)"
					( Origin gFrontEnd )
				)
				( attribute "CHIPS_PART_NAME" "RES"
					( Origin gPackager )
				)
				( attribute "CDS_PART_NAME" "RES_0603-120.0,1%,1/10W,CHIP,GA"
					( Origin gPackager )
				)
				( objectStatus "R7B10" )
				( pin "a"
					( attribute "PN" "1"
						( Origin gPackager )
					)
					( objectStatus "R7B10.1" )
				)
				( pin "b"
					( attribute "PN" "2"
						( Origin gPackager )
					)
					( objectStatus "R7B10.2" )
				)
			)
			( gate "@baseboard_fab2_lib.baseboard_fab2(sch_1):page232_i229"
				( attribute "BOM_COST" "PVPP_KLM_VR"
					( Origin gFrontEnd )
				)
				( attribute "CDS_LIB" "mstr_discrete"
					( Origin gPackager )
				)
				( attribute "CDS_LOCATION" "C6B7"
					( Origin gPackager )
				)
				( attribute "CDS_SEC" "1"
					( Origin gPackager )
				)
				( attribute "LOCATION" "C6B7"
					( Origin gFrontEnd )
				)
				( attribute "MATERIAL" "POSCAP"
					( Origin gFrontEnd )
				)
				( attribute "PACK_TYPE" "7343LF"
					( Origin gFrontEnd )
				)
				( attribute "PART_NUMBER" "724613-042"
					( Origin gFrontEnd )
				)
				( attribute "PHYS_PAGE" "232"
					( Origin gFrontEnd )
				)
				( attribute "REUSE_ID" "28"
					( Origin gFrontEnd )
				)
				( attribute "ROOM" "PVPP_KLM_VR"
					( Origin gFrontEnd )
				)
				( attribute "ROT" "0"
					( Origin gFrontEnd )
				)
				( attribute "SEC" "1"
					( Origin gPackager )
				)
				( attribute "TOLERANCE" "20%"
					( Origin gFrontEnd )
				)
				( attribute "VALUE" "330UF"
					( Origin gFrontEnd )
				)
				( attribute "VER" "1"
					( Origin gFrontEnd )
				)
				( attribute "VOLTAGE" "6.3V"
					( Units "uVoltage" "V" 1.000000)
					( Origin gFrontEnd )
				)
				( attribute "XY" "(-2075,3675)"
					( Origin gFrontEnd )
				)
				( attribute "CHIPS_PART_NAME" "CAPP"
					( Origin gPackager )
				)
				( attribute "CDS_PART_NAME" "CAPP_7343LF-330UF,6.3V,20%,POSA"
					( Origin gPackager )
				)
				( objectStatus "C6B7" )
				( pin "a"
					( attribute "PN" "1"
						( Origin gPackager )
					)
					( objectStatus "C6B7.1" )
				)
				( pin "b"
					( attribute "PN" "2"
						( Origin gPackager )
					)
					( objectStatus "C6B7.2" )
				)
			)
			( gate "@baseboard_fab2_lib.baseboard_fab2(sch_1):page232_i236"
				( attribute "BOM_COST" "PVPP_KLM_VR"
					( Origin gFrontEnd )
				)
				( attribute "CDS_LIB" "mstr_discrete"
					( Origin gPackager )
				)
				( attribute "CDS_LOCATION" "C6B3"
					( Origin gPackager )
				)
				( attribute "CDS_SEC" "1"
					( Origin gPackager )
				)
				( attribute "LOCATION" "C6B3"
					( Origin gFrontEnd )
				)
				( attribute "MATERIAL" "X6S"
					( Origin gFrontEnd )
				)
				( attribute "PACK_TYPE" "0805"
					( Origin gFrontEnd )
				)
				( attribute "PART_NUMBER" "C95333-006"
					( Origin gFrontEnd )
				)
				( attribute "PHYS_PAGE" "232"
					( Origin gFrontEnd )
				)
				( attribute "REUSE_ID" "33"
					( Origin gFrontEnd )
				)
				( attribute "ROOM" "PVPP_KLM_VR"
					( Origin gFrontEnd )
				)
				( attribute "ROT" "0"
					( Origin gFrontEnd )
				)
				( attribute "SEC" "1"
					( Origin gPackager )
				)
				( attribute "TOLERANCE" "20%"
					( Origin gFrontEnd )
				)
				( attribute "VALUE" "47UF"
					( Origin gFrontEnd )
				)
				( attribute "VER" "1"
					( Origin gFrontEnd )
				)
				( attribute "VOLTAGE" "4V"
					( Units "uVoltage" "V" 1.000000)
					( Origin gFrontEnd )
				)
				( attribute "XY" "(-1475,3675)"
					( Origin gFrontEnd )
				)
				( attribute "CHIPS_PART_NAME" "CAP"
					( Origin gPackager )
				)
				( attribute "CDS_PART_NAME" "CAP_0805-47UF,4V,20%,X6S,C9533A"
					( Origin gPackager )
				)
				( objectStatus "C6B3" )
				( pin "a"
					( attribute "PN" "1"
						( Origin gPackager )
					)
					( objectStatus "C6B3.1" )
				)
				( pin "b"
					( attribute "PN" "2"
						( Origin gPackager )
					)
					( objectStatus "C6B3.2" )
				)
			)
			( gate "@baseboard_fab2_lib.baseboard_fab2(sch_1):page232_i238"
				( attribute "BOM_COST" "PVPP_KLM_VR"
					( Origin gFrontEnd )
				)
				( attribute "CDS_LIB" "mstr_discrete"
					( Origin gPackager )
				)
				( attribute "CDS_LOCATION" "C7B7"
					( Origin gPackager )
				)
				( attribute "CDS_SEC" "1"
					( Origin gPackager )
				)
				( attribute "LOCATION" "C7B7"
					( Origin gFrontEnd )
				)
				( attribute "MATERIAL" "X6S"
					( Origin gFrontEnd )
				)
				( attribute "PACK_TYPE" "0805"
					( Origin gFrontEnd )
				)
				( attribute "PART_NUMBER" "C95333-006"
					( Origin gFrontEnd )
				)
				( attribute "PHYS_PAGE" "232"
					( Origin gFrontEnd )
				)
				( attribute "REUSE_ID" "33"
					( Origin gFrontEnd )
				)
				( attribute "ROOM" "PVPP_KLM_VR"
					( Origin gFrontEnd )
				)
				( attribute "ROT" "0"
					( Origin gFrontEnd )
				)
				( attribute "SEC" "1"
					( Origin gPackager )
				)
				( attribute "TOLERANCE" "20%"
					( Origin gFrontEnd )
				)
				( attribute "VALUE" "47UF"
					( Origin gFrontEnd )
				)
				( attribute "VER" "1"
					( Origin gFrontEnd )
				)
				( attribute "VOLTAGE" "4V"
					( Units "uVoltage" "V" 1.000000)
					( Origin gFrontEnd )
				)
				( attribute "XY" "(-1200,3675)"
					( Origin gFrontEnd )
				)
				( attribute "CHIPS_PART_NAME" "CAP"
					( Origin gPackager )
				)
				( attribute "CDS_PART_NAME" "CAP_0805-47UF,4V,20%,X6S,C9533A"
					( Origin gPackager )
				)
				( objectStatus "C7B7" )
				( pin "a"
					( attribute "PN" "1"
						( Origin gPackager )
					)
					( objectStatus "C7B7.1" )
				)
				( pin "b"
					( attribute "PN" "2"
						( Origin gPackager )
					)
					( objectStatus "C7B7.2" )
				)
			)
			( gate "@baseboard_fab2_lib.baseboard_fab2(sch_1):page232_i239"
				( attribute "BOM_COST" "PVPP_KLM_VR"
					( Origin gFrontEnd )
				)
				( attribute "CDS_LIB" "mstr_discrete"
					( Origin gPackager )
				)
				( attribute "CDS_LOCATION" "L7B1"
					( Origin gPackager )
				)
				( attribute "CDS_SEC" "1"
					( Origin gPackager )
				)
				( attribute "LOCATION" "L7B1"
					( Origin gFrontEnd )
				)
				( attribute "MATERIAL" "IND"
					( Origin gFrontEnd )
				)
				( attribute "PACK_TYPE" "SM"
					( Origin gFrontEnd )
				)
				( attribute "PART_NUMBER" "E13358-018"
					( Origin gFrontEnd )
				)
				( attribute "PHYS_PAGE" "232"
					( Origin gFrontEnd )
				)
				( attribute "REUSE_ID" "30"
					( Origin gFrontEnd )
				)
				( attribute "ROOM" "PVPP_KLM_VR"
					( Origin gFrontEnd )
				)
				( attribute "ROT" "0"
					( Origin gFrontEnd )
				)
				( attribute "SEC" "1"
					( Origin gPackager )
				)
				( attribute "TOLERANCE" "1%"
					( Origin gFrontEnd )
				)
				( attribute "VALUE" "0.47UH"
					( Origin gFrontEnd )
				)
				( attribute "VER" "1"
					( Origin gFrontEnd )
				)
				( attribute "XY" "(-2650,3850)"
					( Origin gFrontEnd )
				)
				( attribute "CHIPS_PART_NAME" "INDUCTOR"
					( Origin gPackager )
				)
				( attribute "CDS_PART_NAME" "INDUCTOR_SM-0.47UH,IND,E13358-A"
					( Origin gPackager )
				)
				( objectStatus "L7B1" )
				( pin "ina"
					( attribute "PN" "1"
						( Origin gPackager )
					)
					( objectStatus "L7B1.1" )
				)
				( pin "inb"
					( attribute "PN" "2"
						( Origin gPackager )
					)
					( objectStatus "L7B1.2" )
				)
			)
			( gate "@baseboard_fab2_lib.baseboard_fab2(sch_1):page232_i240"
				( attribute "BOM_COST" "PVPP_KLM_VR"
					( Origin gFrontEnd )
				)
				( attribute "CDS_LIB" "mstr_discrete"
					( Origin gPackager )
				)
				( attribute "CDS_LOCATION" "R7B19"
					( Origin gPackager )
				)
				( attribute "CDS_SEC" "1"
					( Origin gPackager )
				)
				( attribute "LOCATION" "R7B19"
					( Origin gFrontEnd )
				)
				( attribute "MATERIAL" "CHIP"
					( Origin gFrontEnd )
				)
				( attribute "PACK_TYPE" "0402"
					( Origin gFrontEnd )
				)
				( attribute "PART_NUMBER" "G21497-005"
					( Origin gFrontEnd )
				)
				( attribute "PHYS_PAGE" "232"
					( Origin gFrontEnd )
				)
				( attribute "REUSE_ID" "13"
					( Origin gFrontEnd )
				)
				( attribute "ROOM" "PVPP_KLM_VR"
					( Origin gFrontEnd )
				)
				( attribute "ROT" "0"
					( Origin gFrontEnd )
				)
				( attribute "SEC" "1"
					( Origin gPackager )
				)
				( attribute "SPOF" "TRUE"
					( Origin gFrontEnd )
				)
				( attribute "TOLERANCE" "5%"
					( Origin gFrontEnd )
				)
				( attribute "VALUE" "0.0"
					( Origin gFrontEnd )
				)
				( attribute "VER" "1"
					( Origin gFrontEnd )
				)
				( attribute "WATTAGE" "1/16W"
					( Origin gFrontEnd )
				)
				( attribute "XY" "(-4425,4200)"
					( Origin gFrontEnd )
				)
				( attribute "CHIPS_PART_NAME" "RES"
					( Origin gPackager )
				)
				( attribute "CDS_PART_NAME" "RES_0402-0.0,5%,1/16W,CHIP,G21A"
					( Origin gPackager )
				)
				( objectStatus "R7B19" )
				( pin "a"
					( attribute "PN" "1"
						( Origin gPackager )
					)
					( objectStatus "R7B19.1" )
				)
				( pin "b"
					( attribute "PN" "2"
						( Origin gPackager )
					)
					( objectStatus "R7B19.2" )
				)
			)
			( gate "@baseboard_fab2_lib.baseboard_fab2(sch_1):page232_i241"
				( attribute "BOM_COST" "PVPP_KLM_VR"
					( Origin gFrontEnd )
				)
				( attribute "CDS_LIB" "mstr_discrete"
					( Origin gPackager )
				)
				( attribute "CDS_LOCATION" "C7B30"
					( Origin gPackager )
				)
				( attribute "CDS_SEC" "1"
					( Origin gPackager )
				)
				( attribute "LOCATION" "C7B30"
					( Origin gFrontEnd )
				)
				( attribute "MATERIAL" "X7R"
					( Origin gFrontEnd )
				)
				( attribute "PACK_TYPE" "0603LF"
					( Origin gFrontEnd )
				)
				( attribute "PART_NUMBER" "602433-020"
					( Origin gFrontEnd )
				)
				( attribute "PHYS_PAGE" "232"
					( Origin gFrontEnd )
				)
				( attribute "REUSE_ID" "27"
					( Origin gFrontEnd )
				)
				( attribute "ROOM" "PVPP_KLM_VR"
					( Origin gFrontEnd )
				)
				( attribute "ROT" "2"
					( Origin gFrontEnd )
				)
				( attribute "SEC" "1"
					( Origin gPackager )
				)
				( attribute "SPOF" "TRUE"
					( Origin gFrontEnd )
				)
				( attribute "TOLERANCE" "10%"
					( Origin gFrontEnd )
				)
				( attribute "VALUE" "0.1UF"
					( Origin gFrontEnd )
				)
				( attribute "VER" "2"
					( Origin gFrontEnd )
				)
				( attribute "VOLTAGE" "25V"
					( Units "uVoltage" "V" 1.000000)
					( Origin gFrontEnd )
				)
				( attribute "XY" "(-3725,4200)"
					( Origin gFrontEnd )
				)
				( attribute "CHIPS_PART_NAME" "CAP"
					( Origin gPackager )
				)
				( attribute "CDS_PART_NAME" "CAP_0603LF-0.1UF,25V,10%,X7R,6A"
					( Origin gPackager )
				)
				( objectStatus "C7B30" )
				( pin "a"
					( attribute "PN" "1"
						( Origin gPackager )
					)
					( objectStatus "C7B30.1" )
				)
				( pin "b"
					( attribute "PN" "2"
						( Origin gPackager )
					)
					( objectStatus "C7B30.2" )
				)
			)
			( gate "@baseboard_fab2_lib.baseboard_fab2(sch_1):page232_i252"
				( attribute "CDS_LIB" "dev_discrete"
					( Origin gPackager )
				)
				( attribute "CDS_LOCATION" "C7B6"
					( Origin gPackager )
				)
				( attribute "CDS_SEC" "1"
					( Origin gPackager )
				)
				( attribute "LOCATION" "C7B6"
					( Origin gFrontEnd )
				)
				( attribute "MATERIAL" "X7R"
					( Origin gFrontEnd )
				)
				( attribute "PACK_TYPE" "0402V"
					( Origin gFrontEnd )
				)
				( attribute "PART_NUMBER" "A36096-030"
					( Origin gFrontEnd )
				)
				( attribute "PHYS_PAGE" "232"
					( Origin gFrontEnd )
				)
				( attribute "ROT" "0"
					( Origin gFrontEnd )
				)
				( attribute "SEC" "1"
					( Origin gFrontEnd )
				)
				( attribute "SEC_TYPE" "0402V"
					( Origin gFrontEnd )
				)
				( attribute "TOLERANCE" "10%"
					( Origin gFrontEnd )
				)
				( attribute "VALUE" "0.1UF"
					( Origin gFrontEnd )
				)
				( attribute "VER" "1"
					( Origin gFrontEnd )
				)
				( attribute "VOLTAGE" "16V"
					( Units "uVoltage" "V" 1.000000)
					( Origin gFrontEnd )
				)
				( attribute "XY" "(-5475,3525)"
					( Origin gFrontEnd )
				)
				( attribute "CHIPS_PART_NAME" "CAP_A"
					( Origin gPackager )
				)
				( attribute "CDS_PART_NAME" "CAP_A_0402V-0.1UF,16V,10%,X7R,A"
					( Origin gPackager )
				)
				( objectStatus "C7B6" )
				( pin "a"
					( attribute "PN" "1"
						( Origin gPackager )
					)
					( objectStatus "C7B6.1" )
				)
				( pin "b"
					( attribute "PN" "2"
						( Origin gPackager )
					)
					( objectStatus "C7B6.2" )
				)
			)
			( gate "@baseboard_fab2_lib.baseboard_fab2(sch_1):page232_i253"
				( attribute "BOM_COST" "PVPP_KLM_VR"
					( Origin gFrontEnd )
				)
				( attribute "CDS_LIB" "mstr_discrete"
					( Origin gPackager )
				)
				( attribute "CDS_LOCATION" "C3M10"
					( Origin gPackager )
				)
				( attribute "CDS_SEC" "1"
					( Origin gPackager )
				)
				( attribute "LOCATION" "C3M10"
					( Origin gFrontEnd )
				)
				( attribute "MATERIAL" "X6S"
					( Origin gFrontEnd )
				)
				( attribute "PACK_TYPE" "0603"
					( Origin gFrontEnd )
				)
				( attribute "PART_NUMBER" "E15431-003"
					( Origin gFrontEnd )
				)
				( attribute "PHYS_PAGE" "232"
					( Origin gFrontEnd )
				)
				( attribute "REUSE_ID" "26"
					( Origin gFrontEnd )
				)
				( attribute "ROOM" "PVPP_KLM_VR"
					( Origin gFrontEnd )
				)
				( attribute "ROT" "0"
					( Origin gFrontEnd )
				)
				( attribute "SEC" "1"
					( Origin gFrontEnd )
				)
				( attribute "SEC_TYPE" "0603"
					( Origin gFrontEnd )
				)
				( attribute "TOLERANCE" "10%"
					( Origin gFrontEnd )
				)
				( attribute "VALUE" "4.7UF"
					( Origin gFrontEnd )
				)
				( attribute "VER" "1"
					( Origin gFrontEnd )
				)
				( attribute "VOLTAGE" "6.3V"
					( Units "uVoltage" "V" 1.000000)
					( Origin gFrontEnd )
				)
				( attribute "XY" "(-6125,2425)"
					( Origin gFrontEnd )
				)
				( attribute "CHIPS_PART_NAME" "CAP"
					( Origin gPackager )
				)
				( attribute "CDS_PART_NAME" "CAP_0603-4.7UF,6.3V,10%,X6S,E1A"
					( Origin gPackager )
				)
				( objectStatus "C3M10" )
				( pin "a"
					( attribute "PN" "1"
						( Origin gPackager )
					)
					( objectStatus "C3M10.1" )
				)
				( pin "b"
					( attribute "PN" "2"
						( Origin gPackager )
					)
					( objectStatus "C3M10.2" )
				)
			)
			( gate "@baseboard_fab2_lib.baseboard_fab2(sch_1):page232_i257"
				( attribute "CDS_LIB" "mstr_discrete"
					( Origin gPackager )
				)
				( attribute "CDS_LOCATION" "R7B12"
					( Origin gPackager )
				)
				( attribute "CDS_SEC" "1"
					( Origin gPackager )
				)
				( attribute "LOCATION" "R7B12"
					( Origin gFrontEnd )
				)
				( attribute "MATERIAL" "CHIP"
					( Origin gFrontEnd )
				)
				( attribute "PACK_TYPE" "0402"
					( Origin gFrontEnd )
				)
				( attribute "PART_NUMBER" "G21796-250"
					( Origin gFrontEnd )
				)
				( attribute "PHYS_PAGE" "232"
					( Origin gFrontEnd )
				)
				( attribute "ROOM" "PVPP_DEF_VR"
					( Origin gFrontEnd )
				)
				( attribute "ROT" "0"
					( Origin gFrontEnd )
				)
				( attribute "SEC" "1"
					( Origin gFrontEnd )
				)
				( attribute "SEC_TYPE" "0402"
					( Origin gFrontEnd )
				)
				( attribute "TOLERANCE" "1.0%"
					( Origin gFrontEnd )
				)
				( attribute "VALUE" "22.1"
					( Origin gFrontEnd )
				)
				( attribute "VER" "1"
					( Origin gFrontEnd )
				)
				( attribute "WATTAGE" "1/16W"
					( Origin gFrontEnd )
				)
				( attribute "XY" "(-3875,975)"
					( Origin gFrontEnd )
				)
				( attribute "CHIPS_PART_NAME" "RES"
					( Origin gPackager )
				)
				( attribute "CDS_PART_NAME" "RES_0402-22.1,1.0%,1/16W,CHIP,A"
					( Origin gPackager )
				)
				( objectStatus "R7B12" )
				( pin "a"
					( attribute "PN" "1"
						( Origin gPackager )
					)
					( objectStatus "R7B12.1" )
				)
				( pin "b"
					( attribute "PN" "2"
						( Origin gPackager )
					)
					( objectStatus "R7B12.2" )
				)
			)
			( gate "@baseboard_fab2_lib.baseboard_fab2(sch_1):page232_i259"
				( attribute "CDS_LIB" "mstr_discrete"
					( Origin gPackager )
				)
				( attribute "CDS_LOCATION" "C3M8"
					( Origin gPackager )
				)
				( attribute "CDS_SEC" "1"
					( Origin gPackager )
				)
				( attribute "LOCATION" "C3M8"
					( Origin gFrontEnd )
				)
				( attribute "MATERIAL" "X6S"
					( Origin gFrontEnd )
				)
				( attribute "PACK_TYPE" "0805"
					( Origin gFrontEnd )
				)
				( attribute "PART_NUMBER" "C95333-007"
					( Origin gFrontEnd )
				)
				( attribute "PHYS_PAGE" "232"
					( Origin gFrontEnd )
				)
				( attribute "ROT" "0"
					( Origin gFrontEnd )
				)
				( attribute "SEC" "1"
					( Origin gFrontEnd )
				)
				( attribute "SEC_TYPE" "0805"
					( Origin gFrontEnd )
				)
				( attribute "TOLERANCE" "10%"
					( Origin gFrontEnd )
				)
				( attribute "VALUE" "10UF"
					( Origin gFrontEnd )
				)
				( attribute "VER" "1"
					( Origin gFrontEnd )
				)
				( attribute "VOLTAGE" "16V"
					( Units "uVoltage" "V" 1.000000)
					( Origin gFrontEnd )
				)
				( attribute "XY" "(-6975,4100)"
					( Origin gFrontEnd )
				)
				( attribute "CHIPS_PART_NAME" "CAP"
					( Origin gPackager )
				)
				( attribute "CDS_PART_NAME" "CAP_0805-10UF,16V,10%,X6S,C953A"
					( Origin gPackager )
				)
				( objectStatus "C3M8" )
				( pin "a"
					( attribute "PN" "1"
						( Origin gPackager )
					)
					( objectStatus "C3M8.1" )
				)
				( pin "b"
					( attribute "PN" "2"
						( Origin gPackager )
					)
					( objectStatus "C3M8.2" )
				)
			)
			( gate "@baseboard_fab2_lib.baseboard_fab2(sch_1):page232_i260"
				( attribute "CDS_LIB" "mstr_discrete"
					( Origin gPackager )
				)
				( attribute "CDS_LOCATION" "C3M15"
					( Origin gPackager )
				)
				( attribute "CDS_SEC" "1"
					( Origin gPackager )
				)
				( attribute "LOCATION" "C3M15"
					( Origin gFrontEnd )
				)
				( attribute "MATERIAL" "X6S"
					( Origin gFrontEnd )
				)
				( attribute "PACK_TYPE" "0805"
					( Origin gFrontEnd )
				)
				( attribute "PART_NUMBER" "C95333-007"
					( Origin gFrontEnd )
				)
				( attribute "PHYS_PAGE" "232"
					( Origin gFrontEnd )
				)
				( attribute "ROT" "0"
					( Origin gFrontEnd )
				)
				( attribute "SEC" "1"
					( Origin gFrontEnd )
				)
				( attribute "SEC_TYPE" "0805"
					( Origin gFrontEnd )
				)
				( attribute "TOLERANCE" "10%"
					( Origin gFrontEnd )
				)
				( attribute "VALUE" "10UF"
					( Origin gFrontEnd )
				)
				( attribute "VER" "1"
					( Origin gFrontEnd )
				)
				( attribute "VOLTAGE" "16V"
					( Units "uVoltage" "V" 1.000000)
					( Origin gFrontEnd )
				)
				( attribute "XY" "(-6600,4100)"
					( Origin gFrontEnd )
				)
				( attribute "CHIPS_PART_NAME" "CAP"
					( Origin gPackager )
				)
				( attribute "CDS_PART_NAME" "CAP_0805-10UF,16V,10%,X6S,C953A"
					( Origin gPackager )
				)
				( objectStatus "C3M15" )
				( pin "a"
					( attribute "PN" "1"
						( Origin gPackager )
					)
					( objectStatus "C3M15.1" )
				)
				( pin "b"
					( attribute "PN" "2"
						( Origin gPackager )
					)
					( objectStatus "C3M15.2" )
				)
			)
			( gate "@baseboard_fab2_lib.baseboard_fab2(sch_1):page232_i261"
				( attribute "CDS_LIB" "mstr_discrete"
					( Origin gPackager )
				)
				( attribute "CDS_LOCATION" "C3M16"
					( Origin gPackager )
				)
				( attribute "CDS_SEC" "1"
					( Origin gPackager )
				)
				( attribute "LOCATION" "C3M16"
					( Origin gFrontEnd )
				)
				( attribute "MATERIAL" "X6S"
					( Origin gFrontEnd )
				)
				( attribute "PACK_TYPE" "0805"
					( Origin gFrontEnd )
				)
				( attribute "PART_NUMBER" "C95333-007"
					( Origin gFrontEnd )
				)
				( attribute "PHYS_PAGE" "232"
					( Origin gFrontEnd )
				)
				( attribute "ROT" "0"
					( Origin gFrontEnd )
				)
				( attribute "SEC" "1"
					( Origin gFrontEnd )
				)
				( attribute "SEC_TYPE" "0805"
					( Origin gFrontEnd )
				)
				( attribute "TOLERANCE" "10%"
					( Origin gFrontEnd )
				)
				( attribute "VALUE" "10UF"
					( Origin gFrontEnd )
				)
				( attribute "VER" "1"
					( Origin gFrontEnd )
				)
				( attribute "VOLTAGE" "16V"
					( Units "uVoltage" "V" 1.000000)
					( Origin gFrontEnd )
				)
				( attribute "XY" "(-6225,4100)"
					( Origin gFrontEnd )
				)
				( attribute "CHIPS_PART_NAME" "CAP"
					( Origin gPackager )
				)
				( attribute "CDS_PART_NAME" "CAP_0805-10UF,16V,10%,X6S,C953A"
					( Origin gPackager )
				)
				( objectStatus "C3M16" )
				( pin "a"
					( attribute "PN" "1"
						( Origin gPackager )
					)
					( objectStatus "C3M16.1" )
				)
				( pin "b"
					( attribute "PN" "2"
						( Origin gPackager )
					)
					( objectStatus "C3M16.2" )
				)
			)
			( gate "@baseboard_fab2_lib.baseboard_fab2(sch_1):page232_i262"
				( attribute "CDS_LIB" "mstr_discrete"
					( Origin gPackager )
				)
				( attribute "CDS_LOCATION" "C7B5"
					( Origin gPackager )
				)
				( attribute "CDS_SEC" "1"
					( Origin gPackager )
				)
				( attribute "LOCATION" "C7B5"
					( Origin gFrontEnd )
				)
				( attribute "MATERIAL" "X6S"
					( Origin gFrontEnd )
				)
				( attribute "PACK_TYPE" "0805"
					( Origin gFrontEnd )
				)
				( attribute "PART_NUMBER" "C95333-007"
					( Origin gFrontEnd )
				)
				( attribute "PHYS_PAGE" "232"
					( Origin gFrontEnd )
				)
				( attribute "ROT" "0"
					( Origin gFrontEnd )
				)
				( attribute "SEC" "1"
					( Origin gFrontEnd )
				)
				( attribute "SEC_TYPE" "0805"
					( Origin gFrontEnd )
				)
				( attribute "TOLERANCE" "10%"
					( Origin gFrontEnd )
				)
				( attribute "VALUE" "10UF"
					( Origin gFrontEnd )
				)
				( attribute "VER" "1"
					( Origin gFrontEnd )
				)
				( attribute "VOLTAGE" "16V"
					( Units "uVoltage" "V" 1.000000)
					( Origin gFrontEnd )
				)
				( attribute "XY" "(-5850,4100)"
					( Origin gFrontEnd )
				)
				( attribute "CHIPS_PART_NAME" "CAP"
					( Origin gPackager )
				)
				( attribute "CDS_PART_NAME" "CAP_0805-10UF,16V,10%,X6S,C953A"
					( Origin gPackager )
				)
				( objectStatus "C7B5" )
				( pin "a"
					( attribute "PN" "1"
						( Origin gPackager )
					)
					( objectStatus "C7B5.1" )
				)
				( pin "b"
					( attribute "PN" "2"
						( Origin gPackager )
					)
					( objectStatus "C7B5.2" )
				)
			)
			( gate "@baseboard_fab2_lib.baseboard_fab2(sch_1):page232_i267"
				( attribute "CDS_LIB" "mstr_discrete"
					( Origin gPackager )
				)
				( attribute "CDS_LOCATION" "C4M1"
					( Origin gPackager )
				)
				( attribute "CDS_SEC" "1"
					( Origin gPackager )
				)
				( attribute "LOCATION" "C4M1"
					( Origin gFrontEnd )
				)
				( attribute "MATERIAL" "POSCAP"
					( Origin gFrontEnd )
				)
				( attribute "PACK_TYPE" "7343"
					( Origin gFrontEnd )
				)
				( attribute "PART_NUMBER" "724613-067"
					( Origin gFrontEnd )
				)
				( attribute "PHYS_PAGE" "232"
					( Origin gFrontEnd )
				)
				( attribute "ROT" "0"
					( Origin gFrontEnd )
				)
				( attribute "SEC" "1"
					( Origin gFrontEnd )
				)
				( attribute "SEC_TYPE" "7343"
					( Origin gFrontEnd )
				)
				( attribute "TOLERANCE" "20%"
					( Origin gFrontEnd )
				)
				( attribute "VALUE" "220UF"
					( Origin gFrontEnd )
				)
				( attribute "VER" "1"
					( Origin gFrontEnd )
				)
				( attribute "VOLTAGE" "4V"
					( Units "uVoltage" "V" 1.000000)
					( Origin gFrontEnd )
				)
				( attribute "XY" "(-1800,3650)"
					( Origin gFrontEnd )
				)
				( attribute "CHIPS_PART_NAME" "CAPP"
					( Origin gPackager )
				)
				( attribute "CDS_PART_NAME" "CAPP_7343-220UF,4V,20%,POSCAP,A"
					( Origin gPackager )
				)
				( objectStatus "C4M1" )
				( pin "a"
					( attribute "PN" "1"
						( Origin gPackager )
					)
					( objectStatus "C4M1.1" )
				)
				( pin "b"
					( attribute "PN" "2"
						( Origin gPackager )
					)
					( objectStatus "C4M1.2" )
				)
			)
			( gate "@baseboard_fab2_lib.baseboard_fab2(sch_1):page232_i298"
				( attribute "BOM_COST" "PVPP_KLM_VR"
					( Origin gFrontEnd )
				)
				( attribute "CDS_LIB" "mstr_discrete"
					( Origin gPackager )
				)
				( attribute "CDS_LOCATION" "R7B18"
					( Origin gPackager )
				)
				( attribute "CDS_SEC" "1"
					( Origin gPackager )
				)
				( attribute "LOCATION" "R7B18"
					( Origin gFrontEnd )
				)
				( attribute "MATERIAL" "CHIP"
					( Origin gFrontEnd )
				)
				( attribute "PACK_TYPE" "0402"
					( Origin gFrontEnd )
				)
				( attribute "PART_NUMBER" "G85996-004"
					( Origin gFrontEnd )
				)
				( attribute "PHYS_PAGE" "232"
					( Origin gFrontEnd )
				)
				( attribute "REUSE_ID" "9"
					( Origin gFrontEnd )
				)
				( attribute "ROOM" "PVPP_KLM_VR"
					( Origin gFrontEnd )
				)
				( attribute "ROT" "0"
					( Origin gFrontEnd )
				)
				( attribute "SEC" "1"
					( Origin gFrontEnd )
				)
				( attribute "SEC_TYPE" "0402"
					( Origin gFrontEnd )
				)
				( attribute "SPOF" "TRUE"
					( Origin gFrontEnd )
				)
				( attribute "TOLERANCE" "0.1%"
					( Origin gFrontEnd )
				)
				( attribute "VALUE" "1.0K"
					( Origin gFrontEnd )
				)
				( attribute "VER" "2"
					( Origin gFrontEnd )
				)
				( attribute "WATTAGE" "1/16W"
					( Origin gFrontEnd )
				)
				( attribute "XY" "(-1375,2625)"
					( Origin gFrontEnd )
				)
				( attribute "CHIPS_PART_NAME" "RES"
					( Origin gPackager )
				)
				( attribute "CDS_PART_NAME" "RES_0402-1.0K,0.1%,1/16W,CHIP,A"
					( Origin gPackager )
				)
				( objectStatus "R7B18" )
				( pin "a"
					( attribute "PN" "1"
						( Origin gPackager )
					)
					( objectStatus "R7B18.1" )
				)
				( pin "b"
					( attribute "PN" "2"
						( Origin gPackager )
					)
					( objectStatus "R7B18.2" )
				)
			)
			( gate "@baseboard_fab2_lib.baseboard_fab2(sch_1):page232_i299"
				( attribute "CDS_LIB" "mstr_discrete"
					( Origin gPackager )
				)
				( attribute "CDS_LOCATION" "R7B11"
					( Origin gPackager )
				)
				( attribute "CDS_SEC" "1"
					( Origin gPackager )
				)
				( attribute "LOCATION" "R7B11"
					( Origin gFrontEnd )
				)
				( attribute "MATERIAL" "CHIP"
					( Origin gFrontEnd )
				)
				( attribute "PACK_TYPE" "0402"
					( Origin gFrontEnd )
				)
				( attribute "PART_NUMBER" "G21497-005"
					( Origin gFrontEnd )
				)
				( attribute "PHYS_PAGE" "232"
					( Origin gFrontEnd )
				)
				( attribute "ROOM" "PVPP_KLM_VR"
					( Origin gFrontEnd )
				)
				( attribute "ROT" "5"
					( Origin gFrontEnd )
				)
				( attribute "SEC" "1"
					( Origin gFrontEnd )
				)
				( attribute "SEC_TYPE" "0402"
					( Origin gFrontEnd )
				)
				( attribute "SPOF" "TRUE"
					( Origin gFrontEnd )
				)
				( attribute "TOLERANCE" "5%"
					( Origin gFrontEnd )
				)
				( attribute "VALUE" "0.0"
					( Origin gFrontEnd )
				)
				( attribute "VER" "1"
					( Origin gFrontEnd )
				)
				( attribute "WATTAGE" "1/16W"
					( Origin gFrontEnd )
				)
				( attribute "XY" "(-1700,2925)"
					( Origin gFrontEnd )
				)
				( attribute "CHIPS_PART_NAME" "RES"
					( Origin gPackager )
				)
				( attribute "CDS_PART_NAME" "RES_0402-0.0,5%,1/16W,CHIP,G21A"
					( Origin gPackager )
				)
				( objectStatus "R7B11" )
				( pin "a"
					( attribute "PN" "1"
						( Origin gPackager )
					)
					( objectStatus "R7B11.1" )
				)
				( pin "b"
					( attribute "PN" "2"
						( Origin gPackager )
					)
					( objectStatus "R7B11.2" )
				)
			)
			( gate "@baseboard_fab2_lib.baseboard_fab2(sch_1):page232_i300"
				( attribute "BOM_COST" "PVPP_KLM_VR"
					( Origin gFrontEnd )
				)
				( attribute "CDS_LIB" "mstr_discrete"
					( Origin gPackager )
				)
				( attribute "CDS_LOCATION" "R7B16"
					( Origin gPackager )
				)
				( attribute "CDS_SEC" "1"
					( Origin gPackager )
				)
				( attribute "LOCATION" "R7B16"
					( Origin gFrontEnd )
				)
				( attribute "MATERIAL" "CHIP"
					( Origin gFrontEnd )
				)
				( attribute "PACK_TYPE" "0402"
					( Origin gFrontEnd )
				)
				( attribute "PART_NUMBER" "G21796-242"
					( Origin gFrontEnd )
				)
				( attribute "PHYS_PAGE" "232"
					( Origin gFrontEnd )
				)
				( attribute "REUSE_ID" "13"
					( Origin gFrontEnd )
				)
				( attribute "ROOM" "PVPP_KLM_VR"
					( Origin gFrontEnd )
				)
				( attribute "ROT" "0"
					( Origin gFrontEnd )
				)
				( attribute "SEC" "1"
					( Origin gFrontEnd )
				)
				( attribute "SEC_TYPE" "0402"
					( Origin gFrontEnd )
				)
				( attribute "TOLERANCE" "1.0%"
					( Origin gFrontEnd )
				)
				( attribute "VALUE" "7.87K"
					( Origin gFrontEnd )
				)
				( attribute "VER" "1"
					( Origin gFrontEnd )
				)
				( attribute "WATTAGE" "1/16W"
					( Origin gFrontEnd )
				)
				( attribute "XY" "(-2500,2450)"
					( Origin gFrontEnd )
				)
				( attribute "CHIPS_PART_NAME" "RES"
					( Origin gPackager )
				)
				( attribute "CDS_PART_NAME" "RES_0402-7.87K,1.0%,1/16W,CHIPA"
					( Origin gPackager )
				)
				( objectStatus "R7B16" )
				( pin "a"
					( attribute "PN" "1"
						( Origin gPackager )
					)
					( objectStatus "R7B16.1" )
				)
				( pin "b"
					( attribute "PN" "2"
						( Origin gPackager )
					)
					( objectStatus "R7B16.2" )
				)
			)
			( gate "@baseboard_fab2_lib.baseboard_fab2(sch_1):page232_i301"
				( attribute "BOM_COST" "PVPP_KLM_VR"
					( Origin gFrontEnd )
				)
				( attribute "CDS_LIB" "mstr_discrete"
					( Origin gPackager )
				)
				( attribute "CDS_LOCATION" "C7B10"
					( Origin gPackager )
				)
				( attribute "CDS_SEC" "1"
					( Origin gPackager )
				)
				( attribute "LOCATION" "C7B10"
					( Origin gFrontEnd )
				)
				( attribute "MATERIAL" "COG"
					( Origin gFrontEnd )
				)
				( attribute "PACK_TYPE" "0402LF"
					( Origin gFrontEnd )
				)
				( attribute "PART_NUMBER" "A36095-026"
					( Origin gFrontEnd )
				)
				( attribute "PHYS_PAGE" "232"
					( Origin gFrontEnd )
				)
				( attribute "REUSE_ID" "27"
					( Origin gFrontEnd )
				)
				( attribute "ROOM" "PVPP_KLM_VR"
					( Origin gFrontEnd )
				)
				( attribute "ROT" "2"
					( Origin gFrontEnd )
				)
				( attribute "SEC" "1"
					( Origin gFrontEnd )
				)
				( attribute "SEC_TYPE" "0402LF"
					( Origin gFrontEnd )
				)
				( attribute "TOLERANCE" "5%"
					( Origin gFrontEnd )
				)
				( attribute "VALUE" "100.0PF"
					( Origin gFrontEnd )
				)
				( attribute "VER" "2"
					( Origin gFrontEnd )
				)
				( attribute "VOLTAGE" "50V"
					( Units "uVoltage" "V" 1.000000)
					( Origin gFrontEnd )
				)
				( attribute "XY" "(-2775,2825)"
					( Origin gFrontEnd )
				)
				( attribute "CHIPS_PART_NAME" "CAP"
					( Origin gPackager )
				)
				( attribute "CDS_PART_NAME" "CAP_0402LF-100.0PF,50V,5%,COG,A"
					( Origin gPackager )
				)
				( objectStatus "C7B10" )
				( pin "a"
					( attribute "PN" "1"
						( Origin gPackager )
					)
					( objectStatus "C7B10.1" )
				)
				( pin "b"
					( attribute "PN" "2"
						( Origin gPackager )
					)
					( objectStatus "C7B10.2" )
				)
			)
			( gate "@baseboard_fab2_lib.baseboard_fab2(sch_1):page232_i302"
				( attribute "BOM_COST" "PVPP_KLM_VR"
					( Origin gFrontEnd )
				)
				( attribute "CDS_LIB" "mstr_discrete"
					( Origin gPackager )
				)
				( attribute "CDS_LOCATION" "C7B13"
					( Origin gPackager )
				)
				( attribute "CDS_SEC" "1"
					( Origin gPackager )
				)
				( attribute "LOCATION" "C7B13"
					( Origin gFrontEnd )
				)
				( attribute "MATERIAL" "X7R"
					( Origin gFrontEnd )
				)
				( attribute "PACK_TYPE" "0402LF"
					( Origin gFrontEnd )
				)
				( attribute "PART_NUMBER" "A36096-075"
					( Origin gFrontEnd )
				)
				( attribute "PHYS_PAGE" "232"
					( Origin gFrontEnd )
				)
				( attribute "REUSE_ID" "26"
					( Origin gFrontEnd )
				)
				( attribute "ROOM" "PVPP_KLM_VR"
					( Origin gFrontEnd )
				)
				( attribute "ROT" "0"
					( Origin gFrontEnd )
				)
				( attribute "SEC" "1"
					( Origin gFrontEnd )
				)
				( attribute "SEC_TYPE" "0402LF"
					( Origin gFrontEnd )
				)
				( attribute "SPOF" "TRUE"
					( Origin gFrontEnd )
				)
				( attribute "TOLERANCE" "10%"
					( Origin gFrontEnd )
				)
				( attribute "VALUE" "2200PF"
					( Origin gFrontEnd )
				)
				( attribute "VER" "1"
					( Origin gFrontEnd )
				)
				( attribute "VOLTAGE" "50V"
					( Units "uVoltage" "V" 1.000000)
					( Origin gFrontEnd )
				)
				( attribute "XY" "(-1375,2075)"
					( Origin gFrontEnd )
				)
				( attribute "CHIPS_PART_NAME" "CAP"
					( Origin gPackager )
				)
				( attribute "CDS_PART_NAME" "CAP_0402LF-2200PF,50V,10%,X7R,A"
					( Origin gPackager )
				)
				( objectStatus "C7B13" )
				( pin "a"
					( attribute "PN" "1"
						( Origin gPackager )
					)
					( objectStatus "C7B13.1" )
				)
				( pin "b"
					( attribute "PN" "2"
						( Origin gPackager )
					)
					( objectStatus "C7B13.2" )
				)
			)
			( gate "@baseboard_fab2_lib.baseboard_fab2(sch_1):page232_i303"
				( attribute "BOM_COST" "PVPP_KLM_VR"
					( Origin gFrontEnd )
				)
				( attribute "CDS_LIB" "mstr_discrete"
					( Origin gPackager )
				)
				( attribute "CDS_LOCATION" "R7B15"
					( Origin gPackager )
				)
				( attribute "CDS_SEC" "1"
					( Origin gPackager )
				)
				( attribute "LOCATION" "R7B15"
					( Origin gFrontEnd )
				)
				( attribute "MATERIAL" "CHIP"
					( Origin gFrontEnd )
				)
				( attribute "PACK_TYPE" "0402"
					( Origin gFrontEnd )
				)
				( attribute "PART_NUMBER" "G21796-040"
					( Origin gFrontEnd )
				)
				( attribute "PHYS_PAGE" "232"
					( Origin gFrontEnd )
				)
				( attribute "REUSE_ID" "9"
					( Origin gFrontEnd )
				)
				( attribute "ROOM" "PVPP_KLM_VR"
					( Origin gFrontEnd )
				)
				( attribute "ROT" "0"
					( Origin gFrontEnd )
				)
				( attribute "SEC" "1"
					( Origin gPackager )
				)
				( attribute "SPOF" "TRUE"
					( Origin gFrontEnd )
				)
				( attribute "TOLERANCE" "1%"
					( Origin gFrontEnd )
				)
				( attribute "VALUE" "20.0K"
					( Origin gFrontEnd )
				)
				( attribute "VER" "2"
					( Origin gFrontEnd )
				)
				( attribute "WATTAGE" "1/16W"
					( Origin gFrontEnd )
				)
				( attribute "XY" "(-1700,2175)"
					( Origin gFrontEnd )
				)
				( attribute "CHIPS_PART_NAME" "RES"
					( Origin gPackager )
				)
				( attribute "CDS_PART_NAME" "RES_0402-20.0K,1%,1/16W,CHIP,GA"
					( Origin gPackager )
				)
				( objectStatus "R7B15" )
				( pin "a"
					( attribute "PN" "1"
						( Origin gPackager )
					)
					( objectStatus "R7B15.1" )
				)
				( pin "b"
					( attribute "PN" "2"
						( Origin gPackager )
					)
					( objectStatus "R7B15.2" )
				)
			)
			( gate "@baseboard_fab2_lib.baseboard_fab2(sch_1):page232_i304"
				( attribute "BOM_COST" "PVPP_KLM_VR"
					( Origin gFrontEnd )
				)
				( attribute "CDS_LIB" "mstr_discrete"
					( Origin gPackager )
				)
				( attribute "CDS_LOCATION" "R7B13"
					( Origin gPackager )
				)
				( attribute "CDS_SEC" "1"
					( Origin gPackager )
				)
				( attribute "LOCATION" "R7B13"
					( Origin gFrontEnd )
				)
				( attribute "MATERIAL" "CHIP"
					( Origin gFrontEnd )
				)
				( attribute "PACK_TYPE" "0402"
					( Origin gFrontEnd )
				)
				( attribute "PART_NUMBER" "G21796-146"
					( Origin gFrontEnd )
				)
				( attribute "PHYS_PAGE" "232"
					( Origin gFrontEnd )
				)
				( attribute "REUSE_ID" "7"
					( Origin gFrontEnd )
				)
				( attribute "ROOM" "PVPP_KLM_VR"
					( Origin gFrontEnd )
				)
				( attribute "ROT" "0"
					( Origin gFrontEnd )
				)
				( attribute "SEC" "1"
					( Origin gPackager )
				)
				( attribute "SPOF" "TRUE"
					( Origin gFrontEnd )
				)
				( attribute "TOLERANCE" "1%"
					( Origin gFrontEnd )
				)
				( attribute "VALUE" "6.34K"
					( Origin gFrontEnd )
				)
				( attribute "VER" "2"
					( Origin gFrontEnd )
				)
				( attribute "WATTAGE" "1/16W"
					( Origin gFrontEnd )
				)
				( attribute "XY" "(-1700,1550)"
					( Origin gFrontEnd )
				)
				( attribute "CHIPS_PART_NAME" "RES"
					( Origin gPackager )
				)
				( attribute "CDS_PART_NAME" "RES_0402-6.34K,1%,1/16W,CHIP,GA"
					( Origin gPackager )
				)
				( objectStatus "R7B13" )
				( pin "a"
					( attribute "PN" "1"
						( Origin gPackager )
					)
					( objectStatus "R7B13.1" )
				)
				( pin "b"
					( attribute "PN" "2"
						( Origin gPackager )
					)
					( objectStatus "R7B13.2" )
				)
			)
			( gate "@baseboard_fab2_lib.baseboard_fab2(sch_1):page232_i306"
				( attribute "BOM_COST" "PVPP_KLM_VR"
					( Origin gFrontEnd )
				)
				( attribute "CDS_LIB" "mstr_discrete"
					( Origin gPackager )
				)
				( attribute "CDS_LOCATION" "C7B14"
					( Origin gPackager )
				)
				( attribute "CDS_SEC" "1"
					( Origin gPackager )
				)
				( attribute "LOCATION" "C7B14"
					( Origin gFrontEnd )
				)
				( attribute "MATERIAL" "X7R"
					( Origin gFrontEnd )
				)
				( attribute "PACK_TYPE" "0402LF"
					( Origin gFrontEnd )
				)
				( attribute "PART_NUMBER" "A36096-075"
					( Origin gFrontEnd )
				)
				( attribute "PHYS_PAGE" "232"
					( Origin gFrontEnd )
				)
				( attribute "REUSE_ID" "27"
					( Origin gFrontEnd )
				)
				( attribute "ROOM" "PVPP_KLM_VR"
					( Origin gFrontEnd )
				)
				( attribute "ROT" "2"
					( Origin gFrontEnd )
				)
				( attribute "SEC" "1"
					( Origin gFrontEnd )
				)
				( attribute "SEC_TYPE" "0402LF"
					( Origin gFrontEnd )
				)
				( attribute "TOLERANCE" "10%"
					( Origin gFrontEnd )
				)
				( attribute "VALUE" "2200PF"
					( Origin gFrontEnd )
				)
				( attribute "VER" "2"
					( Origin gFrontEnd )
				)
				( attribute "VOLTAGE" "50V"
					( Units "uVoltage" "V" 1.000000)
					( Origin gFrontEnd )
				)
				( attribute "XY" "(-3200,2450)"
					( Origin gFrontEnd )
				)
				( attribute "CHIPS_PART_NAME" "CAP"
					( Origin gPackager )
				)
				( attribute "CDS_PART_NAME" "CAP_0402LF-2200PF,50V,10%,X7R,A"
					( Origin gPackager )
				)
				( objectStatus "C7B14" )
				( pin "a"
					( attribute "PN" "1"
						( Origin gPackager )
					)
					( objectStatus "C7B14.1" )
				)
				( pin "b"
					( attribute "PN" "2"
						( Origin gPackager )
					)
					( objectStatus "C7B14.2" )
				)
			)
			( gate "@baseboard_fab2_lib.baseboard_fab2(sch_1):page232_i307"
				( attribute "CDS_LIB" "mstr_discrete"
					( Origin gPackager )
				)
				( attribute "CDS_LOCATION" "R7B9"
					( Origin gPackager )
				)
				( attribute "CDS_SEC" "1"
					( Origin gPackager )
				)
				( attribute "LOCATION" "R7B9"
					( Origin gFrontEnd )
				)
				( attribute "MATERIAL" "CHIP"
					( Origin gFrontEnd )
				)
				( attribute "PACK_TYPE" "0402"
					( Origin gFrontEnd )
				)
				( attribute "PART_NUMBER" "G21497-005"
					( Origin gFrontEnd )
				)
				( attribute "PHYS_PAGE" "232"
					( Origin gFrontEnd )
				)
				( attribute "ROOM" "PVCCIN_CPU0_VR"
					( Origin gFrontEnd )
				)
				( attribute "ROT" "0"
					( Origin gFrontEnd )
				)
				( attribute "SEC" "1"
					( Origin gFrontEnd )
				)
				( attribute "SEC_TYPE" "0402"
					( Origin gFrontEnd )
				)
				( attribute "TOLERANCE" "5%"
					( Origin gFrontEnd )
				)
				( attribute "VALUE" "0.0"
					( Origin gFrontEnd )
				)
				( attribute "VER" "1"
					( Origin gFrontEnd )
				)
				( attribute "WATTAGE" "1/16W"
					( Origin gFrontEnd )
				)
				( attribute "XY" "(-6500,2825)"
					( Origin gFrontEnd )
				)
				( attribute "CHIPS_PART_NAME" "RES"
					( Origin gPackager )
				)
				( attribute "CDS_PART_NAME" "RES_0402-0.0,5%,1/16W,CHIP,G21A"
					( Origin gPackager )
				)
				( objectStatus "R7B9" )
				( pin "a"
					( attribute "PN" "1"
						( Origin gPackager )
					)
					( objectStatus "R7B9.1" )
				)
				( pin "b"
					( attribute "PN" "2"
						( Origin gPackager )
					)
					( objectStatus "R7B9.2" )
				)
			)
			( gate "@baseboard_fab2_lib.baseboard_fab2(sch_1):page233_i109"
				( attribute "BOM_COST" "MEM_VRD_PVPP_AB"
					( Origin gFrontEnd )
				)
				( attribute "CDS_LIB" "mstr_discrete"
					( Origin gPackager )
				)
				( attribute "CDS_LOCATION" "C7U4"
					( Origin gPackager )
				)
				( attribute "CDS_SEC" "1"
					( Origin gPackager )
				)
				( attribute "LOCATION" "C7U4"
					( Origin gFrontEnd )
				)
				( attribute "MATERIAL" "X6S"
					( Origin gFrontEnd )
				)
				( attribute "PACK_TYPE" "0603LF"
					( Origin gFrontEnd )
				)
				( attribute "PART_NUMBER" "E15431-001"
					( Origin gFrontEnd )
				)
				( attribute "PHYS_PAGE" "233"
					( Origin gFrontEnd )
				)
				( attribute "ROOM" "PVPP_KLM_VR"
					( Origin gFrontEnd )
				)
				( attribute "ROT" "0"
					( Origin gFrontEnd )
				)
				( attribute "SEC" "1"
					( Origin gPackager )
				)
				( attribute "TOLERANCE" "20%"
					( Origin gFrontEnd )
				)
				( attribute "VALUE" "10UF"
					( Origin gFrontEnd )
				)
				( attribute "VER" "1"
					( Origin gFrontEnd )
				)
				( attribute "VOLTAGE" "4V"
					( Units "uVoltage" "V" 1.000000)
					( Origin gFrontEnd )
				)
				( attribute "XY" "(-8100,725)"
					( Origin gFrontEnd )
				)
				( attribute "CHIPS_PART_NAME" "CAP"
					( Origin gPackager )
				)
				( attribute "CDS_PART_NAME" "CAP_0603LF-10UF,4V,20%,X6S,E15A"
					( Origin gPackager )
				)
				( objectStatus "C7U4" )
				( pin "a"
					( attribute "PN" "1"
						( Origin gPackager )
					)
					( objectStatus "C7U4.1" )
				)
				( pin "b"
					( attribute "PN" "2"
						( Origin gPackager )
					)
					( objectStatus "C7U4.2" )
				)
			)
			( gate "@baseboard_fab2_lib.baseboard_fab2(sch_1):page233_i111"
				( attribute "BOM_COST" "MEM_VRD_PVPP_AB"
					( Origin gFrontEnd )
				)
				( attribute "CDS_LIB" "mstr_discrete"
					( Origin gPackager )
				)
				( attribute "CDS_LOCATION" "C7U5"
					( Origin gPackager )
				)
				( attribute "CDS_SEC" "1"
					( Origin gPackager )
				)
				( attribute "LOCATION" "C7U5"
					( Origin gFrontEnd )
				)
				( attribute "MATERIAL" "X6S"
					( Origin gFrontEnd )
				)
				( attribute "PACK_TYPE" "0603LF"
					( Origin gFrontEnd )
				)
				( attribute "PART_NUMBER" "E15431-001"
					( Origin gFrontEnd )
				)
				( attribute "PHYS_PAGE" "233"
					( Origin gFrontEnd )
				)
				( attribute "ROOM" "PVPP_KLM_VR"
					( Origin gFrontEnd )
				)
				( attribute "ROT" "0"
					( Origin gFrontEnd )
				)
				( attribute "SEC" "1"
					( Origin gPackager )
				)
				( attribute "TOLERANCE" "20%"
					( Origin gFrontEnd )
				)
				( attribute "VALUE" "10UF"
					( Origin gFrontEnd )
				)
				( attribute "VER" "1"
					( Origin gFrontEnd )
				)
				( attribute "VOLTAGE" "4V"
					( Units "uVoltage" "V" 1.000000)
					( Origin gFrontEnd )
				)
				( attribute "XY" "(-7850,725)"
					( Origin gFrontEnd )
				)
				( attribute "CHIPS_PART_NAME" "CAP"
					( Origin gPackager )
				)
				( attribute "CDS_PART_NAME" "CAP_0603LF-10UF,4V,20%,X6S,E15A"
					( Origin gPackager )
				)
				( objectStatus "C7U5" )
				( pin "a"
					( attribute "PN" "1"
						( Origin gPackager )
					)
					( objectStatus "C7U5.1" )
				)
				( pin "b"
					( attribute "PN" "2"
						( Origin gPackager )
					)
					( objectStatus "C7U5.2" )
				)
			)
			( gate "@baseboard_fab2_lib.baseboard_fab2(sch_1):page233_i112"
				( attribute "BOM_COST" "MEM_VRD_PVPP_AB"
					( Origin gFrontEnd )
				)
				( attribute "CDS_LIB" "mstr_discrete"
					( Origin gPackager )
				)
				( attribute "CDS_LOCATION" "C7T2"
					( Origin gPackager )
				)
				( attribute "CDS_SEC" "1"
					( Origin gPackager )
				)
				( attribute "LOCATION" "C7T2"
					( Origin gFrontEnd )
				)
				( attribute "MATERIAL" "X6S"
					( Origin gFrontEnd )
				)
				( attribute "PACK_TYPE" "0603LF"
					( Origin gFrontEnd )
				)
				( attribute "PART_NUMBER" "E15431-001"
					( Origin gFrontEnd )
				)
				( attribute "PHYS_PAGE" "233"
					( Origin gFrontEnd )
				)
				( attribute "ROOM" "PVPP_KLM_VR"
					( Origin gFrontEnd )
				)
				( attribute "ROT" "0"
					( Origin gFrontEnd )
				)
				( attribute "SEC" "1"
					( Origin gPackager )
				)
				( attribute "TOLERANCE" "20%"
					( Origin gFrontEnd )
				)
				( attribute "VALUE" "10UF"
					( Origin gFrontEnd )
				)
				( attribute "VER" "1"
					( Origin gFrontEnd )
				)
				( attribute "VOLTAGE" "4V"
					( Units "uVoltage" "V" 1.000000)
					( Origin gFrontEnd )
				)
				( attribute "XY" "(-7575,725)"
					( Origin gFrontEnd )
				)
				( attribute "CHIPS_PART_NAME" "CAP"
					( Origin gPackager )
				)
				( attribute "CDS_PART_NAME" "CAP_0603LF-10UF,4V,20%,X6S,E15A"
					( Origin gPackager )
				)
				( objectStatus "C7T2" )
				( pin "a"
					( attribute "PN" "1"
						( Origin gPackager )
					)
					( objectStatus "C7T2.1" )
				)
				( pin "b"
					( attribute "PN" "2"
						( Origin gPackager )
					)
					( objectStatus "C7T2.2" )
				)
			)
			( gate "@baseboard_fab2_lib.baseboard_fab2(sch_1):page233_i113"
				( attribute "BOM_COST" "MEM_VRD_PVPP_AB"
					( Origin gFrontEnd )
				)
				( attribute "CDS_LIB" "mstr_discrete"
					( Origin gPackager )
				)
				( attribute "CDS_LOCATION" "C7T3"
					( Origin gPackager )
				)
				( attribute "CDS_SEC" "1"
					( Origin gPackager )
				)
				( attribute "LOCATION" "C7T3"
					( Origin gFrontEnd )
				)
				( attribute "MATERIAL" "X6S"
					( Origin gFrontEnd )
				)
				( attribute "PACK_TYPE" "0603LF"
					( Origin gFrontEnd )
				)
				( attribute "PART_NUMBER" "E15431-001"
					( Origin gFrontEnd )
				)
				( attribute "PHYS_PAGE" "233"
					( Origin gFrontEnd )
				)
				( attribute "ROOM" "PVPP_KLM_VR"
					( Origin gFrontEnd )
				)
				( attribute "ROT" "0"
					( Origin gFrontEnd )
				)
				( attribute "SEC" "1"
					( Origin gPackager )
				)
				( attribute "TOLERANCE" "20%"
					( Origin gFrontEnd )
				)
				( attribute "VALUE" "10UF"
					( Origin gFrontEnd )
				)
				( attribute "VER" "1"
					( Origin gFrontEnd )
				)
				( attribute "VOLTAGE" "4V"
					( Units "uVoltage" "V" 1.000000)
					( Origin gFrontEnd )
				)
				( attribute "XY" "(-7325,700)"
					( Origin gFrontEnd )
				)
				( attribute "CHIPS_PART_NAME" "CAP"
					( Origin gPackager )
				)
				( attribute "CDS_PART_NAME" "CAP_0603LF-10UF,4V,20%,X6S,E15A"
					( Origin gPackager )
				)
				( objectStatus "C7T3" )
				( pin "a"
					( attribute "PN" "1"
						( Origin gPackager )
					)
					( objectStatus "C7T3.1" )
				)
				( pin "b"
					( attribute "PN" "2"
						( Origin gPackager )
					)
					( objectStatus "C7T3.2" )
				)
			)
			( gate "@baseboard_fab2_lib.baseboard_fab2(sch_1):page233_i115"
				( attribute "BOM_COST" "MEM_VRD_PVPP_AB"
					( Origin gFrontEnd )
				)
				( attribute "CDS_LIB" "mstr_discrete"
					( Origin gPackager )
				)
				( attribute "CDS_LOCATION" "C7U6"
					( Origin gPackager )
				)
				( attribute "CDS_SEC" "1"
					( Origin gPackager )
				)
				( attribute "LOCATION" "C7U6"
					( Origin gFrontEnd )
				)
				( attribute "MATERIAL" "X6S"
					( Origin gFrontEnd )
				)
				( attribute "PACK_TYPE" "0603LF"
					( Origin gFrontEnd )
				)
				( attribute "PART_NUMBER" "E15431-001"
					( Origin gFrontEnd )
				)
				( attribute "PHYS_PAGE" "233"
					( Origin gFrontEnd )
				)
				( attribute "ROOM" "PVPP_KLM_VR"
					( Origin gFrontEnd )
				)
				( attribute "ROT" "0"
					( Origin gFrontEnd )
				)
				( attribute "SEC" "1"
					( Origin gPackager )
				)
				( attribute "TOLERANCE" "20%"
					( Origin gFrontEnd )
				)
				( attribute "VALUE" "10UF"
					( Origin gFrontEnd )
				)
				( attribute "VER" "1"
					( Origin gFrontEnd )
				)
				( attribute "VOLTAGE" "4V"
					( Units "uVoltage" "V" 1.000000)
					( Origin gFrontEnd )
				)
				( attribute "XY" "(-7050,725)"
					( Origin gFrontEnd )
				)
				( attribute "CHIPS_PART_NAME" "CAP"
					( Origin gPackager )
				)
				( attribute "CDS_PART_NAME" "CAP_0603LF-10UF,4V,20%,X6S,E15A"
					( Origin gPackager )
				)
				( objectStatus "C7U6" )
				( pin "a"
					( attribute "PN" "1"
						( Origin gPackager )
					)
					( objectStatus "C7U6.1" )
				)
				( pin "b"
					( attribute "PN" "2"
						( Origin gPackager )
					)
					( objectStatus "C7U6.2" )
				)
			)
			( gate "@baseboard_fab2_lib.baseboard_fab2(sch_1):page233_i116"
				( attribute "BOM_COST" "MEM_VRD_PVPP_AB"
					( Origin gFrontEnd )
				)
				( attribute "CDS_LIB" "mstr_discrete"
					( Origin gPackager )
				)
				( attribute "CDS_LOCATION" "C3F3"
					( Origin gPackager )
				)
				( attribute "CDS_SEC" "1"
					( Origin gPackager )
				)
				( attribute "LOCATION" "C3F3"
					( Origin gFrontEnd )
				)
				( attribute "MATERIAL" "X6S"
					( Origin gFrontEnd )
				)
				( attribute "PACK_TYPE" "0603LF"
					( Origin gFrontEnd )
				)
				( attribute "PART_NUMBER" "E15431-001"
					( Origin gFrontEnd )
				)
				( attribute "PHYS_PAGE" "233"
					( Origin gFrontEnd )
				)
				( attribute "ROOM" "PVPP_KLM_VR"
					( Origin gFrontEnd )
				)
				( attribute "ROT" "0"
					( Origin gFrontEnd )
				)
				( attribute "SEC" "1"
					( Origin gPackager )
				)
				( attribute "TOLERANCE" "20%"
					( Origin gFrontEnd )
				)
				( attribute "VALUE" "10UF"
					( Origin gFrontEnd )
				)
				( attribute "VER" "1"
					( Origin gFrontEnd )
				)
				( attribute "VOLTAGE" "4V"
					( Units "uVoltage" "V" 1.000000)
					( Origin gFrontEnd )
				)
				( attribute "XY" "(-6750,725)"
					( Origin gFrontEnd )
				)
				( attribute "CHIPS_PART_NAME" "CAP"
					( Origin gPackager )
				)
				( attribute "CDS_PART_NAME" "CAP_0603LF-10UF,4V,20%,X6S,E15A"
					( Origin gPackager )
				)
				( objectStatus "C3F3" )
				( pin "a"
					( attribute "PN" "1"
						( Origin gPackager )
					)
					( objectStatus "C3F3.1" )
				)
				( pin "b"
					( attribute "PN" "2"
						( Origin gPackager )
					)
					( objectStatus "C3F3.2" )
				)
			)
			( gate "@baseboard_fab2_lib.baseboard_fab2(sch_1):page233_i117"
				( attribute "BOM_COST" "MEM_VRD_PVPP_AB"
					( Origin gFrontEnd )
				)
				( attribute "CDS_LIB" "mstr_discrete"
					( Origin gPackager )
				)
				( attribute "CDS_LOCATION" "C3F4"
					( Origin gPackager )
				)
				( attribute "CDS_SEC" "1"
					( Origin gPackager )
				)
				( attribute "LOCATION" "C3F4"
					( Origin gFrontEnd )
				)
				( attribute "MATERIAL" "X6S"
					( Origin gFrontEnd )
				)
				( attribute "PACK_TYPE" "0603LF"
					( Origin gFrontEnd )
				)
				( attribute "PART_NUMBER" "E15431-001"
					( Origin gFrontEnd )
				)
				( attribute "PHYS_PAGE" "233"
					( Origin gFrontEnd )
				)
				( attribute "ROOM" "PVPP_KLM_VR"
					( Origin gFrontEnd )
				)
				( attribute "ROT" "0"
					( Origin gFrontEnd )
				)
				( attribute "SEC" "1"
					( Origin gPackager )
				)
				( attribute "TOLERANCE" "20%"
					( Origin gFrontEnd )
				)
				( attribute "VALUE" "10UF"
					( Origin gFrontEnd )
				)
				( attribute "VER" "1"
					( Origin gFrontEnd )
				)
				( attribute "VOLTAGE" "4V"
					( Units "uVoltage" "V" 1.000000)
					( Origin gFrontEnd )
				)
				( attribute "XY" "(-6475,725)"
					( Origin gFrontEnd )
				)
				( attribute "CHIPS_PART_NAME" "CAP"
					( Origin gPackager )
				)
				( attribute "CDS_PART_NAME" "CAP_0603LF-10UF,4V,20%,X6S,E15A"
					( Origin gPackager )
				)
				( objectStatus "C3F4" )
				( pin "a"
					( attribute "PN" "1"
						( Origin gPackager )
					)
					( objectStatus "C3F4.1" )
				)
				( pin "b"
					( attribute "PN" "2"
						( Origin gPackager )
					)
					( objectStatus "C3F4.2" )
				)
			)
			( gate "@baseboard_fab2_lib.baseboard_fab2(sch_1):page233_i118"
				( attribute "BOM_COST" "MEM_VRD_PVPP_AB"
					( Origin gFrontEnd )
				)
				( attribute "CDS_LIB" "mstr_discrete"
					( Origin gPackager )
				)
				( attribute "CDS_LOCATION" "C3G3"
					( Origin gPackager )
				)
				( attribute "CDS_SEC" "1"
					( Origin gPackager )
				)
				( attribute "LOCATION" "C3G3"
					( Origin gFrontEnd )
				)
				( attribute "MATERIAL" "X6S"
					( Origin gFrontEnd )
				)
				( attribute "PACK_TYPE" "0603LF"
					( Origin gFrontEnd )
				)
				( attribute "PART_NUMBER" "E15431-001"
					( Origin gFrontEnd )
				)
				( attribute "PHYS_PAGE" "233"
					( Origin gFrontEnd )
				)
				( attribute "ROOM" "PVPP_KLM_VR"
					( Origin gFrontEnd )
				)
				( attribute "ROT" "0"
					( Origin gFrontEnd )
				)
				( attribute "SEC" "1"
					( Origin gPackager )
				)
				( attribute "TOLERANCE" "20%"
					( Origin gFrontEnd )
				)
				( attribute "VALUE" "10UF"
					( Origin gFrontEnd )
				)
				( attribute "VER" "1"
					( Origin gFrontEnd )
				)
				( attribute "VOLTAGE" "4V"
					( Units "uVoltage" "V" 1.000000)
					( Origin gFrontEnd )
				)
				( attribute "XY" "(-6175,725)"
					( Origin gFrontEnd )
				)
				( attribute "CHIPS_PART_NAME" "CAP"
					( Origin gPackager )
				)
				( attribute "CDS_PART_NAME" "CAP_0603LF-10UF,4V,20%,X6S,E15A"
					( Origin gPackager )
				)
				( objectStatus "C3G3" )
				( pin "a"
					( attribute "PN" "1"
						( Origin gPackager )
					)
					( objectStatus "C3G3.1" )
				)
				( pin "b"
					( attribute "PN" "2"
						( Origin gPackager )
					)
					( objectStatus "C3G3.2" )
				)
			)
			( gate "@baseboard_fab2_lib.baseboard_fab2(sch_1):page233_i132"
				( attribute "BOM_COST" "MEM_VRD_PVPP_AB"
					( Origin gFrontEnd )
				)
				( attribute "CDS_LIB" "mstr_discrete"
					( Origin gPackager )
				)
				( attribute "CDS_LOCATION" "C3G7"
					( Origin gPackager )
				)
				( attribute "CDS_SEC" "1"
					( Origin gPackager )
				)
				( attribute "LOCATION" "C3G7"
					( Origin gFrontEnd )
				)
				( attribute "MATERIAL" "X6S"
					( Origin gFrontEnd )
				)
				( attribute "PACK_TYPE" "0603LF"
					( Origin gFrontEnd )
				)
				( attribute "PART_NUMBER" "E15431-001"
					( Origin gFrontEnd )
				)
				( attribute "PHYS_PAGE" "233"
					( Origin gFrontEnd )
				)
				( attribute "ROOM" "PVPP_KLM_VR"
					( Origin gFrontEnd )
				)
				( attribute "ROT" "0"
					( Origin gFrontEnd )
				)
				( attribute "SEC" "1"
					( Origin gPackager )
				)
				( attribute "TOLERANCE" "20%"
					( Origin gFrontEnd )
				)
				( attribute "VALUE" "10UF"
					( Origin gFrontEnd )
				)
				( attribute "VER" "1"
					( Origin gFrontEnd )
				)
				( attribute "VOLTAGE" "4V"
					( Units "uVoltage" "V" 1.000000)
					( Origin gFrontEnd )
				)
				( attribute "XY" "(-5875,725)"
					( Origin gFrontEnd )
				)
				( attribute "CHIPS_PART_NAME" "CAP"
					( Origin gPackager )
				)
				( attribute "CDS_PART_NAME" "CAP_0603LF-10UF,4V,20%,X6S,E15A"
					( Origin gPackager )
				)
				( objectStatus "C3G7" )
				( pin "a"
					( attribute "PN" "1"
						( Origin gPackager )
					)
					( objectStatus "C3G7.1" )
				)
				( pin "b"
					( attribute "PN" "2"
						( Origin gPackager )
					)
					( objectStatus "C3G7.2" )
				)
			)
			( gate "@baseboard_fab2_lib.baseboard_fab2(sch_1):page233_i133"
				( attribute "BOM_COST" "MEM_VRD_PVPP_AB"
					( Origin gFrontEnd )
				)
				( attribute "CDS_LIB" "mstr_discrete"
					( Origin gPackager )
				)
				( attribute "CDS_LOCATION" "C3G4"
					( Origin gPackager )
				)
				( attribute "CDS_SEC" "1"
					( Origin gPackager )
				)
				( attribute "LOCATION" "C3G4"
					( Origin gFrontEnd )
				)
				( attribute "MATERIAL" "X6S"
					( Origin gFrontEnd )
				)
				( attribute "PACK_TYPE" "0603LF"
					( Origin gFrontEnd )
				)
				( attribute "PART_NUMBER" "E15431-001"
					( Origin gFrontEnd )
				)
				( attribute "PHYS_PAGE" "233"
					( Origin gFrontEnd )
				)
				( attribute "ROOM" "PVPP_KLM_VR"
					( Origin gFrontEnd )
				)
				( attribute "ROT" "0"
					( Origin gFrontEnd )
				)
				( attribute "SEC" "1"
					( Origin gPackager )
				)
				( attribute "TOLERANCE" "20%"
					( Origin gFrontEnd )
				)
				( attribute "VALUE" "10UF"
					( Origin gFrontEnd )
				)
				( attribute "VER" "1"
					( Origin gFrontEnd )
				)
				( attribute "VOLTAGE" "4V"
					( Units "uVoltage" "V" 1.000000)
					( Origin gFrontEnd )
				)
				( attribute "XY" "(-5600,700)"
					( Origin gFrontEnd )
				)
				( attribute "CHIPS_PART_NAME" "CAP"
					( Origin gPackager )
				)
				( attribute "CDS_PART_NAME" "CAP_0603LF-10UF,4V,20%,X6S,E15A"
					( Origin gPackager )
				)
				( objectStatus "C3G4" )
				( pin "a"
					( attribute "PN" "1"
						( Origin gPackager )
					)
					( objectStatus "C3G4.1" )
				)
				( pin "b"
					( attribute "PN" "2"
						( Origin gPackager )
					)
					( objectStatus "C3G4.2" )
				)
			)
			( gate "@baseboard_fab2_lib.baseboard_fab2(sch_1):page233_i135"
				( attribute "BOM_COST" "MEM_VRD_PVPP_AB"
					( Origin gFrontEnd )
				)
				( attribute "CDS_LIB" "mstr_discrete"
					( Origin gPackager )
				)
				( attribute "CDS_LOCATION" "C3G8"
					( Origin gPackager )
				)
				( attribute "CDS_SEC" "1"
					( Origin gPackager )
				)
				( attribute "LOCATION" "C3G8"
					( Origin gFrontEnd )
				)
				( attribute "MATERIAL" "X6S"
					( Origin gFrontEnd )
				)
				( attribute "PACK_TYPE" "0603LF"
					( Origin gFrontEnd )
				)
				( attribute "PART_NUMBER" "E15431-001"
					( Origin gFrontEnd )
				)
				( attribute "PHYS_PAGE" "233"
					( Origin gFrontEnd )
				)
				( attribute "ROOM" "PVPP_KLM_VR"
					( Origin gFrontEnd )
				)
				( attribute "ROT" "0"
					( Origin gFrontEnd )
				)
				( attribute "SEC" "1"
					( Origin gPackager )
				)
				( attribute "TOLERANCE" "20%"
					( Origin gFrontEnd )
				)
				( attribute "VALUE" "10UF"
					( Origin gFrontEnd )
				)
				( attribute "VER" "1"
					( Origin gFrontEnd )
				)
				( attribute "VOLTAGE" "4V"
					( Units "uVoltage" "V" 1.000000)
					( Origin gFrontEnd )
				)
				( attribute "XY" "(-5325,700)"
					( Origin gFrontEnd )
				)
				( attribute "CHIPS_PART_NAME" "CAP"
					( Origin gPackager )
				)
				( attribute "CDS_PART_NAME" "CAP_0603LF-10UF,4V,20%,X6S,E15A"
					( Origin gPackager )
				)
				( objectStatus "C3G8" )
				( pin "a"
					( attribute "PN" "1"
						( Origin gPackager )
					)
					( objectStatus "C3G8.1" )
				)
				( pin "b"
					( attribute "PN" "2"
						( Origin gPackager )
					)
					( objectStatus "C3G8.2" )
				)
			)
			( gate "@baseboard_fab2_lib.baseboard_fab2(sch_1):page233_i136"
				( attribute "BOM_COST" "MEM_VRD_PVPP_AB"
					( Origin gFrontEnd )
				)
				( attribute "CDS_LIB" "mstr_discrete"
					( Origin gPackager )
				)
				( attribute "CDS_LOCATION" "C7U3"
					( Origin gPackager )
				)
				( attribute "CDS_SEC" "1"
					( Origin gPackager )
				)
				( attribute "LOCATION" "C7U3"
					( Origin gFrontEnd )
				)
				( attribute "MATERIAL" "X6S"
					( Origin gFrontEnd )
				)
				( attribute "PACK_TYPE" "0603LF"
					( Origin gFrontEnd )
				)
				( attribute "PART_NUMBER" "E15431-001"
					( Origin gFrontEnd )
				)
				( attribute "PHYS_PAGE" "233"
					( Origin gFrontEnd )
				)
				( attribute "ROOM" "PVPP_KLM_VR"
					( Origin gFrontEnd )
				)
				( attribute "ROT" "0"
					( Origin gFrontEnd )
				)
				( attribute "SEC" "1"
					( Origin gFrontEnd )
				)
				( attribute "SEC_TYPE" "0603LF"
					( Origin gFrontEnd )
				)
				( attribute "TOLERANCE" "20%"
					( Origin gFrontEnd )
				)
				( attribute "VALUE" "10UF"
					( Origin gFrontEnd )
				)
				( attribute "VER" "1"
					( Origin gFrontEnd )
				)
				( attribute "VOLTAGE" "4V"
					( Units "uVoltage" "V" 1.000000)
					( Origin gFrontEnd )
				)
				( attribute "XY" "(-5075,725)"
					( Origin gFrontEnd )
				)
				( attribute "CHIPS_PART_NAME" "CAP"
					( Origin gPackager )
				)
				( attribute "CDS_PART_NAME" "CAP_0603LF-10UF,4V,20%,X6S,E15A"
					( Origin gPackager )
				)
				( objectStatus "C7U3" )
				( pin "a"
					( attribute "PN" "1"
						( Origin gPackager )
					)
					( objectStatus "C7U3.1" )
				)
				( pin "b"
					( attribute "PN" "2"
						( Origin gPackager )
					)
					( objectStatus "C7U3.2" )
				)
			)
			( gate "@baseboard_fab2_lib.baseboard_fab2(sch_1):page233_i157"
				( attribute "CDS_LIB" "mstr_discrete"
					( Origin gPackager )
				)
				( attribute "CDS_LOCATION" "R4G25"
					( Origin gPackager )
				)
				( attribute "CDS_SEC" "1"
					( Origin gPackager )
				)
				( attribute "LOCATION" "R4G25"
					( Origin gFrontEnd )
				)
				( attribute "MATERIAL" "CHIP"
					( Origin gFrontEnd )
				)
				( attribute "PACK_TYPE" "0402"
					( Origin gFrontEnd )
				)
				( attribute "PART_NUMBER" "G21497-005"
					( Origin gFrontEnd )
				)
				( attribute "PHYS_PAGE" "233"
					( Origin gFrontEnd )
				)
				( attribute "ROOM" "PVPP_KLM_VR"
					( Origin gFrontEnd )
				)
				( attribute "ROT" "0"
					( Origin gFrontEnd )
				)
				( attribute "SEC" "1"
					( Origin gPackager )
				)
				( attribute "TOLERANCE" "5%"
					( Origin gFrontEnd )
				)
				( attribute "VALUE" "0.0"
					( Origin gFrontEnd )
				)
				( attribute "VER" "1"
					( Origin gFrontEnd )
				)
				( attribute "WATTAGE" "1/16W"
					( Origin gFrontEnd )
				)
				( attribute "XY" "(-1100,550)"
					( Origin gFrontEnd )
				)
				( attribute "CHIPS_PART_NAME" "RES"
					( Origin gPackager )
				)
				( attribute "CDS_PART_NAME" "RES_0402-0.0,5%,1/16W,CHIP,G21A"
					( Origin gPackager )
				)
				( objectStatus "R4G25" )
				( pin "a"
					( attribute "PN" "1"
						( Origin gPackager )
					)
					( objectStatus "R4G25.1" )
				)
				( pin "b"
					( attribute "PN" "2"
						( Origin gPackager )
					)
					( objectStatus "R4G25.2" )
				)
			)
			( gate "@baseboard_fab2_lib.baseboard_fab2(sch_1):page233_i182"
				( attribute "BOM" "SYSB_CPLD"
					( Origin gFrontEnd )
				)
				( attribute "BOM_COST" "PVPP_KLM_VR"
					( Origin gFrontEnd )
				)
				( attribute "CDS_LIB" "mstr_discrete"
					( Origin gPackager )
				)
				( attribute "CDS_LOCATION" "R4G5"
					( Origin gPackager )
				)
				( attribute "CDS_SEC" "1"
					( Origin gPackager )
				)
				( attribute "LOCATION" "R4G5"
					( Origin gFrontEnd )
				)
				( attribute "MATERIAL" "CHIP"
					( Origin gFrontEnd )
				)
				( attribute "PACK_TYPE" "0402"
					( Origin gFrontEnd )
				)
				( attribute "PART_NUMBER" "G21796-016"
					( Origin gFrontEnd )
				)
				( attribute "PHYS_PAGE" "233"
					( Origin gFrontEnd )
				)
				( attribute "ROOM" "PVPP_KLM_VR"
					( Origin gFrontEnd )
				)
				( attribute "ROT" "0"
					( Origin gFrontEnd )
				)
				( attribute "SEC" "1"
					( Origin gPackager )
				)
				( attribute "TOLERANCE" "1%"
					( Origin gFrontEnd )
				)
				( attribute "VALUE" "10.0K"
					( Origin gFrontEnd )
				)
				( attribute "VER" "2"
					( Origin gFrontEnd )
				)
				( attribute "WATTAGE" "1/16W"
					( Origin gFrontEnd )
				)
				( attribute "XY" "(-7175,2125)"
					( Origin gFrontEnd )
				)
				( attribute "CHIPS_PART_NAME" "RES"
					( Origin gPackager )
				)
				( attribute "CDS_PART_NAME" "RES_0402-10.0K,1%,1/16W,CHIP,GA"
					( Origin gPackager )
				)
				( objectStatus "R4G5" )
				( pin "a"
					( attribute "PN" "1"
						( Origin gPackager )
					)
					( objectStatus "R4G5.1" )
				)
				( pin "b"
					( attribute "PN" "2"
						( Origin gPackager )
					)
					( objectStatus "R4G5.2" )
				)
			)
			( gate "@baseboard_fab2_lib.baseboard_fab2(sch_1):page233_i183"
				( attribute "BOM_COST" "PVPP_KLM_VR"
					( Origin gFrontEnd )
				)
				( attribute "CDS_LIB" "mstr_discrete"
					( Origin gPackager )
				)
				( attribute "CDS_LOCATION" "C4G7"
					( Origin gPackager )
				)
				( attribute "CDS_SEC" "1"
					( Origin gPackager )
				)
				( attribute "FIN" "VR_1P2"
					( Origin gFrontEnd )
				)
				( attribute "LOCATION" "C4G7"
					( Origin gFrontEnd )
				)
				( attribute "MATERIAL" "EMPTY"
					( Origin gFrontEnd )
				)
				( attribute "PACK_TYPE" "0402LF"
					( Origin gFrontEnd )
				)
				( attribute "PART_NUMBER" "A36096-046"
					( Origin gFrontEnd )
				)
				( attribute "PHYS_PAGE" "233"
					( Origin gFrontEnd )
				)
				( attribute "REUSE_ID" "1"
					( Origin gFrontEnd )
				)
				( attribute "ROOM" "PVPP_KLM_VR"
					( Origin gFrontEnd )
				)
				( attribute "ROT" "2"
					( Origin gFrontEnd )
				)
				( attribute "SEC" "1"
					( Origin gPackager )
				)
				( attribute "TOLERANCE" "10%"
					( Origin gFrontEnd )
				)
				( attribute "VALUE" "1000PF"
					( Origin gFrontEnd )
				)
				( attribute "VER" "1"
					( Origin gFrontEnd )
				)
				( attribute "VOLTAGE" "50V"
					( Units "uVoltage" "V" 1.000000)
					( Origin gFrontEnd )
				)
				( attribute "XY" "(-6500,2200)"
					( Origin gFrontEnd )
				)
				( attribute "CHIPS_PART_NAME" "CAP"
					( Origin gPackager )
				)
				( attribute "CDS_PART_NAME" "CAP_0402LF-1000PF,50V,10%,EMPTA"
					( Origin gPackager )
				)
				( objectStatus "C4G7" )
				( pin "a"
					( attribute "PN" "1"
						( Origin gPackager )
					)
					( objectStatus "C4G7.1" )
				)
				( pin "b"
					( attribute "PN" "2"
						( Origin gPackager )
					)
					( objectStatus "C4G7.2" )
				)
			)
			( gate "@baseboard_fab2_lib.baseboard_fab2(sch_1):page233_i184"
				( attribute "BOM_COST" "PVPP_KLM_VR"
					( Origin gFrontEnd )
				)
				( attribute "CDS_LIB" "mstr_discrete"
					( Origin gPackager )
				)
				( attribute "CDS_LOCATION" "R4G11"
					( Origin gPackager )
				)
				( attribute "CDS_SEC" "1"
					( Origin gPackager )
				)
				( attribute "LOCATION" "R4G11"
					( Origin gFrontEnd )
				)
				( attribute "MATERIAL" "CHIP"
					( Origin gFrontEnd )
				)
				( attribute "PACK_TYPE" "0402"
					( Origin gFrontEnd )
				)
				( attribute "PART_NUMBER" "G21796-242"
					( Origin gFrontEnd )
				)
				( attribute "PHYS_PAGE" "233"
					( Origin gFrontEnd )
				)
				( attribute "ROOM" "PVPP_KLM_VR"
					( Origin gFrontEnd )
				)
				( attribute "ROT" "2"
					( Origin gFrontEnd )
				)
				( attribute "SEC" "1"
					( Origin gFrontEnd )
				)
				( attribute "SEC_TYPE" "0402"
					( Origin gFrontEnd )
				)
				( attribute "TOLERANCE" "1.0%"
					( Origin gFrontEnd )
				)
				( attribute "VALUE" "7.87K"
					( Origin gFrontEnd )
				)
				( attribute "VER" "2"
					( Origin gFrontEnd )
				)
				( attribute "WATTAGE" "1/16W"
					( Origin gFrontEnd )
				)
				( attribute "XY" "(-4675,1500)"
					( Origin gFrontEnd )
				)
				( attribute "CHIPS_PART_NAME" "RES"
					( Origin gPackager )
				)
				( attribute "CDS_PART_NAME" "RES_0402-7.87K,1.0%,1/16W,CHIPA"
					( Origin gPackager )
				)
				( objectStatus "R4G11" )
				( pin "a"
					( attribute "PN" "1"
						( Origin gPackager )
					)
					( objectStatus "R4G11.1" )
				)
				( pin "b"
					( attribute "PN" "2"
						( Origin gPackager )
					)
					( objectStatus "R4G11.2" )
				)
			)
			( gate "@baseboard_fab2_lib.baseboard_fab2(sch_1):page233_i185"
				( attribute "BOM_COST" "PVPP_KLM_VR"
					( Origin gFrontEnd )
				)
				( attribute "CDS_LIB" "mstr_discrete"
					( Origin gPackager )
				)
				( attribute "CDS_LOCATION" "R4G14"
					( Origin gPackager )
				)
				( attribute "CDS_SEC" "1"
					( Origin gPackager )
				)
				( attribute "LOCATION" "R4G14"
					( Origin gFrontEnd )
				)
				( attribute "MATERIAL" "CHIP"
					( Origin gFrontEnd )
				)
				( attribute "PACK_TYPE" "0402"
					( Origin gFrontEnd )
				)
				( attribute "PART_NUMBER" "G21796-026"
					( Origin gFrontEnd )
				)
				( attribute "PHYS_PAGE" "233"
					( Origin gFrontEnd )
				)
				( attribute "REUSE_ID" "21"
					( Origin gFrontEnd )
				)
				( attribute "ROOM" "PVPP_KLM_VR"
					( Origin gFrontEnd )
				)
				( attribute "ROT" "0"
					( Origin gFrontEnd )
				)
				( attribute "SEC" "1"
					( Origin gFrontEnd )
				)
				( attribute "SEC_TYPE" "0402"
					( Origin gFrontEnd )
				)
				( attribute "TOLERANCE" "1%"
					( Origin gFrontEnd )
				)
				( attribute "VALUE" "1.00K"
					( Origin gFrontEnd )
				)
				( attribute "VER" "2"
					( Origin gFrontEnd )
				)
				( attribute "WATTAGE" "1/16W"
					( Origin gFrontEnd )
				)
				( attribute "XY" "(-4150,1100)"
					( Origin gFrontEnd )
				)
				( attribute "CHIPS_PART_NAME" "RES"
					( Origin gPackager )
				)
				( attribute "CDS_PART_NAME" "RES_0402-1.00K,1%,1/16W,CHIP,GA"
					( Origin gPackager )
				)
				( objectStatus "R4G14" )
				( pin "a"
					( attribute "PN" "1"
						( Origin gPackager )
					)
					( objectStatus "R4G14.1" )
				)
				( pin "b"
					( attribute "PN" "2"
						( Origin gPackager )
					)
					( objectStatus "R4G14.2" )
				)
			)
			( gate "@baseboard_fab2_lib.baseboard_fab2(sch_1):page233_i187"
				( attribute "BOM_COST" "PVPP_KLM_VR"
					( Origin gFrontEnd )
				)
				( attribute "CDS_LIB" "mstr_discrete"
					( Origin gPackager )
				)
				( attribute "CDS_LOCATION" "C6U6"
					( Origin gPackager )
				)
				( attribute "CDS_SEC" "1"
					( Origin gPackager )
				)
				( attribute "LOCATION" "C6U6"
					( Origin gFrontEnd )
				)
				( attribute "MATERIAL" "X6S"
					( Origin gFrontEnd )
				)
				( attribute "PACK_TYPE" "0603"
					( Origin gFrontEnd )
				)
				( attribute "PART_NUMBER" "E15431-003"
					( Origin gFrontEnd )
				)
				( attribute "PHYS_PAGE" "233"
					( Origin gFrontEnd )
				)
				( attribute "REUSE_ID" "26"
					( Origin gFrontEnd )
				)
				( attribute "ROOM" "PVPP_KLM_VR"
					( Origin gFrontEnd )
				)
				( attribute "ROT" "0"
					( Origin gFrontEnd )
				)
				( attribute "SEC" "1"
					( Origin gFrontEnd )
				)
				( attribute "SEC_TYPE" "0603"
					( Origin gFrontEnd )
				)
				( attribute "TOLERANCE" "10%"
					( Origin gFrontEnd )
				)
				( attribute "VALUE" "4.7UF"
					( Origin gFrontEnd )
				)
				( attribute "VER" "1"
					( Origin gFrontEnd )
				)
				( attribute "VOLTAGE" "6.3V"
					( Units "uVoltage" "V" 1.000000)
					( Origin gFrontEnd )
				)
				( attribute "XY" "(-5525,2250)"
					( Origin gFrontEnd )
				)
				( attribute "CHIPS_PART_NAME" "CAP"
					( Origin gPackager )
				)
				( attribute "CDS_PART_NAME" "CAP_0603-4.7UF,6.3V,10%,X6S,E1A"
					( Origin gPackager )
				)
				( objectStatus "C6U6" )
				( pin "a"
					( attribute "PN" "1"
						( Origin gPackager )
					)
					( objectStatus "C6U6.1" )
				)
				( pin "b"
					( attribute "PN" "2"
						( Origin gPackager )
					)
					( objectStatus "C6U6.2" )
				)
			)
			( gate "@baseboard_fab2_lib.baseboard_fab2(sch_1):page233_i189"
				( attribute "BOM_COST" "PVPP_KLM_VR"
					( Origin gFrontEnd )
				)
				( attribute "CDS_LIB" "mstr_discrete"
					( Origin gPackager )
				)
				( attribute "CDS_LOCATION" "C4G5"
					( Origin gPackager )
				)
				( attribute "CDS_SEC" "1"
					( Origin gPackager )
				)
				( attribute "LOCATION" "C4G5"
					( Origin gFrontEnd )
				)
				( attribute "MATERIAL" "X6S"
					( Origin gFrontEnd )
				)
				( attribute "PACK_TYPE" "1210"
					( Origin gFrontEnd )
				)
				( attribute "PART_NUMBER" "D38464-007"
					( Origin gFrontEnd )
				)
				( attribute "PHYS_PAGE" "233"
					( Origin gFrontEnd )
				)
				( attribute "ROOM" "PVPP_KLM_VR"
					( Origin gFrontEnd )
				)
				( attribute "ROT" "0"
					( Origin gFrontEnd )
				)
				( attribute "SEC" "1"
					( Origin gPackager )
				)
				( attribute "TOLERANCE" "20%"
					( Origin gFrontEnd )
				)
				( attribute "VALUE" "47UF"
					( Origin gFrontEnd )
				)
				( attribute "VER" "1"
					( Origin gFrontEnd )
				)
				( attribute "VOLTAGE" "16V"
					( Units "uVoltage" "V" 1.000000)
					( Origin gFrontEnd )
				)
				( attribute "XY" "(-7025,4000)"
					( Origin gFrontEnd )
				)
				( attribute "CHIPS_PART_NAME" "CAP"
					( Origin gPackager )
				)
				( attribute "CDS_PART_NAME" "CAP_1210-47UF,16V,20%,X6S,D384A"
					( Origin gPackager )
				)
				( objectStatus "C4G5" )
				( pin "a"
					( attribute "PN" "1"
						( Origin gPackager )
					)
					( objectStatus "C4G5.1" )
				)
				( pin "b"
					( attribute "PN" "2"
						( Origin gPackager )
					)
					( objectStatus "C4G5.2" )
				)
			)
			( gate "@baseboard_fab2_lib.baseboard_fab2(sch_1):page233_i194"
				( attribute "BOM_COST" "PVPP_KLM_VR"
					( Origin gFrontEnd )
				)
				( attribute "CDS_LIB" "mstr_discrete"
					( Origin gPackager )
				)
				( attribute "CDS_LOCATION" "C4G8"
					( Origin gPackager )
				)
				( attribute "CDS_SEC" "1"
					( Origin gPackager )
				)
				( attribute "LOCATION" "C4G8"
					( Origin gFrontEnd )
				)
				( attribute "MATERIAL" "X7R"
					( Origin gFrontEnd )
				)
				( attribute "PACK_TYPE" "0402"
					( Origin gFrontEnd )
				)
				( attribute "PART_NUMBER" "A36096-129"
					( Origin gFrontEnd )
				)
				( attribute "PHYS_PAGE" "233"
					( Origin gFrontEnd )
				)
				( attribute "REUSE_ID" "26"
					( Origin gFrontEnd )
				)
				( attribute "ROOM" "PVPP_KLM_VR"
					( Origin gFrontEnd )
				)
				( attribute "ROT" "0"
					( Origin gFrontEnd )
				)
				( attribute "SEC" "1"
					( Origin gFrontEnd )
				)
				( attribute "SEC_TYPE" "0402"
					( Origin gFrontEnd )
				)
				( attribute "TOLERANCE" "10%"
					( Origin gFrontEnd )
				)
				( attribute "VALUE" "0.027UF"
					( Origin gFrontEnd )
				)
				( attribute "VER" "1"
					( Origin gFrontEnd )
				)
				( attribute "VOLTAGE" "16V"
					( Units "uVoltage" "V" 1.000000)
					( Origin gFrontEnd )
				)
				( attribute "XY" "(-5000,2025)"
					( Origin gFrontEnd )
				)
				( attribute "CHIPS_PART_NAME" "CAP"
					( Origin gPackager )
				)
				( attribute "CDS_PART_NAME" "CAP_0402-0.027UF,16V,10%,X7R,AA"
					( Origin gPackager )
				)
				( objectStatus "C4G8" )
				( pin "a"
					( attribute "PN" "1"
						( Origin gPackager )
					)
					( objectStatus "C4G8.1" )
				)
				( pin "b"
					( attribute "PN" "2"
						( Origin gPackager )
					)
					( objectStatus "C4G8.2" )
				)
			)
			( gate "@baseboard_fab2_lib.baseboard_fab2(sch_1):page233_i196"
				( attribute "BOM_COST" "PVPP_KLM_VR"
					( Origin gFrontEnd )
				)
				( attribute "CDS_LIB" "mstr_discrete"
					( Origin gPackager )
				)
				( attribute "CDS_LOCATION" "C4G4"
					( Origin gPackager )
				)
				( attribute "CDS_SEC" "1"
					( Origin gPackager )
				)
				( attribute "FIN" "VR_1P2"
					( Origin gFrontEnd )
				)
				( attribute "LOCATION" "C4G4"
					( Origin gFrontEnd )
				)
				( attribute "MATERIAL" "X6S"
					( Origin gFrontEnd )
				)
				( attribute "PACK_TYPE" "0402"
					( Origin gFrontEnd )
				)
				( attribute "PART_NUMBER" "D97712-011"
					( Origin gFrontEnd )
				)
				( attribute "PHYS_PAGE" "233"
					( Origin gFrontEnd )
				)
				( attribute "REUSE_ID" "1"
					( Origin gFrontEnd )
				)
				( attribute "ROOM" "PVPP_KLM_VR"
					( Origin gFrontEnd )
				)
				( attribute "ROT" "0"
					( Origin gFrontEnd )
				)
				( attribute "SEC" "1"
					( Origin gPackager )
				)
				( attribute "TOLERANCE" "10%"
					( Origin gFrontEnd )
				)
				( attribute "VALUE" "1.0UF"
					( Origin gFrontEnd )
				)
				( attribute "VER" "1"
					( Origin gFrontEnd )
				)
				( attribute "VOLTAGE" "16V"
					( Units "uVoltage" "V" 1.000000)
					( Origin gFrontEnd )
				)
				( attribute "XY" "(-4875,4000)"
					( Origin gFrontEnd )
				)
				( attribute "CHIPS_PART_NAME" "CAP"
					( Origin gPackager )
				)
				( attribute "CDS_PART_NAME" "CAP_0402-1.0UF,16V,10%,X6S,D97A"
					( Origin gPackager )
				)
				( objectStatus "C4G4" )
				( pin "a"
					( attribute "PN" "1"
						( Origin gPackager )
					)
					( objectStatus "C4G4.1" )
				)
				( pin "b"
					( attribute "PN" "2"
						( Origin gPackager )
					)
					( objectStatus "C4G4.2" )
				)
			)
			( gate "@baseboard_fab2_lib.baseboard_fab2(sch_1):page233_i198"
				( attribute "CDS_LIB" "mstr_discrete"
					( Origin gPackager )
				)
				( attribute "CDS_LOCATION" "FB4G1"
					( Origin gPackager )
				)
				( attribute "CDS_SEC" "1"
					( Origin gPackager )
				)
				( attribute "LOCATION" "FB4G1"
					( Origin gFrontEnd )
				)
				( attribute "MATERIAL" "FB"
					( Origin gFrontEnd )
				)
				( attribute "PACK_TYPE" "SM"
					( Origin gFrontEnd )
				)
				( attribute "PART_NUMBER" "656554-051"
					( Origin gFrontEnd )
				)
				( attribute "PHYS_PAGE" "233"
					( Origin gFrontEnd )
				)
				( attribute "ROOM" "PVPP_KLM_VR"
					( Origin gFrontEnd )
				)
				( attribute "ROT" "0"
					( Origin gFrontEnd )
				)
				( attribute "SEC" "1"
					( Origin gFrontEnd )
				)
				( attribute "SEC_TYPE" "SM"
					( Origin gFrontEnd )
				)
				( attribute "TOLERANCE" "1%"
					( Origin gFrontEnd )
				)
				( attribute "VALUE" "22"
					( Origin gFrontEnd )
				)
				( attribute "VER" "1"
					( Origin gFrontEnd )
				)
				( attribute "XY" "(-7225,4150)"
					( Origin gFrontEnd )
				)
				( attribute "CHIPS_PART_NAME" "FERRITE"
					( Origin gPackager )
				)
				( attribute "CDS_PART_NAME" "FERRITE_SM-22,FB,656554-051"
					( Origin gPackager )
				)
				( objectStatus "FB4G1" )
				( pin "a"
					( attribute "PN" "1"
						( Origin gPackager )
					)
					( objectStatus "FB4G1.1" )
				)
				( pin "b"
					( attribute "PN" "2"
						( Origin gPackager )
					)
					( objectStatus "FB4G1.2" )
				)
			)
			( gate "@baseboard_fab2_lib.baseboard_fab2(sch_1):page233_i199"
				( attribute "BOM_COST" "PVPP_KLM_VR"
					( Origin gFrontEnd )
				)
				( attribute "CDS_LIB" "mstr_discrete"
					( Origin gPackager )
				)
				( attribute "CDS_LOCATION" "R4G24"
					( Origin gPackager )
				)
				( attribute "CDS_SEC" "1"
					( Origin gPackager )
				)
				( attribute "LOCATION" "R4G24"
					( Origin gFrontEnd )
				)
				( attribute "MATERIAL" "CHIP"
					( Origin gFrontEnd )
				)
				( attribute "PACK_TYPE" "0402"
					( Origin gFrontEnd )
				)
				( attribute "PART_NUMBER" "G21497-005"
					( Origin gFrontEnd )
				)
				( attribute "PHYS_PAGE" "233"
					( Origin gFrontEnd )
				)
				( attribute "REUSE_ID" "13"
					( Origin gFrontEnd )
				)
				( attribute "ROOM" "PVPP_KLM_VR"
					( Origin gFrontEnd )
				)
				( attribute "ROT" "0"
					( Origin gFrontEnd )
				)
				( attribute "SEC" "1"
					( Origin gPackager )
				)
				( attribute "SPOF" "TRUE"
					( Origin gFrontEnd )
				)
				( attribute "TOLERANCE" "5%"
					( Origin gFrontEnd )
				)
				( attribute "VALUE" "0.0"
					( Origin gFrontEnd )
				)
				( attribute "VER" "1"
					( Origin gFrontEnd )
				)
				( attribute "WATTAGE" "1/16W"
					( Origin gFrontEnd )
				)
				( attribute "XY" "(-4000,4050)"
					( Origin gFrontEnd )
				)
				( attribute "CHIPS_PART_NAME" "RES"
					( Origin gPackager )
				)
				( attribute "CDS_PART_NAME" "RES_0402-0.0,5%,1/16W,CHIP,G21A"
					( Origin gPackager )
				)
				( objectStatus "R4G24" )
				( pin "a"
					( attribute "PN" "1"
						( Origin gPackager )
					)
					( objectStatus "R4G24.1" )
				)
				( pin "b"
					( attribute "PN" "2"
						( Origin gPackager )
					)
					( objectStatus "R4G24.2" )
				)
			)
			( gate "@baseboard_fab2_lib.baseboard_fab2(sch_1):page233_i201"
				( attribute "BOM_COST" "PVPP_KLM_VR"
					( Origin gFrontEnd )
				)
				( attribute "CDS_LIB" "mstr_discrete"
					( Origin gPackager )
				)
				( attribute "CDS_LOCATION" "C4G9"
					( Origin gPackager )
				)
				( attribute "CDS_SEC" "1"
					( Origin gPackager )
				)
				( attribute "LOCATION" "C4G9"
					( Origin gFrontEnd )
				)
				( attribute "MATERIAL" "X7R"
					( Origin gFrontEnd )
				)
				( attribute "PACK_TYPE" "0402LF"
					( Origin gFrontEnd )
				)
				( attribute "PART_NUMBER" "A36096-046"
					( Origin gFrontEnd )
				)
				( attribute "PHYS_PAGE" "233"
					( Origin gFrontEnd )
				)
				( attribute "REUSE_ID" "17"
					( Origin gFrontEnd )
				)
				( attribute "ROOM" "PVPP_KLM_VR"
					( Origin gFrontEnd )
				)
				( attribute "ROT" "0"
					( Origin gFrontEnd )
				)
				( attribute "SEC" "1"
					( Origin gPackager )
				)
				( attribute "TOLERANCE" "10%"
					( Origin gFrontEnd )
				)
				( attribute "VALUE" "1000PF"
					( Origin gFrontEnd )
				)
				( attribute "VER" "1"
					( Origin gFrontEnd )
				)
				( attribute "VOLTAGE" "50V"
					( Units "uVoltage" "V" 1.000000)
					( Origin gFrontEnd )
				)
				( attribute "XY" "(-3800,575)"
					( Origin gFrontEnd )
				)
				( attribute "CHIPS_PART_NAME" "CAP"
					( Origin gPackager )
				)
				( attribute "CDS_PART_NAME" "CAP_0402LF-1000PF,50V,10%,X7R,A"
					( Origin gPackager )
				)
				( objectStatus "C4G9" )
				( pin "a"
					( attribute "PN" "1"
						( Origin gPackager )
					)
					( objectStatus "C4G9.1" )
				)
				( pin "b"
					( attribute "PN" "2"
						( Origin gPackager )
					)
					( objectStatus "C4G9.2" )
				)
			)
			( gate "@baseboard_fab2_lib.baseboard_fab2(sch_1):page233_i208"
				( attribute "BOM_COST" "PVPP_KLM_VR"
					( Origin gFrontEnd )
				)
				( attribute "CDS_LIB" "mstr_discrete"
					( Origin gPackager )
				)
				( attribute "CDS_LOCATION" "R4F6"
					( Origin gPackager )
				)
				( attribute "CDS_SEC" "1"
					( Origin gPackager )
				)
				( attribute "LOCATION" "R4F6"
					( Origin gFrontEnd )
				)
				( attribute "MATERIAL" "EMPTY"
					( Origin gFrontEnd )
				)
				( attribute "PACK_TYPE" "0402"
					( Origin gFrontEnd )
				)
				( attribute "PART_NUMBER" "G21497-016"
					( Origin gFrontEnd )
				)
				( attribute "PHYS_PAGE" "233"
					( Origin gFrontEnd )
				)
				( attribute "REUSE_ID" "29"
					( Origin gFrontEnd )
				)
				( attribute "ROOM" "PVPP_KLM_VR"
					( Origin gFrontEnd )
				)
				( attribute "ROT" "0"
					( Origin gFrontEnd )
				)
				( attribute "SEC" "1"
					( Origin gPackager )
				)
				( attribute "TOLERANCE" "5%"
					( Origin gFrontEnd )
				)
				( attribute "VALUE" "2.2"
					( Origin gFrontEnd )
				)
				( attribute "VER" "2"
					( Origin gFrontEnd )
				)
				( attribute "WATTAGE" "1/16W"
					( Origin gFrontEnd )
				)
				( attribute "XY" "(-2575,3200)"
					( Origin gFrontEnd )
				)
				( attribute "CHIPS_PART_NAME" "RES"
					( Origin gPackager )
				)
				( attribute "CDS_PART_NAME" "RES_0402-2.2,5%,1/16W,EMPTY,G2A"
					( Origin gPackager )
				)
				( objectStatus "R4F6" )
				( pin "a"
					( attribute "PN" "1"
						( Origin gPackager )
					)
					( objectStatus "R4F6.1" )
				)
				( pin "b"
					( attribute "PN" "2"
						( Origin gPackager )
					)
					( objectStatus "R4F6.2" )
				)
			)
			( gate "@baseboard_fab2_lib.baseboard_fab2(sch_1):page233_i209"
				( attribute "BOM_COST" "PVPP_KLM_VR"
					( Origin gFrontEnd )
				)
				( attribute "CDS_LIB" "mstr_discrete"
					( Origin gPackager )
				)
				( attribute "CDS_LOCATION" "C4F12"
					( Origin gPackager )
				)
				( attribute "CDS_SEC" "1"
					( Origin gPackager )
				)
				( attribute "LOCATION" "C4F12"
					( Origin gFrontEnd )
				)
				( attribute "MATERIAL" "EMPTY"
					( Origin gFrontEnd )
				)
				( attribute "PACK_TYPE" "0402LF"
					( Origin gFrontEnd )
				)
				( attribute "PART_NUMBER" "A36096-091"
					( Origin gFrontEnd )
				)
				( attribute "PHYS_PAGE" "233"
					( Origin gFrontEnd )
				)
				( attribute "REUSE_ID" "26"
					( Origin gFrontEnd )
				)
				( attribute "ROOM" "PVPP_KLM_VR"
					( Origin gFrontEnd )
				)
				( attribute "ROT" "0"
					( Origin gFrontEnd )
				)
				( attribute "SEC" "1"
					( Origin gPackager )
				)
				( attribute "TOLERANCE" "10%"
					( Origin gFrontEnd )
				)
				( attribute "VALUE" "3300PF"
					( Origin gFrontEnd )
				)
				( attribute "VER" "1"
					( Origin gFrontEnd )
				)
				( attribute "VOLTAGE" "50V"
					( Units "uVoltage" "V" 1.000000)
					( Origin gFrontEnd )
				)
				( attribute "XY" "(-2575,3550)"
					( Origin gFrontEnd )
				)
				( attribute "CHIPS_PART_NAME" "CAP"
					( Origin gPackager )
				)
				( attribute "CDS_PART_NAME" "CAP_0402LF-3300PF,50V,10%,EMPTA"
					( Origin gPackager )
				)
				( objectStatus "C4F12" )
				( pin "a"
					( attribute "PN" "1"
						( Origin gPackager )
					)
					( objectStatus "C4F12.1" )
				)
				( pin "b"
					( attribute "PN" "2"
						( Origin gPackager )
					)
					( objectStatus "C4F12.2" )
				)
			)
			( gate "@baseboard_fab2_lib.baseboard_fab2(sch_1):page233_i211"
				( attribute "BOM_COST" "PVPP_KLM_VR"
					( Origin gFrontEnd )
				)
				( attribute "CDS_LIB" "mstr_discrete"
					( Origin gPackager )
				)
				( attribute "CDS_LOCATION" "R4G6"
					( Origin gPackager )
				)
				( attribute "CDS_SEC" "1"
					( Origin gPackager )
				)
				( attribute "LOCATION" "R4G6"
					( Origin gFrontEnd )
				)
				( attribute "MATERIAL" "CHIP"
					( Origin gFrontEnd )
				)
				( attribute "PACK_TYPE" "0603"
					( Origin gFrontEnd )
				)
				( attribute "PART_NUMBER" "G22026-003"
					( Origin gFrontEnd )
				)
				( attribute "PHYS_PAGE" "233"
					( Origin gFrontEnd )
				)
				( attribute "REUSE_ID" "34"
					( Origin gFrontEnd )
				)
				( attribute "ROOM" "PVPP_KLM_VR"
					( Origin gFrontEnd )
				)
				( attribute "ROT" "0"
					( Origin gFrontEnd )
				)
				( attribute "SEC" "1"
					( Origin gPackager )
				)
				( attribute "TOLERANCE" "1%"
					( Origin gFrontEnd )
				)
				( attribute "VALUE" "120.0"
					( Origin gFrontEnd )
				)
				( attribute "VER" "2"
					( Origin gFrontEnd )
				)
				( attribute "WATTAGE" "1/10W"
					( Origin gFrontEnd )
				)
				( attribute "XY" "(-2000,3525)"
					( Origin gFrontEnd )
				)
				( attribute "CHIPS_PART_NAME" "RES"
					( Origin gPackager )
				)
				( attribute "CDS_PART_NAME" "RES_0603-120.0,1%,1/10W,CHIP,GA"
					( Origin gPackager )
				)
				( objectStatus "R4G6" )
				( pin "a"
					( attribute "PN" "1"
						( Origin gPackager )
					)
					( objectStatus "R4G6.1" )
				)
				( pin "b"
					( attribute "PN" "2"
						( Origin gPackager )
					)
					( objectStatus "R4G6.2" )
				)
			)
			( gate "@baseboard_fab2_lib.baseboard_fab2(sch_1):page233_i217"
				( attribute "BOM_COST" "PVPP_KLM_VR"
					( Origin gFrontEnd )
				)
				( attribute "CDS_LIB" "mstr_discrete"
					( Origin gPackager )
				)
				( attribute "CDS_LOCATION" "C4F7"
					( Origin gPackager )
				)
				( attribute "CDS_SEC" "1"
					( Origin gPackager )
				)
				( attribute "LOCATION" "C4F7"
					( Origin gFrontEnd )
				)
				( attribute "MATERIAL" "POSCAP"
					( Origin gFrontEnd )
				)
				( attribute "PACK_TYPE" "7343LF"
					( Origin gFrontEnd )
				)
				( attribute "PART_NUMBER" "724613-042"
					( Origin gFrontEnd )
				)
				( attribute "PHYS_PAGE" "233"
					( Origin gFrontEnd )
				)
				( attribute "REUSE_ID" "28"
					( Origin gFrontEnd )
				)
				( attribute "ROOM" "PVPP_KLM_VR"
					( Origin gFrontEnd )
				)
				( attribute "ROT" "0"
					( Origin gFrontEnd )
				)
				( attribute "SEC" "1"
					( Origin gPackager )
				)
				( attribute "TOLERANCE" "20%"
					( Origin gFrontEnd )
				)
				( attribute "VALUE" "330UF"
					( Origin gFrontEnd )
				)
				( attribute "VER" "1"
					( Origin gFrontEnd )
				)
				( attribute "VOLTAGE" "6.3V"
					( Units "uVoltage" "V" 1.000000)
					( Origin gFrontEnd )
				)
				( attribute "XY" "(-1675,3525)"
					( Origin gFrontEnd )
				)
				( attribute "CHIPS_PART_NAME" "CAPP"
					( Origin gPackager )
				)
				( attribute "CDS_PART_NAME" "CAPP_7343LF-330UF,6.3V,20%,POSA"
					( Origin gPackager )
				)
				( objectStatus "C4F7" )
				( pin "a"
					( attribute "PN" "1"
						( Origin gPackager )
					)
					( objectStatus "C4F7.1" )
				)
				( pin "b"
					( attribute "PN" "2"
						( Origin gPackager )
					)
					( objectStatus "C4F7.2" )
				)
			)
			( gate "@baseboard_fab2_lib.baseboard_fab2(sch_1):page233_i221"
				( attribute "BOM_COST" "PVPP_KLM_VR"
					( Origin gFrontEnd )
				)
				( attribute "CDS_LIB" "mstr_discrete"
					( Origin gPackager )
				)
				( attribute "CDS_LOCATION" "C6U3"
					( Origin gPackager )
				)
				( attribute "CDS_SEC" "1"
					( Origin gPackager )
				)
				( attribute "LOCATION" "C6U3"
					( Origin gFrontEnd )
				)
				( attribute "MATERIAL" "X6S"
					( Origin gFrontEnd )
				)
				( attribute "PACK_TYPE" "0805"
					( Origin gFrontEnd )
				)
				( attribute "PART_NUMBER" "C95333-006"
					( Origin gFrontEnd )
				)
				( attribute "PHYS_PAGE" "233"
					( Origin gFrontEnd )
				)
				( attribute "REUSE_ID" "33"
					( Origin gFrontEnd )
				)
				( attribute "ROOM" "PVPP_KLM_VR"
					( Origin gFrontEnd )
				)
				( attribute "ROT" "0"
					( Origin gFrontEnd )
				)
				( attribute "SEC" "1"
					( Origin gPackager )
				)
				( attribute "TOLERANCE" "20%"
					( Origin gFrontEnd )
				)
				( attribute "VALUE" "47UF"
					( Origin gFrontEnd )
				)
				( attribute "VER" "1"
					( Origin gFrontEnd )
				)
				( attribute "VOLTAGE" "4V"
					( Units "uVoltage" "V" 1.000000)
					( Origin gFrontEnd )
				)
				( attribute "XY" "(-1075,3525)"
					( Origin gFrontEnd )
				)
				( attribute "CHIPS_PART_NAME" "CAP"
					( Origin gPackager )
				)
				( attribute "CDS_PART_NAME" "CAP_0805-47UF,4V,20%,X6S,C9533A"
					( Origin gPackager )
				)
				( objectStatus "C6U3" )
				( pin "a"
					( attribute "PN" "1"
						( Origin gPackager )
					)
					( objectStatus "C6U3.1" )
				)
				( pin "b"
					( attribute "PN" "2"
						( Origin gPackager )
					)
					( objectStatus "C6U3.2" )
				)
			)
			( gate "@baseboard_fab2_lib.baseboard_fab2(sch_1):page233_i223"
				( attribute "BOM_COST" "PVPP_KLM_VR"
					( Origin gFrontEnd )
				)
				( attribute "CDS_LIB" "mstr_discrete"
					( Origin gPackager )
				)
				( attribute "CDS_LOCATION" "C6U2"
					( Origin gPackager )
				)
				( attribute "CDS_SEC" "1"
					( Origin gPackager )
				)
				( attribute "LOCATION" "C6U2"
					( Origin gFrontEnd )
				)
				( attribute "MATERIAL" "X6S"
					( Origin gFrontEnd )
				)
				( attribute "PACK_TYPE" "0805"
					( Origin gFrontEnd )
				)
				( attribute "PART_NUMBER" "C95333-006"
					( Origin gFrontEnd )
				)
				( attribute "PHYS_PAGE" "233"
					( Origin gFrontEnd )
				)
				( attribute "REUSE_ID" "33"
					( Origin gFrontEnd )
				)
				( attribute "ROOM" "PVPP_KLM_VR"
					( Origin gFrontEnd )
				)
				( attribute "ROT" "0"
					( Origin gFrontEnd )
				)
				( attribute "SEC" "1"
					( Origin gPackager )
				)
				( attribute "TOLERANCE" "20%"
					( Origin gFrontEnd )
				)
				( attribute "VALUE" "47UF"
					( Origin gFrontEnd )
				)
				( attribute "VER" "1"
					( Origin gFrontEnd )
				)
				( attribute "VOLTAGE" "4V"
					( Units "uVoltage" "V" 1.000000)
					( Origin gFrontEnd )
				)
				( attribute "XY" "(-775,3500)"
					( Origin gFrontEnd )
				)
				( attribute "CHIPS_PART_NAME" "CAP"
					( Origin gPackager )
				)
				( attribute "CDS_PART_NAME" "CAP_0805-47UF,4V,20%,X6S,C9533A"
					( Origin gPackager )
				)
				( objectStatus "C6U2" )
				( pin "a"
					( attribute "PN" "1"
						( Origin gPackager )
					)
					( objectStatus "C6U2.1" )
				)
				( pin "b"
					( attribute "PN" "2"
						( Origin gPackager )
					)
					( objectStatus "C6U2.2" )
				)
			)
			( gate "@baseboard_fab2_lib.baseboard_fab2(sch_1):page233_i224"
				( attribute "BOM_COST" "PVPP_KLM_VR"
					( Origin gFrontEnd )
				)
				( attribute "CDS_LIB" "mstr_discrete"
					( Origin gPackager )
				)
				( attribute "CDS_LOCATION" "C4G26"
					( Origin gPackager )
				)
				( attribute "CDS_SEC" "1"
					( Origin gPackager )
				)
				( attribute "LOCATION" "C4G26"
					( Origin gFrontEnd )
				)
				( attribute "MATERIAL" "X7R"
					( Origin gFrontEnd )
				)
				( attribute "PACK_TYPE" "0603LF"
					( Origin gFrontEnd )
				)
				( attribute "PART_NUMBER" "602433-020"
					( Origin gFrontEnd )
				)
				( attribute "PHYS_PAGE" "233"
					( Origin gFrontEnd )
				)
				( attribute "REUSE_ID" "27"
					( Origin gFrontEnd )
				)
				( attribute "ROOM" "PVPP_KLM_VR"
					( Origin gFrontEnd )
				)
				( attribute "ROT" "2"
					( Origin gFrontEnd )
				)
				( attribute "SEC" "1"
					( Origin gPackager )
				)
				( attribute "SPOF" "TRUE"
					( Origin gFrontEnd )
				)
				( attribute "TOLERANCE" "10%"
					( Origin gFrontEnd )
				)
				( attribute "VALUE" "0.1UF"
					( Origin gFrontEnd )
				)
				( attribute "VER" "2"
					( Origin gFrontEnd )
				)
				( attribute "VOLTAGE" "25V"
					( Units "uVoltage" "V" 1.000000)
					( Origin gFrontEnd )
				)
				( attribute "XY" "(-3300,4050)"
					( Origin gFrontEnd )
				)
				( attribute "CHIPS_PART_NAME" "CAP"
					( Origin gPackager )
				)
				( attribute "CDS_PART_NAME" "CAP_0603LF-0.1UF,25V,10%,X7R,6A"
					( Origin gPackager )
				)
				( objectStatus "C4G26" )
				( pin "a"
					( attribute "PN" "1"
						( Origin gPackager )
					)
					( objectStatus "C4G26.1" )
				)
				( pin "b"
					( attribute "PN" "2"
						( Origin gPackager )
					)
					( objectStatus "C4G26.2" )
				)
			)
			( gate "@baseboard_fab2_lib.baseboard_fab2(sch_1):page233_i225"
				( attribute "CDS_LIB" "mstr_vreg"
					( Origin gPackager )
				)
				( attribute "CDS_LMAN_SYM_OUTLINE" "-450,850,450,-900"
					( Origin gPackager )
				)
				( attribute "CDS_LOCATION" "EU4G1"
					( Origin gPackager )
				)
				( attribute "CDS_SEC" "1"
					( Origin gPackager )
				)
				( attribute "LOCATION" "EU4G1"
					( Origin gFrontEnd )
				)
				( attribute "MATERIAL" "IC"
					( Origin gFrontEnd )
				)
				( attribute "PACK_TYPE" "SM"
					( Origin gFrontEnd )
				)
				( attribute "PART_NUMBER" "H86355-001"
					( Origin gFrontEnd )
				)
				( attribute "PHYS_PAGE" "233"
					( Origin gFrontEnd )
				)
				( attribute "ROT" "0"
					( Origin gFrontEnd )
				)
				( attribute "SEC" "1"
					( Origin gFrontEnd )
				)
				( attribute "SEC_TYPE" "SM"
					( Origin gFrontEnd )
				)
				( attribute "VER" "1"
					( Origin gFrontEnd )
				)
				( attribute "XY" "(-3725,2725)"
					( Origin gFrontEnd )
				)
				( attribute "CHIPS_PART_NAME" "NCP3232L"
					( Origin gPackager )
				)
				( attribute "CDS_PART_NAME" "NCP3232L_SM-IC,H86355-001"
					( Origin gPackager )
				)
				( objectStatus "EU4G1" )
				( pin "agnd"
					( attribute "PN" "5"
						( Origin gPackager )
					)
					( objectStatus "EU4G1.5" )
				)
				( pin "bst"
					( attribute "PN" "36"
						( Origin gPackager )
					)
					( objectStatus "EU4G1.36" )
				)
				( pin "comp"
					( attribute "PN" "3"
						( Origin gPackager )
					)
					( objectStatus "EU4G1.3" )
				)
				( pin "en"
					( attribute "PN" "40"
						( Origin gPackager )
					)
					( objectStatus "EU4G1.40" )
				)
				( pin "fb"
					( attribute "PN" "2"
						( Origin gPackager )
					)
					( objectStatus "EU4G1.2" )
				)
				( pin "gnd"
					( attribute "PN" "41"
						( Origin gPackager )
					)
					( objectStatus "EU4G1.41" )
				)
				( pin "iset"
					( attribute "PN" "4"
						( Origin gPackager )
					)
					( objectStatus "EU4G1.4" )
				)
				( pin "ots"
					( attribute "PN" "6"
						( Origin gPackager )
					)
					( objectStatus "EU4G1.6" )
				)
				( pin "pg"
					( attribute "PN" "7"
						( Origin gPackager )
					)
					( objectStatus "EU4G1.7" )
				)
				( pin "pgnd(0)"
					( attribute "PN" "16"
						( Origin gPackager )
					)
					( objectStatus "EU4G1.16" )
				)
				( pin "pgnd(1)"
					( attribute "PN" "17"
						( Origin gPackager )
					)
					( objectStatus "EU4G1.17" )
				)
				( pin "pgnd(2)"
					( attribute "PN" "18"
						( Origin gPackager )
					)
					( objectStatus "EU4G1.18" )
				)
				( pin "pgnd(3)"
					( attribute "PN" "19"
						( Origin gPackager )
					)
					( objectStatus "EU4G1.19" )
				)
				( pin "pgnd(4)"
					( attribute "PN" "20"
						( Origin gPackager )
					)
					( objectStatus "EU4G1.20" )
				)
				( pin "pgnd(5)"
					( attribute "PN" "21"
						( Origin gPackager )
					)
					( objectStatus "EU4G1.21" )
				)
				( pin "pgnd(6)"
					( attribute "PN" "22"
						( Origin gPackager )
					)
					( objectStatus "EU4G1.22" )
				)
				( pin "pgnd(7)"
					( attribute "PN" "23"
						( Origin gPackager )
					)
					( objectStatus "EU4G1.23" )
				)
				( pin "pgnd(8)"
					( attribute "PN" "24"
						( Origin gPackager )
					)
					( objectStatus "EU4G1.24" )
				)
				( pin "pgnd(9)"
					( attribute "PN" "25"
						( Origin gPackager )
					)
					( objectStatus "EU4G1.25" )
				)
				( pin "pgnd(10)"
					( attribute "PN" "26"
						( Origin gPackager )
					)
					( objectStatus "EU4G1.26" )
				)
				( pin "pgnd(11)"
					( attribute "PN" "27"
						( Origin gPackager )
					)
					( objectStatus "EU4G1.27" )
				)
				( pin "pgnd(12)"
					( attribute "PN" "28"
						( Origin gPackager )
					)
					( objectStatus "EU4G1.28" )
				)
				( pin "pgnd(13)"
					( attribute "PN" "37"
						( Origin gPackager )
					)
					( objectStatus "EU4G1.37" )
				)
				( pin "ss"
					( attribute "PN" "1"
						( Origin gPackager )
					)
					( objectStatus "EU4G1.1" )
				)
				( pin "vb"
					( attribute "PN" "38"
						( Origin gPackager )
					)
					( objectStatus "EU4G1.38" )
				)
				( pin "vcc"
					( attribute "PN" "39"
						( Origin gPackager )
					)
					( objectStatus "EU4G1.39" )
				)
				( pin "vin(0)"
					( attribute "PN" "8"
						( Origin gPackager )
					)
					( objectStatus "EU4G1.8" )
				)
				( pin "vin(1)"
					( attribute "PN" "9"
						( Origin gPackager )
					)
					( objectStatus "EU4G1.9" )
				)
				( pin "vin(2)"
					( attribute "PN" "10"
						( Origin gPackager )
					)
					( objectStatus "EU4G1.10" )
				)
				( pin "vin(3)"
					( attribute "PN" "11"
						( Origin gPackager )
					)
					( objectStatus "EU4G1.11" )
				)
				( pin "vin(4)"
					( attribute "PN" "12"
						( Origin gPackager )
					)
					( objectStatus "EU4G1.12" )
				)
				( pin "vin(5)"
					( attribute "PN" "13"
						( Origin gPackager )
					)
					( objectStatus "EU4G1.13" )
				)
				( pin "vin(6)"
					( attribute "PN" "14"
						( Origin gPackager )
					)
					( objectStatus "EU4G1.14" )
				)
				( pin "vin(7)"
					( attribute "PN" "42"
						( Origin gPackager )
					)
					( objectStatus "EU4G1.42" )
				)
				( pin "vsw"
					( attribute "PN" "35"
						( Origin gPackager )
					)
					( objectStatus "EU4G1.35" )
				)
				( pin "vswh(0)"
					( attribute "PN" "15"
						( Origin gPackager )
					)
					( objectStatus "EU4G1.15" )
				)
				( pin "vswh(1)"
					( attribute "PN" "29"
						( Origin gPackager )
					)
					( objectStatus "EU4G1.29" )
				)
				( pin "vswh(2)"
					( attribute "PN" "30"
						( Origin gPackager )
					)
					( objectStatus "EU4G1.30" )
				)
				( pin "vswh(3)"
					( attribute "PN" "31"
						( Origin gPackager )
					)
					( objectStatus "EU4G1.31" )
				)
				( pin "vswh(4)"
					( attribute "PN" "32"
						( Origin gPackager )
					)
					( objectStatus "EU4G1.32" )
				)
				( pin "vswh(5)"
					( attribute "PN" "33"
						( Origin gPackager )
					)
					( objectStatus "EU4G1.33" )
				)
				( pin "vswh(6)"
					( attribute "PN" "34"
						( Origin gPackager )
					)
					( objectStatus "EU4G1.34" )
				)
				( pin "vswh(7)"
					( attribute "PN" "43"
						( Origin gPackager )
					)
					( objectStatus "EU4G1.43" )
				)
			)
			( gate "@baseboard_fab2_lib.baseboard_fab2(sch_1):page233_i242"
				( attribute "CDS_LIB" "dev_discrete"
					( Origin gPackager )
				)
				( attribute "CDS_LOCATION" "C6U5"
					( Origin gPackager )
				)
				( attribute "CDS_SEC" "1"
					( Origin gPackager )
				)
				( attribute "LOCATION" "C6U5"
					( Origin gFrontEnd )
				)
				( attribute "MATERIAL" "X7R"
					( Origin gFrontEnd )
				)
				( attribute "PACK_TYPE" "0402V"
					( Origin gFrontEnd )
				)
				( attribute "PART_NUMBER" "A36096-030"
					( Origin gFrontEnd )
				)
				( attribute "PHYS_PAGE" "233"
					( Origin gFrontEnd )
				)
				( attribute "ROT" "0"
					( Origin gFrontEnd )
				)
				( attribute "SEC" "1"
					( Origin gFrontEnd )
				)
				( attribute "SEC_TYPE" "0402V"
					( Origin gFrontEnd )
				)
				( attribute "TOLERANCE" "10%"
					( Origin gFrontEnd )
				)
				( attribute "VALUE" "0.1UF"
					( Origin gFrontEnd )
				)
				( attribute "VER" "1"
					( Origin gFrontEnd )
				)
				( attribute "VOLTAGE" "16V"
					( Units "uVoltage" "V" 1.000000)
					( Origin gFrontEnd )
				)
				( attribute "XY" "(-5050,3325)"
					( Origin gFrontEnd )
				)
				( attribute "CHIPS_PART_NAME" "CAP_A"
					( Origin gPackager )
				)
				( attribute "CDS_PART_NAME" "CAP_A_0402V-0.1UF,16V,10%,X7R,A"
					( Origin gPackager )
				)
				( objectStatus "C6U5" )
				( pin "a"
					( attribute "PN" "1"
						( Origin gPackager )
					)
					( objectStatus "C6U5.1" )
				)
				( pin "b"
					( attribute "PN" "2"
						( Origin gPackager )
					)
					( objectStatus "C6U5.2" )
				)
			)
			( gate "@baseboard_fab2_lib.baseboard_fab2(sch_1):page233_i247"
				( attribute "CDS_LIB" "mstr_discrete"
					( Origin gPackager )
				)
				( attribute "CDS_LOCATION" "R4G12"
					( Origin gPackager )
				)
				( attribute "CDS_SEC" "1"
					( Origin gPackager )
				)
				( attribute "LOCATION" "R4G12"
					( Origin gFrontEnd )
				)
				( attribute "MATERIAL" "CHIP"
					( Origin gFrontEnd )
				)
				( attribute "PACK_TYPE" "0402"
					( Origin gFrontEnd )
				)
				( attribute "PART_NUMBER" "G21796-250"
					( Origin gFrontEnd )
				)
				( attribute "PHYS_PAGE" "233"
					( Origin gFrontEnd )
				)
				( attribute "ROOM" "PVPP_GHJ_VR"
					( Origin gFrontEnd )
				)
				( attribute "ROT" "0"
					( Origin gFrontEnd )
				)
				( attribute "SEC" "1"
					( Origin gFrontEnd )
				)
				( attribute "SEC_TYPE" "0402"
					( Origin gFrontEnd )
				)
				( attribute "TOLERANCE" "1.0%"
					( Origin gFrontEnd )
				)
				( attribute "VALUE" "22.1"
					( Origin gFrontEnd )
				)
				( attribute "VER" "1"
					( Origin gFrontEnd )
				)
				( attribute "WATTAGE" "1/16W"
					( Origin gFrontEnd )
				)
				( attribute "XY" "(-3375,825)"
					( Origin gFrontEnd )
				)
				( attribute "CHIPS_PART_NAME" "RES"
					( Origin gPackager )
				)
				( attribute "CDS_PART_NAME" "RES_0402-22.1,1.0%,1/16W,CHIP,A"
					( Origin gPackager )
				)
				( objectStatus "R4G12" )
				( pin "a"
					( attribute "PN" "1"
						( Origin gPackager )
					)
					( objectStatus "R4G12.1" )
				)
				( pin "b"
					( attribute "PN" "2"
						( Origin gPackager )
					)
					( objectStatus "R4G12.2" )
				)
			)
			( gate "@baseboard_fab2_lib.baseboard_fab2(sch_1):page233_i248"
				( attribute "CDS_LIB" "mstr_discrete"
					( Origin gPackager )
				)
				( attribute "CDS_LOCATION" "C6U4"
					( Origin gPackager )
				)
				( attribute "CDS_SEC" "1"
					( Origin gPackager )
				)
				( attribute "LOCATION" "C6U4"
					( Origin gFrontEnd )
				)
				( attribute "MATERIAL" "X6S"
					( Origin gFrontEnd )
				)
				( attribute "PACK_TYPE" "0805"
					( Origin gFrontEnd )
				)
				( attribute "PART_NUMBER" "C95333-007"
					( Origin gFrontEnd )
				)
				( attribute "PHYS_PAGE" "233"
					( Origin gFrontEnd )
				)
				( attribute "ROT" "0"
					( Origin gFrontEnd )
				)
				( attribute "SEC" "1"
					( Origin gFrontEnd )
				)
				( attribute "SEC_TYPE" "0805"
					( Origin gFrontEnd )
				)
				( attribute "TOLERANCE" "10%"
					( Origin gFrontEnd )
				)
				( attribute "VALUE" "10UF"
					( Origin gFrontEnd )
				)
				( attribute "VER" "1"
					( Origin gFrontEnd )
				)
				( attribute "VOLTAGE" "16V"
					( Units "uVoltage" "V" 1.000000)
					( Origin gFrontEnd )
				)
				( attribute "XY" "(-6700,3975)"
					( Origin gFrontEnd )
				)
				( attribute "CHIPS_PART_NAME" "CAP"
					( Origin gPackager )
				)
				( attribute "CDS_PART_NAME" "CAP_0805-10UF,16V,10%,X6S,C953A"
					( Origin gPackager )
				)
				( objectStatus "C6U4" )
				( pin "a"
					( attribute "PN" "1"
						( Origin gPackager )
					)
					( objectStatus "C6U4.1" )
				)
				( pin "b"
					( attribute "PN" "2"
						( Origin gPackager )
					)
					( objectStatus "C6U4.2" )
				)
			)
			( gate "@baseboard_fab2_lib.baseboard_fab2(sch_1):page233_i253"
				( attribute "CDS_LIB" "mstr_discrete"
					( Origin gPackager )
				)
				( attribute "CDS_LOCATION" "C4G2"
					( Origin gPackager )
				)
				( attribute "CDS_SEC" "1"
					( Origin gPackager )
				)
				( attribute "LOCATION" "C4G2"
					( Origin gFrontEnd )
				)
				( attribute "MATERIAL" "X6S"
					( Origin gFrontEnd )
				)
				( attribute "PACK_TYPE" "0805"
					( Origin gFrontEnd )
				)
				( attribute "PART_NUMBER" "C95333-007"
					( Origin gFrontEnd )
				)
				( attribute "PHYS_PAGE" "233"
					( Origin gFrontEnd )
				)
				( attribute "ROT" "0"
					( Origin gFrontEnd )
				)
				( attribute "SEC" "1"
					( Origin gFrontEnd )
				)
				( attribute "SEC_TYPE" "0805"
					( Origin gFrontEnd )
				)
				( attribute "TOLERANCE" "10%"
					( Origin gFrontEnd )
				)
				( attribute "VALUE" "10UF"
					( Origin gFrontEnd )
				)
				( attribute "VER" "1"
					( Origin gFrontEnd )
				)
				( attribute "VOLTAGE" "16V"
					( Units "uVoltage" "V" 1.000000)
					( Origin gFrontEnd )
				)
				( attribute "XY" "(-6300,3975)"
					( Origin gFrontEnd )
				)
				( attribute "CHIPS_PART_NAME" "CAP"
					( Origin gPackager )
				)
				( attribute "CDS_PART_NAME" "CAP_0805-10UF,16V,10%,X6S,C953A"
					( Origin gPackager )
				)
				( objectStatus "C4G2" )
				( pin "a"
					( attribute "PN" "1"
						( Origin gPackager )
					)
					( objectStatus "C4G2.1" )
				)
				( pin "b"
					( attribute "PN" "2"
						( Origin gPackager )
					)
					( objectStatus "C4G2.2" )
				)
			)
			( gate "@baseboard_fab2_lib.baseboard_fab2(sch_1):page233_i254"
				( attribute "CDS_LIB" "mstr_discrete"
					( Origin gPackager )
				)
				( attribute "CDS_LOCATION" "C6U7"
					( Origin gPackager )
				)
				( attribute "CDS_SEC" "1"
					( Origin gPackager )
				)
				( attribute "LOCATION" "C6U7"
					( Origin gFrontEnd )
				)
				( attribute "MATERIAL" "X6S"
					( Origin gFrontEnd )
				)
				( attribute "PACK_TYPE" "0805"
					( Origin gFrontEnd )
				)
				( attribute "PART_NUMBER" "C95333-007"
					( Origin gFrontEnd )
				)
				( attribute "PHYS_PAGE" "233"
					( Origin gFrontEnd )
				)
				( attribute "ROT" "0"
					( Origin gFrontEnd )
				)
				( attribute "SEC" "1"
					( Origin gFrontEnd )
				)
				( attribute "SEC_TYPE" "0805"
					( Origin gFrontEnd )
				)
				( attribute "TOLERANCE" "10%"
					( Origin gFrontEnd )
				)
				( attribute "VALUE" "10UF"
					( Origin gFrontEnd )
				)
				( attribute "VER" "1"
					( Origin gFrontEnd )
				)
				( attribute "VOLTAGE" "16V"
					( Units "uVoltage" "V" 1.000000)
					( Origin gFrontEnd )
				)
				( attribute "XY" "(-5875,3975)"
					( Origin gFrontEnd )
				)
				( attribute "CHIPS_PART_NAME" "CAP"
					( Origin gPackager )
				)
				( attribute "CDS_PART_NAME" "CAP_0805-10UF,16V,10%,X6S,C953A"
					( Origin gPackager )
				)
				( objectStatus "C6U7" )
				( pin "a"
					( attribute "PN" "1"
						( Origin gPackager )
					)
					( objectStatus "C6U7.1" )
				)
				( pin "b"
					( attribute "PN" "2"
						( Origin gPackager )
					)
					( objectStatus "C6U7.2" )
				)
			)
			( gate "@baseboard_fab2_lib.baseboard_fab2(sch_1):page233_i255"
				( attribute "CDS_LIB" "mstr_discrete"
					( Origin gPackager )
				)
				( attribute "CDS_LOCATION" "C6U8"
					( Origin gPackager )
				)
				( attribute "CDS_SEC" "1"
					( Origin gPackager )
				)
				( attribute "LOCATION" "C6U8"
					( Origin gFrontEnd )
				)
				( attribute "MATERIAL" "X6S"
					( Origin gFrontEnd )
				)
				( attribute "PACK_TYPE" "0805"
					( Origin gFrontEnd )
				)
				( attribute "PART_NUMBER" "C95333-007"
					( Origin gFrontEnd )
				)
				( attribute "PHYS_PAGE" "233"
					( Origin gFrontEnd )
				)
				( attribute "ROT" "0"
					( Origin gFrontEnd )
				)
				( attribute "SEC" "1"
					( Origin gFrontEnd )
				)
				( attribute "SEC_TYPE" "0805"
					( Origin gFrontEnd )
				)
				( attribute "TOLERANCE" "10%"
					( Origin gFrontEnd )
				)
				( attribute "VALUE" "10UF"
					( Origin gFrontEnd )
				)
				( attribute "VER" "1"
					( Origin gFrontEnd )
				)
				( attribute "VOLTAGE" "16V"
					( Units "uVoltage" "V" 1.000000)
					( Origin gFrontEnd )
				)
				( attribute "XY" "(-5450,3975)"
					( Origin gFrontEnd )
				)
				( attribute "CHIPS_PART_NAME" "CAP"
					( Origin gPackager )
				)
				( attribute "CDS_PART_NAME" "CAP_0805-10UF,16V,10%,X6S,C953A"
					( Origin gPackager )
				)
				( objectStatus "C6U8" )
				( pin "a"
					( attribute "PN" "1"
						( Origin gPackager )
					)
					( objectStatus "C6U8.1" )
				)
				( pin "b"
					( attribute "PN" "2"
						( Origin gPackager )
					)
					( objectStatus "C6U8.2" )
				)
			)
			( gate "@baseboard_fab2_lib.baseboard_fab2(sch_1):page233_i256"
				( attribute "CDS_LIB" "mstr_discrete"
					( Origin gPackager )
				)
				( attribute "CDS_LOCATION" "C4F11"
					( Origin gPackager )
				)
				( attribute "CDS_SEC" "1"
					( Origin gPackager )
				)
				( attribute "LOCATION" "C4F11"
					( Origin gFrontEnd )
				)
				( attribute "MATERIAL" "POSCAP"
					( Origin gFrontEnd )
				)
				( attribute "PACK_TYPE" "7343"
					( Origin gFrontEnd )
				)
				( attribute "PART_NUMBER" "724613-067"
					( Origin gFrontEnd )
				)
				( attribute "PHYS_PAGE" "233"
					( Origin gFrontEnd )
				)
				( attribute "ROT" "0"
					( Origin gFrontEnd )
				)
				( attribute "SEC" "1"
					( Origin gFrontEnd )
				)
				( attribute "SEC_TYPE" "7343"
					( Origin gFrontEnd )
				)
				( attribute "TOLERANCE" "20%"
					( Origin gFrontEnd )
				)
				( attribute "VALUE" "220UF"
					( Origin gFrontEnd )
				)
				( attribute "VER" "1"
					( Origin gFrontEnd )
				)
				( attribute "VOLTAGE" "4V"
					( Units "uVoltage" "V" 1.000000)
					( Origin gFrontEnd )
				)
				( attribute "XY" "(-1375,3500)"
					( Origin gFrontEnd )
				)
				( attribute "CHIPS_PART_NAME" "CAPP"
					( Origin gPackager )
				)
				( attribute "CDS_PART_NAME" "CAPP_7343-220UF,4V,20%,POSCAP,A"
					( Origin gPackager )
				)
				( objectStatus "C4F11" )
				( pin "a"
					( attribute "PN" "1"
						( Origin gPackager )
					)
					( objectStatus "C4F11.1" )
				)
				( pin "b"
					( attribute "PN" "2"
						( Origin gPackager )
					)
					( objectStatus "C4F11.2" )
				)
			)
			( gate "@baseboard_fab2_lib.baseboard_fab2(sch_1):page233_i266"
				( attribute "BOM_COST" "PVPP_KLM_VR"
					( Origin gFrontEnd )
				)
				( attribute "CDS_LIB" "mstr_discrete"
					( Origin gPackager )
				)
				( attribute "CDS_LOCATION" "R4G10"
					( Origin gPackager )
				)
				( attribute "CDS_SEC" "1"
					( Origin gPackager )
				)
				( attribute "LOCATION" "R4G10"
					( Origin gFrontEnd )
				)
				( attribute "MATERIAL" "CHIP"
					( Origin gFrontEnd )
				)
				( attribute "PACK_TYPE" "0402"
					( Origin gFrontEnd )
				)
				( attribute "PART_NUMBER" "G85996-004"
					( Origin gFrontEnd )
				)
				( attribute "PHYS_PAGE" "233"
					( Origin gFrontEnd )
				)
				( attribute "REUSE_ID" "9"
					( Origin gFrontEnd )
				)
				( attribute "ROOM" "PVPP_KLM_VR"
					( Origin gFrontEnd )
				)
				( attribute "ROT" "0"
					( Origin gFrontEnd )
				)
				( attribute "SEC" "1"
					( Origin gFrontEnd )
				)
				( attribute "SEC_TYPE" "0402"
					( Origin gFrontEnd )
				)
				( attribute "SPOF" "TRUE"
					( Origin gFrontEnd )
				)
				( attribute "TOLERANCE" "0.1%"
					( Origin gFrontEnd )
				)
				( attribute "VALUE" "1.0K"
					( Origin gFrontEnd )
				)
				( attribute "VER" "2"
					( Origin gFrontEnd )
				)
				( attribute "WATTAGE" "1/16W"
					( Origin gFrontEnd )
				)
				( attribute "XY" "(-950,2475)"
					( Origin gFrontEnd )
				)
				( attribute "CHIPS_PART_NAME" "RES"
					( Origin gPackager )
				)
				( attribute "CDS_PART_NAME" "RES_0402-1.0K,0.1%,1/16W,CHIP,A"
					( Origin gPackager )
				)
				( objectStatus "R4G10" )
				( pin "a"
					( attribute "PN" "1"
						( Origin gPackager )
					)
					( objectStatus "R4G10.1" )
				)
				( pin "b"
					( attribute "PN" "2"
						( Origin gPackager )
					)
					( objectStatus "R4G10.2" )
				)
			)
			( gate "@baseboard_fab2_lib.baseboard_fab2(sch_1):page233_i267"
				( attribute "BOM_COST" "PVPP_KLM_VR"
					( Origin gFrontEnd )
				)
				( attribute "CDS_LIB" "mstr_discrete"
					( Origin gPackager )
				)
				( attribute "CDS_LOCATION" "C4G11"
					( Origin gPackager )
				)
				( attribute "CDS_SEC" "1"
					( Origin gPackager )
				)
				( attribute "LOCATION" "C4G11"
					( Origin gFrontEnd )
				)
				( attribute "MATERIAL" "X7R"
					( Origin gFrontEnd )
				)
				( attribute "PACK_TYPE" "0402LF"
					( Origin gFrontEnd )
				)
				( attribute "PART_NUMBER" "A36096-075"
					( Origin gFrontEnd )
				)
				( attribute "PHYS_PAGE" "233"
					( Origin gFrontEnd )
				)
				( attribute "REUSE_ID" "26"
					( Origin gFrontEnd )
				)
				( attribute "ROOM" "PVPP_KLM_VR"
					( Origin gFrontEnd )
				)
				( attribute "ROT" "0"
					( Origin gFrontEnd )
				)
				( attribute "SEC" "1"
					( Origin gFrontEnd )
				)
				( attribute "SEC_TYPE" "0402LF"
					( Origin gFrontEnd )
				)
				( attribute "SPOF" "TRUE"
					( Origin gFrontEnd )
				)
				( attribute "TOLERANCE" "10%"
					( Origin gFrontEnd )
				)
				( attribute "VALUE" "2200PF"
					( Origin gFrontEnd )
				)
				( attribute "VER" "1"
					( Origin gFrontEnd )
				)
				( attribute "VOLTAGE" "50V"
					( Units "uVoltage" "V" 1.000000)
					( Origin gFrontEnd )
				)
				( attribute "XY" "(-950,1925)"
					( Origin gFrontEnd )
				)
				( attribute "CHIPS_PART_NAME" "CAP"
					( Origin gPackager )
				)
				( attribute "CDS_PART_NAME" "CAP_0402LF-2200PF,50V,10%,X7R,A"
					( Origin gPackager )
				)
				( objectStatus "C4G11" )
				( pin "a"
					( attribute "PN" "1"
						( Origin gPackager )
					)
					( objectStatus "C4G11.1" )
				)
				( pin "b"
					( attribute "PN" "2"
						( Origin gPackager )
					)
					( objectStatus "C4G11.2" )
				)
			)
			( gate "@baseboard_fab2_lib.baseboard_fab2(sch_1):page233_i269"
				( attribute "BOM_COST" "PVPP_KLM_VR"
					( Origin gFrontEnd )
				)
				( attribute "CDS_LIB" "mstr_discrete"
					( Origin gPackager )
				)
				( attribute "CDS_LOCATION" "R4G9"
					( Origin gPackager )
				)
				( attribute "CDS_SEC" "1"
					( Origin gPackager )
				)
				( attribute "LOCATION" "R4G9"
					( Origin gFrontEnd )
				)
				( attribute "MATERIAL" "CHIP"
					( Origin gFrontEnd )
				)
				( attribute "PACK_TYPE" "0402"
					( Origin gFrontEnd )
				)
				( attribute "PART_NUMBER" "G21796-146"
					( Origin gFrontEnd )
				)
				( attribute "PHYS_PAGE" "233"
					( Origin gFrontEnd )
				)
				( attribute "REUSE_ID" "7"
					( Origin gFrontEnd )
				)
				( attribute "ROOM" "PVPP_KLM_VR"
					( Origin gFrontEnd )
				)
				( attribute "ROT" "0"
					( Origin gFrontEnd )
				)
				( attribute "SEC" "1"
					( Origin gPackager )
				)
				( attribute "SPOF" "TRUE"
					( Origin gFrontEnd )
				)
				( attribute "TOLERANCE" "1%"
					( Origin gFrontEnd )
				)
				( attribute "VALUE" "6.34K"
					( Origin gFrontEnd )
				)
				( attribute "VER" "2"
					( Origin gFrontEnd )
				)
				( attribute "WATTAGE" "1/16W"
					( Origin gFrontEnd )
				)
				( attribute "XY" "(-1275,1400)"
					( Origin gFrontEnd )
				)
				( attribute "CHIPS_PART_NAME" "RES"
					( Origin gPackager )
				)
				( attribute "CDS_PART_NAME" "RES_0402-6.34K,1%,1/16W,CHIP,GA"
					( Origin gPackager )
				)
				( objectStatus "R4G9" )
				( pin "a"
					( attribute "PN" "1"
						( Origin gPackager )
					)
					( objectStatus "R4G9.1" )
				)
				( pin "b"
					( attribute "PN" "2"
						( Origin gPackager )
					)
					( objectStatus "R4G9.2" )
				)
			)
			( gate "@baseboard_fab2_lib.baseboard_fab2(sch_1):page233_i270"
				( attribute "BOM_COST" "PVPP_KLM_VR"
					( Origin gFrontEnd )
				)
				( attribute "CDS_LIB" "mstr_discrete"
					( Origin gPackager )
				)
				( attribute "CDS_LOCATION" "R4G7"
					( Origin gPackager )
				)
				( attribute "CDS_SEC" "1"
					( Origin gPackager )
				)
				( attribute "LOCATION" "R4G7"
					( Origin gFrontEnd )
				)
				( attribute "MATERIAL" "CHIP"
					( Origin gFrontEnd )
				)
				( attribute "PACK_TYPE" "0402"
					( Origin gFrontEnd )
				)
				( attribute "PART_NUMBER" "G21796-040"
					( Origin gFrontEnd )
				)
				( attribute "PHYS_PAGE" "233"
					( Origin gFrontEnd )
				)
				( attribute "REUSE_ID" "9"
					( Origin gFrontEnd )
				)
				( attribute "ROOM" "PVPP_KLM_VR"
					( Origin gFrontEnd )
				)
				( attribute "ROT" "0"
					( Origin gFrontEnd )
				)
				( attribute "SEC" "1"
					( Origin gPackager )
				)
				( attribute "SPOF" "TRUE"
					( Origin gFrontEnd )
				)
				( attribute "TOLERANCE" "1%"
					( Origin gFrontEnd )
				)
				( attribute "VALUE" "20.0K"
					( Origin gFrontEnd )
				)
				( attribute "VER" "2"
					( Origin gFrontEnd )
				)
				( attribute "WATTAGE" "1/16W"
					( Origin gFrontEnd )
				)
				( attribute "XY" "(-1275,2025)"
					( Origin gFrontEnd )
				)
				( attribute "CHIPS_PART_NAME" "RES"
					( Origin gPackager )
				)
				( attribute "CDS_PART_NAME" "RES_0402-20.0K,1%,1/16W,CHIP,GA"
					( Origin gPackager )
				)
				( objectStatus "R4G7" )
				( pin "a"
					( attribute "PN" "1"
						( Origin gPackager )
					)
					( objectStatus "R4G7.1" )
				)
				( pin "b"
					( attribute "PN" "2"
						( Origin gPackager )
					)
					( objectStatus "R4G7.2" )
				)
			)
			( gate "@baseboard_fab2_lib.baseboard_fab2(sch_1):page233_i271"
				( attribute "CDS_LIB" "mstr_discrete"
					( Origin gPackager )
				)
				( attribute "CDS_LOCATION" "R4G8"
					( Origin gPackager )
				)
				( attribute "CDS_SEC" "1"
					( Origin gPackager )
				)
				( attribute "LOCATION" "R4G8"
					( Origin gFrontEnd )
				)
				( attribute "MATERIAL" "CHIP"
					( Origin gFrontEnd )
				)
				( attribute "PACK_TYPE" "0402"
					( Origin gFrontEnd )
				)
				( attribute "PART_NUMBER" "G21497-005"
					( Origin gFrontEnd )
				)
				( attribute "PHYS_PAGE" "233"
					( Origin gFrontEnd )
				)
				( attribute "ROOM" "PVPP_KLM_VR"
					( Origin gFrontEnd )
				)
				( attribute "ROT" "5"
					( Origin gFrontEnd )
				)
				( attribute "SEC" "1"
					( Origin gFrontEnd )
				)
				( attribute "SEC_TYPE" "0402"
					( Origin gFrontEnd )
				)
				( attribute "SPOF" "TRUE"
					( Origin gFrontEnd )
				)
				( attribute "TOLERANCE" "5%"
					( Origin gFrontEnd )
				)
				( attribute "VALUE" "0.0"
					( Origin gFrontEnd )
				)
				( attribute "VER" "1"
					( Origin gFrontEnd )
				)
				( attribute "WATTAGE" "1/16W"
					( Origin gFrontEnd )
				)
				( attribute "XY" "(-1275,2775)"
					( Origin gFrontEnd )
				)
				( attribute "CHIPS_PART_NAME" "RES"
					( Origin gPackager )
				)
				( attribute "CDS_PART_NAME" "RES_0402-0.0,5%,1/16W,CHIP,G21A"
					( Origin gPackager )
				)
				( objectStatus "R4G8" )
				( pin "a"
					( attribute "PN" "1"
						( Origin gPackager )
					)
					( objectStatus "R4G8.1" )
				)
				( pin "b"
					( attribute "PN" "2"
						( Origin gPackager )
					)
					( objectStatus "R4G8.2" )
				)
			)
			( gate "@baseboard_fab2_lib.baseboard_fab2(sch_1):page233_i272"
				( attribute "BOM_COST" "PVPP_KLM_VR"
					( Origin gFrontEnd )
				)
				( attribute "CDS_LIB" "mstr_discrete"
					( Origin gPackager )
				)
				( attribute "CDS_LOCATION" "R4G13"
					( Origin gPackager )
				)
				( attribute "CDS_SEC" "1"
					( Origin gPackager )
				)
				( attribute "LOCATION" "R4G13"
					( Origin gFrontEnd )
				)
				( attribute "MATERIAL" "CHIP"
					( Origin gFrontEnd )
				)
				( attribute "PACK_TYPE" "0402"
					( Origin gFrontEnd )
				)
				( attribute "PART_NUMBER" "G21796-242"
					( Origin gFrontEnd )
				)
				( attribute "PHYS_PAGE" "233"
					( Origin gFrontEnd )
				)
				( attribute "REUSE_ID" "13"
					( Origin gFrontEnd )
				)
				( attribute "ROOM" "PVPP_KLM_VR"
					( Origin gFrontEnd )
				)
				( attribute "ROT" "0"
					( Origin gFrontEnd )
				)
				( attribute "SEC" "1"
					( Origin gFrontEnd )
				)
				( attribute "SEC_TYPE" "0402"
					( Origin gFrontEnd )
				)
				( attribute "TOLERANCE" "1.0%"
					( Origin gFrontEnd )
				)
				( attribute "VALUE" "7.87K"
					( Origin gFrontEnd )
				)
				( attribute "VER" "1"
					( Origin gFrontEnd )
				)
				( attribute "WATTAGE" "1/16W"
					( Origin gFrontEnd )
				)
				( attribute "XY" "(-2075,2300)"
					( Origin gFrontEnd )
				)
				( attribute "CHIPS_PART_NAME" "RES"
					( Origin gPackager )
				)
				( attribute "CDS_PART_NAME" "RES_0402-7.87K,1.0%,1/16W,CHIPA"
					( Origin gPackager )
				)
				( objectStatus "R4G13" )
				( pin "a"
					( attribute "PN" "1"
						( Origin gPackager )
					)
					( objectStatus "R4G13.1" )
				)
				( pin "b"
					( attribute "PN" "2"
						( Origin gPackager )
					)
					( objectStatus "R4G13.2" )
				)
			)
			( gate "@baseboard_fab2_lib.baseboard_fab2(sch_1):page233_i273"
				( attribute "BOM_COST" "PVPP_KLM_VR"
					( Origin gFrontEnd )
				)
				( attribute "CDS_LIB" "mstr_discrete"
					( Origin gPackager )
				)
				( attribute "CDS_LOCATION" "C4G6"
					( Origin gPackager )
				)
				( attribute "CDS_SEC" "1"
					( Origin gPackager )
				)
				( attribute "LOCATION" "C4G6"
					( Origin gFrontEnd )
				)
				( attribute "MATERIAL" "COG"
					( Origin gFrontEnd )
				)
				( attribute "PACK_TYPE" "0402LF"
					( Origin gFrontEnd )
				)
				( attribute "PART_NUMBER" "A36095-026"
					( Origin gFrontEnd )
				)
				( attribute "PHYS_PAGE" "233"
					( Origin gFrontEnd )
				)
				( attribute "REUSE_ID" "27"
					( Origin gFrontEnd )
				)
				( attribute "ROOM" "PVPP_KLM_VR"
					( Origin gFrontEnd )
				)
				( attribute "ROT" "2"
					( Origin gFrontEnd )
				)
				( attribute "SEC" "1"
					( Origin gFrontEnd )
				)
				( attribute "SEC_TYPE" "0402LF"
					( Origin gFrontEnd )
				)
				( attribute "TOLERANCE" "5%"
					( Origin gFrontEnd )
				)
				( attribute "VALUE" "100.0PF"
					( Origin gFrontEnd )
				)
				( attribute "VER" "2"
					( Origin gFrontEnd )
				)
				( attribute "VOLTAGE" "50V"
					( Units "uVoltage" "V" 1.000000)
					( Origin gFrontEnd )
				)
				( attribute "XY" "(-2350,2675)"
					( Origin gFrontEnd )
				)
				( attribute "CHIPS_PART_NAME" "CAP"
					( Origin gPackager )
				)
				( attribute "CDS_PART_NAME" "CAP_0402LF-100.0PF,50V,5%,COG,A"
					( Origin gPackager )
				)
				( objectStatus "C4G6" )
				( pin "a"
					( attribute "PN" "1"
						( Origin gPackager )
					)
					( objectStatus "C4G6.1" )
				)
				( pin "b"
					( attribute "PN" "2"
						( Origin gPackager )
					)
					( objectStatus "C4G6.2" )
				)
			)
			( gate "@baseboard_fab2_lib.baseboard_fab2(sch_1):page233_i274"
				( attribute "BOM_COST" "PVPP_KLM_VR"
					( Origin gFrontEnd )
				)
				( attribute "CDS_LIB" "mstr_discrete"
					( Origin gPackager )
				)
				( attribute "CDS_LOCATION" "C4G10"
					( Origin gPackager )
				)
				( attribute "CDS_SEC" "1"
					( Origin gPackager )
				)
				( attribute "LOCATION" "C4G10"
					( Origin gFrontEnd )
				)
				( attribute "MATERIAL" "X7R"
					( Origin gFrontEnd )
				)
				( attribute "PACK_TYPE" "0402LF"
					( Origin gFrontEnd )
				)
				( attribute "PART_NUMBER" "A36096-075"
					( Origin gFrontEnd )
				)
				( attribute "PHYS_PAGE" "233"
					( Origin gFrontEnd )
				)
				( attribute "REUSE_ID" "27"
					( Origin gFrontEnd )
				)
				( attribute "ROOM" "PVPP_KLM_VR"
					( Origin gFrontEnd )
				)
				( attribute "ROT" "2"
					( Origin gFrontEnd )
				)
				( attribute "SEC" "1"
					( Origin gFrontEnd )
				)
				( attribute "SEC_TYPE" "0402LF"
					( Origin gFrontEnd )
				)
				( attribute "TOLERANCE" "10%"
					( Origin gFrontEnd )
				)
				( attribute "VALUE" "2200PF"
					( Origin gFrontEnd )
				)
				( attribute "VER" "2"
					( Origin gFrontEnd )
				)
				( attribute "VOLTAGE" "50V"
					( Units "uVoltage" "V" 1.000000)
					( Origin gFrontEnd )
				)
				( attribute "XY" "(-2775,2300)"
					( Origin gFrontEnd )
				)
				( attribute "CHIPS_PART_NAME" "CAP"
					( Origin gPackager )
				)
				( attribute "CDS_PART_NAME" "CAP_0402LF-2200PF,50V,10%,X7R,A"
					( Origin gPackager )
				)
				( objectStatus "C4G10" )
				( pin "a"
					( attribute "PN" "1"
						( Origin gPackager )
					)
					( objectStatus "C4G10.1" )
				)
				( pin "b"
					( attribute "PN" "2"
						( Origin gPackager )
					)
					( objectStatus "C4G10.2" )
				)
			)
			( gate "@baseboard_fab2_lib.baseboard_fab2(sch_1):page233_i275"
				( attribute "CDS_LIB" "mstr_discrete"
					( Origin gPackager )
				)
				( attribute "CDS_LOCATION" "R4G4"
					( Origin gPackager )
				)
				( attribute "CDS_SEC" "1"
					( Origin gPackager )
				)
				( attribute "LOCATION" "R4G4"
					( Origin gFrontEnd )
				)
				( attribute "MATERIAL" "CHIP"
					( Origin gFrontEnd )
				)
				( attribute "PACK_TYPE" "0402"
					( Origin gFrontEnd )
				)
				( attribute "PART_NUMBER" "G21497-005"
					( Origin gFrontEnd )
				)
				( attribute "PHYS_PAGE" "233"
					( Origin gFrontEnd )
				)
				( attribute "ROOM" "PVCCIN_CPU0_VR"
					( Origin gFrontEnd )
				)
				( attribute "ROT" "0"
					( Origin gFrontEnd )
				)
				( attribute "SEC" "1"
					( Origin gFrontEnd )
				)
				( attribute "SEC_TYPE" "0402"
					( Origin gFrontEnd )
				)
				( attribute "TOLERANCE" "5%"
					( Origin gFrontEnd )
				)
				( attribute "VALUE" "0.0"
					( Origin gFrontEnd )
				)
				( attribute "VER" "1"
					( Origin gFrontEnd )
				)
				( attribute "WATTAGE" "1/16W"
					( Origin gFrontEnd )
				)
				( attribute "XY" "(-6000,2675)"
					( Origin gFrontEnd )
				)
				( attribute "CHIPS_PART_NAME" "RES"
					( Origin gPackager )
				)
				( attribute "CDS_PART_NAME" "RES_0402-0.0,5%,1/16W,CHIP,G21A"
					( Origin gPackager )
				)
				( objectStatus "R4G4" )
				( pin "a"
					( attribute "PN" "1"
						( Origin gPackager )
					)
					( objectStatus "R4G4.1" )
				)
				( pin "b"
					( attribute "PN" "2"
						( Origin gPackager )
					)
					( objectStatus "R4G4.2" )
				)
			)
			( gate "@baseboard_fab2_lib.baseboard_fab2(sch_1):page233_i277"
				( attribute "BOM_COST" "PVPP_GHJ_VR"
					( Origin gFrontEnd )
				)
				( attribute "CDS_LIB" "mstr_discrete"
					( Origin gPackager )
				)
				( attribute "CDS_LOCATION" "L4G1"
					( Origin gPackager )
				)
				( attribute "CDS_SEC" "1"
					( Origin gPackager )
				)
				( attribute "LOCATION" "L4G1"
					( Origin gFrontEnd )
				)
				( attribute "MATERIAL" "IND"
					( Origin gFrontEnd )
				)
				( attribute "PACK_TYPE" "SM"
					( Origin gFrontEnd )
				)
				( attribute "PART_NUMBER" "E13358-018"
					( Origin gFrontEnd )
				)
				( attribute "PHYS_PAGE" "233"
					( Origin gFrontEnd )
				)
				( attribute "REUSE_ID" "30"
					( Origin gFrontEnd )
				)
				( attribute "ROOM" "PVPP_GHJ_VR"
					( Origin gFrontEnd )
				)
				( attribute "ROT" "0"
					( Origin gFrontEnd )
				)
				( attribute "SEC" "1"
					( Origin gFrontEnd )
				)
				( attribute "SEC_TYPE" "SM"
					( Origin gFrontEnd )
				)
				( attribute "TOLERANCE" "1%"
					( Origin gFrontEnd )
				)
				( attribute "VALUE" "0.47UH"
					( Origin gFrontEnd )
				)
				( attribute "VER" "1"
					( Origin gFrontEnd )
				)
				( attribute "XY" "(-2175,3700)"
					( Origin gFrontEnd )
				)
				( attribute "CHIPS_PART_NAME" "INDUCTOR"
					( Origin gPackager )
				)
				( attribute "CDS_PART_NAME" "INDUCTOR_SM-0.47UH,IND,E13358-A"
					( Origin gPackager )
				)
				( objectStatus "L4G1" )
				( pin "ina"
					( attribute "PN" "1"
						( Origin gPackager )
					)
					( objectStatus "L4G1.1" )
				)
				( pin "inb"
					( attribute "PN" "2"
						( Origin gPackager )
					)
					( objectStatus "L4G1.2" )
				)
			)
			( gate "@baseboard_fab2_lib.baseboard_fab2(sch_1):page234_i29"
				( attribute "CDS_LIB" "mstr_discrete"
					( Origin gPackager )
				)
				( attribute "CDS_LOCATION" "R4B14"
					( Origin gPackager )
				)
				( attribute "CDS_SEC" "1"
					( Origin gPackager )
				)
				( attribute "LOCATION" "R4B14"
					( Origin gFrontEnd )
				)
				( attribute "MATERIAL" "CHIP"
					( Origin gFrontEnd )
				)
				( attribute "PACK_TYPE" "0402"
					( Origin gFrontEnd )
				)
				( attribute "PART_NUMBER" "G21497-005"
					( Origin gFrontEnd )
				)
				( attribute "PHYS_PAGE" "234"
					( Origin gFrontEnd )
				)
				( attribute "ROOM" "PVPP_KLM_VR"
					( Origin gFrontEnd )
				)
				( attribute "ROT" "0"
					( Origin gFrontEnd )
				)
				( attribute "SEC" "1"
					( Origin gPackager )
				)
				( attribute "TOLERANCE" "5%"
					( Origin gFrontEnd )
				)
				( attribute "VALUE" "0.0"
					( Origin gFrontEnd )
				)
				( attribute "VER" "1"
					( Origin gFrontEnd )
				)
				( attribute "WATTAGE" "1/16W"
					( Origin gFrontEnd )
				)
				( attribute "XY" "(-1150,650)"
					( Origin gFrontEnd )
				)
				( attribute "CHIPS_PART_NAME" "RES"
					( Origin gPackager )
				)
				( attribute "CDS_PART_NAME" "RES_0402-0.0,5%,1/16W,CHIP,G21A"
					( Origin gPackager )
				)
				( objectStatus "R4B14" )
				( pin "a"
					( attribute "PN" "1"
						( Origin gPackager )
					)
					( objectStatus "R4B14.1" )
				)
				( pin "b"
					( attribute "PN" "2"
						( Origin gPackager )
					)
					( objectStatus "R4B14.2" )
				)
			)
			( gate "@baseboard_fab2_lib.baseboard_fab2(sch_1):page234_i84"
				( attribute "BOM_COST" "MEM_VRD_PVPP_AB"
					( Origin gFrontEnd )
				)
				( attribute "CDS_LIB" "mstr_discrete"
					( Origin gPackager )
				)
				( attribute "CDS_LOCATION" "C3B2"
					( Origin gPackager )
				)
				( attribute "CDS_SEC" "1"
					( Origin gPackager )
				)
				( attribute "LOCATION" "C3B2"
					( Origin gFrontEnd )
				)
				( attribute "MATERIAL" "X6S"
					( Origin gFrontEnd )
				)
				( attribute "PACK_TYPE" "0603LF"
					( Origin gFrontEnd )
				)
				( attribute "PART_NUMBER" "E15431-001"
					( Origin gFrontEnd )
				)
				( attribute "PHYS_PAGE" "234"
					( Origin gFrontEnd )
				)
				( attribute "ROOM" "PVPP_KLM_VR"
					( Origin gFrontEnd )
				)
				( attribute "ROT" "0"
					( Origin gFrontEnd )
				)
				( attribute "SEC" "1"
					( Origin gFrontEnd )
				)
				( attribute "SEC_TYPE" "0603LF"
					( Origin gFrontEnd )
				)
				( attribute "TOLERANCE" "20%"
					( Origin gFrontEnd )
				)
				( attribute "VALUE" "10UF"
					( Origin gFrontEnd )
				)
				( attribute "VER" "1"
					( Origin gFrontEnd )
				)
				( attribute "VOLTAGE" "4V"
					( Units "uVoltage" "V" 1.000000)
					( Origin gFrontEnd )
				)
				( attribute "XY" "(-5150,725)"
					( Origin gFrontEnd )
				)
				( attribute "CHIPS_PART_NAME" "CAP"
					( Origin gPackager )
				)
				( attribute "CDS_PART_NAME" "CAP_0603LF-10UF,4V,20%,X6S,E15A"
					( Origin gPackager )
				)
				( objectStatus "C3B2" )
				( pin "a"
					( attribute "PN" "1"
						( Origin gPackager )
					)
					( objectStatus "C3B2.1" )
				)
				( pin "b"
					( attribute "PN" "2"
						( Origin gPackager )
					)
					( objectStatus "C3B2.2" )
				)
			)
			( gate "@baseboard_fab2_lib.baseboard_fab2(sch_1):page234_i86"
				( attribute "BOM_COST" "MEM_VRD_PVPP_AB"
					( Origin gFrontEnd )
				)
				( attribute "CDS_LIB" "mstr_discrete"
					( Origin gPackager )
				)
				( attribute "CDS_LOCATION" "C3A8"
					( Origin gPackager )
				)
				( attribute "CDS_SEC" "1"
					( Origin gPackager )
				)
				( attribute "LOCATION" "C3A8"
					( Origin gFrontEnd )
				)
				( attribute "MATERIAL" "X6S"
					( Origin gFrontEnd )
				)
				( attribute "PACK_TYPE" "0603LF"
					( Origin gFrontEnd )
				)
				( attribute "PART_NUMBER" "E15431-001"
					( Origin gFrontEnd )
				)
				( attribute "PHYS_PAGE" "234"
					( Origin gFrontEnd )
				)
				( attribute "ROOM" "PVPP_KLM_VR"
					( Origin gFrontEnd )
				)
				( attribute "ROT" "0"
					( Origin gFrontEnd )
				)
				( attribute "SEC" "1"
					( Origin gPackager )
				)
				( attribute "TOLERANCE" "20%"
					( Origin gFrontEnd )
				)
				( attribute "VALUE" "10UF"
					( Origin gFrontEnd )
				)
				( attribute "VER" "1"
					( Origin gFrontEnd )
				)
				( attribute "VOLTAGE" "4V"
					( Units "uVoltage" "V" 1.000000)
					( Origin gFrontEnd )
				)
				( attribute "XY" "(-5400,700)"
					( Origin gFrontEnd )
				)
				( attribute "CHIPS_PART_NAME" "CAP"
					( Origin gPackager )
				)
				( attribute "CDS_PART_NAME" "CAP_0603LF-10UF,4V,20%,X6S,E15A"
					( Origin gPackager )
				)
				( objectStatus "C3A8" )
				( pin "a"
					( attribute "PN" "1"
						( Origin gPackager )
					)
					( objectStatus "C3A8.1" )
				)
				( pin "b"
					( attribute "PN" "2"
						( Origin gPackager )
					)
					( objectStatus "C3A8.2" )
				)
			)
			( gate "@baseboard_fab2_lib.baseboard_fab2(sch_1):page234_i87"
				( attribute "BOM_COST" "MEM_VRD_PVPP_AB"
					( Origin gFrontEnd )
				)
				( attribute "CDS_LIB" "mstr_discrete"
					( Origin gPackager )
				)
				( attribute "CDS_LOCATION" "C7L3"
					( Origin gPackager )
				)
				( attribute "CDS_SEC" "1"
					( Origin gPackager )
				)
				( attribute "LOCATION" "C7L3"
					( Origin gFrontEnd )
				)
				( attribute "MATERIAL" "X6S"
					( Origin gFrontEnd )
				)
				( attribute "PACK_TYPE" "0603LF"
					( Origin gFrontEnd )
				)
				( attribute "PART_NUMBER" "E15431-001"
					( Origin gFrontEnd )
				)
				( attribute "PHYS_PAGE" "234"
					( Origin gFrontEnd )
				)
				( attribute "ROOM" "PVPP_KLM_VR"
					( Origin gFrontEnd )
				)
				( attribute "ROT" "0"
					( Origin gFrontEnd )
				)
				( attribute "SEC" "1"
					( Origin gPackager )
				)
				( attribute "TOLERANCE" "20%"
					( Origin gFrontEnd )
				)
				( attribute "VALUE" "10UF"
					( Origin gFrontEnd )
				)
				( attribute "VER" "1"
					( Origin gFrontEnd )
				)
				( attribute "VOLTAGE" "4V"
					( Units "uVoltage" "V" 1.000000)
					( Origin gFrontEnd )
				)
				( attribute "XY" "(-5675,700)"
					( Origin gFrontEnd )
				)
				( attribute "CHIPS_PART_NAME" "CAP"
					( Origin gPackager )
				)
				( attribute "CDS_PART_NAME" "CAP_0603LF-10UF,4V,20%,X6S,E15A"
					( Origin gPackager )
				)
				( objectStatus "C7L3" )
				( pin "a"
					( attribute "PN" "1"
						( Origin gPackager )
					)
					( objectStatus "C7L3.1" )
				)
				( pin "b"
					( attribute "PN" "2"
						( Origin gPackager )
					)
					( objectStatus "C7L3.2" )
				)
			)
			( gate "@baseboard_fab2_lib.baseboard_fab2(sch_1):page234_i88"
				( attribute "BOM_COST" "MEM_VRD_PVPP_AB"
					( Origin gFrontEnd )
				)
				( attribute "CDS_LIB" "mstr_discrete"
					( Origin gPackager )
				)
				( attribute "CDS_LOCATION" "C7L2"
					( Origin gPackager )
				)
				( attribute "CDS_SEC" "1"
					( Origin gPackager )
				)
				( attribute "LOCATION" "C7L2"
					( Origin gFrontEnd )
				)
				( attribute "MATERIAL" "X6S"
					( Origin gFrontEnd )
				)
				( attribute "PACK_TYPE" "0603LF"
					( Origin gFrontEnd )
				)
				( attribute "PART_NUMBER" "E15431-001"
					( Origin gFrontEnd )
				)
				( attribute "PHYS_PAGE" "234"
					( Origin gFrontEnd )
				)
				( attribute "ROOM" "PVPP_KLM_VR"
					( Origin gFrontEnd )
				)
				( attribute "ROT" "0"
					( Origin gFrontEnd )
				)
				( attribute "SEC" "1"
					( Origin gPackager )
				)
				( attribute "TOLERANCE" "20%"
					( Origin gFrontEnd )
				)
				( attribute "VALUE" "10UF"
					( Origin gFrontEnd )
				)
				( attribute "VER" "1"
					( Origin gFrontEnd )
				)
				( attribute "VOLTAGE" "4V"
					( Units "uVoltage" "V" 1.000000)
					( Origin gFrontEnd )
				)
				( attribute "XY" "(-5950,725)"
					( Origin gFrontEnd )
				)
				( attribute "CHIPS_PART_NAME" "CAP"
					( Origin gPackager )
				)
				( attribute "CDS_PART_NAME" "CAP_0603LF-10UF,4V,20%,X6S,E15A"
					( Origin gPackager )
				)
				( objectStatus "C7L2" )
				( pin "a"
					( attribute "PN" "1"
						( Origin gPackager )
					)
					( objectStatus "C7L2.1" )
				)
				( pin "b"
					( attribute "PN" "2"
						( Origin gPackager )
					)
					( objectStatus "C7L2.2" )
				)
			)
			( gate "@baseboard_fab2_lib.baseboard_fab2(sch_1):page234_i89"
				( attribute "BOM_COST" "MEM_VRD_PVPP_AB"
					( Origin gFrontEnd )
				)
				( attribute "CDS_LIB" "mstr_discrete"
					( Origin gPackager )
				)
				( attribute "CDS_LOCATION" "C7L7"
					( Origin gPackager )
				)
				( attribute "CDS_SEC" "1"
					( Origin gPackager )
				)
				( attribute "LOCATION" "C7L7"
					( Origin gFrontEnd )
				)
				( attribute "MATERIAL" "X6S"
					( Origin gFrontEnd )
				)
				( attribute "PACK_TYPE" "0603LF"
					( Origin gFrontEnd )
				)
				( attribute "PART_NUMBER" "E15431-001"
					( Origin gFrontEnd )
				)
				( attribute "PHYS_PAGE" "234"
					( Origin gFrontEnd )
				)
				( attribute "ROOM" "PVPP_KLM_VR"
					( Origin gFrontEnd )
				)
				( attribute "ROT" "0"
					( Origin gFrontEnd )
				)
				( attribute "SEC" "1"
					( Origin gPackager )
				)
				( attribute "TOLERANCE" "20%"
					( Origin gFrontEnd )
				)
				( attribute "VALUE" "10UF"
					( Origin gFrontEnd )
				)
				( attribute "VER" "1"
					( Origin gFrontEnd )
				)
				( attribute "VOLTAGE" "4V"
					( Units "uVoltage" "V" 1.000000)
					( Origin gFrontEnd )
				)
				( attribute "XY" "(-6250,725)"
					( Origin gFrontEnd )
				)
				( attribute "CHIPS_PART_NAME" "CAP"
					( Origin gPackager )
				)
				( attribute "CDS_PART_NAME" "CAP_0603LF-10UF,4V,20%,X6S,E15A"
					( Origin gPackager )
				)
				( objectStatus "C7L7" )
				( pin "a"
					( attribute "PN" "1"
						( Origin gPackager )
					)
					( objectStatus "C7L7.1" )
				)
				( pin "b"
					( attribute "PN" "2"
						( Origin gPackager )
					)
					( objectStatus "C7L7.2" )
				)
			)
			( gate "@baseboard_fab2_lib.baseboard_fab2(sch_1):page234_i90"
				( attribute "BOM_COST" "MEM_VRD_PVPP_AB"
					( Origin gFrontEnd )
				)
				( attribute "CDS_LIB" "mstr_discrete"
					( Origin gPackager )
				)
				( attribute "CDS_LOCATION" "C7L6"
					( Origin gPackager )
				)
				( attribute "CDS_SEC" "1"
					( Origin gPackager )
				)
				( attribute "LOCATION" "C7L6"
					( Origin gFrontEnd )
				)
				( attribute "MATERIAL" "X6S"
					( Origin gFrontEnd )
				)
				( attribute "PACK_TYPE" "0603LF"
					( Origin gFrontEnd )
				)
				( attribute "PART_NUMBER" "E15431-001"
					( Origin gFrontEnd )
				)
				( attribute "PHYS_PAGE" "234"
					( Origin gFrontEnd )
				)
				( attribute "ROOM" "PVPP_KLM_VR"
					( Origin gFrontEnd )
				)
				( attribute "ROT" "0"
					( Origin gFrontEnd )
				)
				( attribute "SEC" "1"
					( Origin gPackager )
				)
				( attribute "TOLERANCE" "20%"
					( Origin gFrontEnd )
				)
				( attribute "VALUE" "10UF"
					( Origin gFrontEnd )
				)
				( attribute "VER" "1"
					( Origin gFrontEnd )
				)
				( attribute "VOLTAGE" "4V"
					( Units "uVoltage" "V" 1.000000)
					( Origin gFrontEnd )
				)
				( attribute "XY" "(-6550,725)"
					( Origin gFrontEnd )
				)
				( attribute "CHIPS_PART_NAME" "CAP"
					( Origin gPackager )
				)
				( attribute "CDS_PART_NAME" "CAP_0603LF-10UF,4V,20%,X6S,E15A"
					( Origin gPackager )
				)
				( objectStatus "C7L6" )
				( pin "a"
					( attribute "PN" "1"
						( Origin gPackager )
					)
					( objectStatus "C7L6.1" )
				)
				( pin "b"
					( attribute "PN" "2"
						( Origin gPackager )
					)
					( objectStatus "C7L6.2" )
				)
			)
			( gate "@baseboard_fab2_lib.baseboard_fab2(sch_1):page234_i91"
				( attribute "BOM_COST" "MEM_VRD_PVPP_AB"
					( Origin gFrontEnd )
				)
				( attribute "CDS_LIB" "mstr_discrete"
					( Origin gPackager )
				)
				( attribute "CDS_LOCATION" "C7M4"
					( Origin gPackager )
				)
				( attribute "CDS_SEC" "1"
					( Origin gPackager )
				)
				( attribute "LOCATION" "C7M4"
					( Origin gFrontEnd )
				)
				( attribute "MATERIAL" "X6S"
					( Origin gFrontEnd )
				)
				( attribute "PACK_TYPE" "0603LF"
					( Origin gFrontEnd )
				)
				( attribute "PART_NUMBER" "E15431-001"
					( Origin gFrontEnd )
				)
				( attribute "PHYS_PAGE" "234"
					( Origin gFrontEnd )
				)
				( attribute "ROOM" "PVPP_KLM_VR"
					( Origin gFrontEnd )
				)
				( attribute "ROT" "0"
					( Origin gFrontEnd )
				)
				( attribute "SEC" "1"
					( Origin gPackager )
				)
				( attribute "TOLERANCE" "20%"
					( Origin gFrontEnd )
				)
				( attribute "VALUE" "10UF"
					( Origin gFrontEnd )
				)
				( attribute "VER" "1"
					( Origin gFrontEnd )
				)
				( attribute "VOLTAGE" "4V"
					( Units "uVoltage" "V" 1.000000)
					( Origin gFrontEnd )
				)
				( attribute "XY" "(-6825,725)"
					( Origin gFrontEnd )
				)
				( attribute "CHIPS_PART_NAME" "CAP"
					( Origin gPackager )
				)
				( attribute "CDS_PART_NAME" "CAP_0603LF-10UF,4V,20%,X6S,E15A"
					( Origin gPackager )
				)
				( objectStatus "C7M4" )
				( pin "a"
					( attribute "PN" "1"
						( Origin gPackager )
					)
					( objectStatus "C7M4.1" )
				)
				( pin "b"
					( attribute "PN" "2"
						( Origin gPackager )
					)
					( objectStatus "C7M4.2" )
				)
			)
			( gate "@baseboard_fab2_lib.baseboard_fab2(sch_1):page234_i92"
				( attribute "BOM_COST" "MEM_VRD_PVPP_AB"
					( Origin gFrontEnd )
				)
				( attribute "CDS_LIB" "mstr_discrete"
					( Origin gPackager )
				)
				( attribute "CDS_LOCATION" "C7M3"
					( Origin gPackager )
				)
				( attribute "CDS_SEC" "1"
					( Origin gPackager )
				)
				( attribute "LOCATION" "C7M3"
					( Origin gFrontEnd )
				)
				( attribute "MATERIAL" "X6S"
					( Origin gFrontEnd )
				)
				( attribute "PACK_TYPE" "0603LF"
					( Origin gFrontEnd )
				)
				( attribute "PART_NUMBER" "E15431-001"
					( Origin gFrontEnd )
				)
				( attribute "PHYS_PAGE" "234"
					( Origin gFrontEnd )
				)
				( attribute "ROOM" "PVPP_KLM_VR"
					( Origin gFrontEnd )
				)
				( attribute "ROT" "0"
					( Origin gFrontEnd )
				)
				( attribute "SEC" "1"
					( Origin gPackager )
				)
				( attribute "TOLERANCE" "20%"
					( Origin gFrontEnd )
				)
				( attribute "VALUE" "10UF"
					( Origin gFrontEnd )
				)
				( attribute "VER" "1"
					( Origin gFrontEnd )
				)
				( attribute "VOLTAGE" "4V"
					( Units "uVoltage" "V" 1.000000)
					( Origin gFrontEnd )
				)
				( attribute "XY" "(-7125,725)"
					( Origin gFrontEnd )
				)
				( attribute "CHIPS_PART_NAME" "CAP"
					( Origin gPackager )
				)
				( attribute "CDS_PART_NAME" "CAP_0603LF-10UF,4V,20%,X6S,E15A"
					( Origin gPackager )
				)
				( objectStatus "C7M3" )
				( pin "a"
					( attribute "PN" "1"
						( Origin gPackager )
					)
					( objectStatus "C7M3.1" )
				)
				( pin "b"
					( attribute "PN" "2"
						( Origin gPackager )
					)
					( objectStatus "C7M3.2" )
				)
			)
			( gate "@baseboard_fab2_lib.baseboard_fab2(sch_1):page234_i93"
				( attribute "BOM_COST" "MEM_VRD_PVPP_AB"
					( Origin gFrontEnd )
				)
				( attribute "CDS_LIB" "mstr_discrete"
					( Origin gPackager )
				)
				( attribute "CDS_LOCATION" "C3A4"
					( Origin gPackager )
				)
				( attribute "CDS_SEC" "1"
					( Origin gPackager )
				)
				( attribute "LOCATION" "C3A4"
					( Origin gFrontEnd )
				)
				( attribute "MATERIAL" "X6S"
					( Origin gFrontEnd )
				)
				( attribute "PACK_TYPE" "0603LF"
					( Origin gFrontEnd )
				)
				( attribute "PART_NUMBER" "E15431-001"
					( Origin gFrontEnd )
				)
				( attribute "PHYS_PAGE" "234"
					( Origin gFrontEnd )
				)
				( attribute "ROOM" "PVPP_KLM_VR"
					( Origin gFrontEnd )
				)
				( attribute "ROT" "0"
					( Origin gFrontEnd )
				)
				( attribute "SEC" "1"
					( Origin gPackager )
				)
				( attribute "TOLERANCE" "20%"
					( Origin gFrontEnd )
				)
				( attribute "VALUE" "10UF"
					( Origin gFrontEnd )
				)
				( attribute "VER" "1"
					( Origin gFrontEnd )
				)
				( attribute "VOLTAGE" "4V"
					( Units "uVoltage" "V" 1.000000)
					( Origin gFrontEnd )
				)
				( attribute "XY" "(-7400,700)"
					( Origin gFrontEnd )
				)
				( attribute "CHIPS_PART_NAME" "CAP"
					( Origin gPackager )
				)
				( attribute "CDS_PART_NAME" "CAP_0603LF-10UF,4V,20%,X6S,E15A"
					( Origin gPackager )
				)
				( objectStatus "C3A4" )
				( pin "a"
					( attribute "PN" "1"
						( Origin gPackager )
					)
					( objectStatus "C3A4.1" )
				)
				( pin "b"
					( attribute "PN" "2"
						( Origin gPackager )
					)
					( objectStatus "C3A4.2" )
				)
			)
			( gate "@baseboard_fab2_lib.baseboard_fab2(sch_1):page234_i94"
				( attribute "BOM_COST" "MEM_VRD_PVPP_AB"
					( Origin gFrontEnd )
				)
				( attribute "CDS_LIB" "mstr_discrete"
					( Origin gPackager )
				)
				( attribute "CDS_LOCATION" "C3B1"
					( Origin gPackager )
				)
				( attribute "CDS_SEC" "1"
					( Origin gPackager )
				)
				( attribute "LOCATION" "C3B1"
					( Origin gFrontEnd )
				)
				( attribute "MATERIAL" "X6S"
					( Origin gFrontEnd )
				)
				( attribute "PACK_TYPE" "0603LF"
					( Origin gFrontEnd )
				)
				( attribute "PART_NUMBER" "E15431-001"
					( Origin gFrontEnd )
				)
				( attribute "PHYS_PAGE" "234"
					( Origin gFrontEnd )
				)
				( attribute "ROOM" "PVPP_KLM_VR"
					( Origin gFrontEnd )
				)
				( attribute "ROT" "0"
					( Origin gFrontEnd )
				)
				( attribute "SEC" "1"
					( Origin gPackager )
				)
				( attribute "TOLERANCE" "20%"
					( Origin gFrontEnd )
				)
				( attribute "VALUE" "10UF"
					( Origin gFrontEnd )
				)
				( attribute "VER" "1"
					( Origin gFrontEnd )
				)
				( attribute "VOLTAGE" "4V"
					( Units "uVoltage" "V" 1.000000)
					( Origin gFrontEnd )
				)
				( attribute "XY" "(-7650,725)"
					( Origin gFrontEnd )
				)
				( attribute "CHIPS_PART_NAME" "CAP"
					( Origin gPackager )
				)
				( attribute "CDS_PART_NAME" "CAP_0603LF-10UF,4V,20%,X6S,E15A"
					( Origin gPackager )
				)
				( objectStatus "C3B1" )
				( pin "a"
					( attribute "PN" "1"
						( Origin gPackager )
					)
					( objectStatus "C3B1.1" )
				)
				( pin "b"
					( attribute "PN" "2"
						( Origin gPackager )
					)
					( objectStatus "C3B1.2" )
				)
			)
			( gate "@baseboard_fab2_lib.baseboard_fab2(sch_1):page234_i95"
				( attribute "BOM_COST" "MEM_VRD_PVPP_AB"
					( Origin gFrontEnd )
				)
				( attribute "CDS_LIB" "mstr_discrete"
					( Origin gPackager )
				)
				( attribute "CDS_LOCATION" "C3A7"
					( Origin gPackager )
				)
				( attribute "CDS_SEC" "1"
					( Origin gPackager )
				)
				( attribute "LOCATION" "C3A7"
					( Origin gFrontEnd )
				)
				( attribute "MATERIAL" "X6S"
					( Origin gFrontEnd )
				)
				( attribute "PACK_TYPE" "0603LF"
					( Origin gFrontEnd )
				)
				( attribute "PART_NUMBER" "E15431-001"
					( Origin gFrontEnd )
				)
				( attribute "PHYS_PAGE" "234"
					( Origin gFrontEnd )
				)
				( attribute "ROOM" "PVPP_KLM_VR"
					( Origin gFrontEnd )
				)
				( attribute "ROT" "0"
					( Origin gFrontEnd )
				)
				( attribute "SEC" "1"
					( Origin gPackager )
				)
				( attribute "TOLERANCE" "20%"
					( Origin gFrontEnd )
				)
				( attribute "VALUE" "10UF"
					( Origin gFrontEnd )
				)
				( attribute "VER" "1"
					( Origin gFrontEnd )
				)
				( attribute "VOLTAGE" "4V"
					( Units "uVoltage" "V" 1.000000)
					( Origin gFrontEnd )
				)
				( attribute "XY" "(-7925,725)"
					( Origin gFrontEnd )
				)
				( attribute "CHIPS_PART_NAME" "CAP"
					( Origin gPackager )
				)
				( attribute "CDS_PART_NAME" "CAP_0603LF-10UF,4V,20%,X6S,E15A"
					( Origin gPackager )
				)
				( objectStatus "C3A7" )
				( pin "a"
					( attribute "PN" "1"
						( Origin gPackager )
					)
					( objectStatus "C3A7.1" )
				)
				( pin "b"
					( attribute "PN" "2"
						( Origin gPackager )
					)
					( objectStatus "C3A7.2" )
				)
			)
			( gate "@baseboard_fab2_lib.baseboard_fab2(sch_1):page234_i97"
				( attribute "BOM_COST" "MEM_VRD_PVPP_AB"
					( Origin gFrontEnd )
				)
				( attribute "CDS_LIB" "mstr_discrete"
					( Origin gPackager )
				)
				( attribute "CDS_LOCATION" "C3A3"
					( Origin gPackager )
				)
				( attribute "CDS_SEC" "1"
					( Origin gPackager )
				)
				( attribute "LOCATION" "C3A3"
					( Origin gFrontEnd )
				)
				( attribute "MATERIAL" "X6S"
					( Origin gFrontEnd )
				)
				( attribute "PACK_TYPE" "0603LF"
					( Origin gFrontEnd )
				)
				( attribute "PART_NUMBER" "E15431-001"
					( Origin gFrontEnd )
				)
				( attribute "PHYS_PAGE" "234"
					( Origin gFrontEnd )
				)
				( attribute "ROOM" "PVPP_KLM_VR"
					( Origin gFrontEnd )
				)
				( attribute "ROT" "0"
					( Origin gFrontEnd )
				)
				( attribute "SEC" "1"
					( Origin gPackager )
				)
				( attribute "TOLERANCE" "20%"
					( Origin gFrontEnd )
				)
				( attribute "VALUE" "10UF"
					( Origin gFrontEnd )
				)
				( attribute "VER" "1"
					( Origin gFrontEnd )
				)
				( attribute "VOLTAGE" "4V"
					( Units "uVoltage" "V" 1.000000)
					( Origin gFrontEnd )
				)
				( attribute "XY" "(-8175,725)"
					( Origin gFrontEnd )
				)
				( attribute "CHIPS_PART_NAME" "CAP"
					( Origin gPackager )
				)
				( attribute "CDS_PART_NAME" "CAP_0603LF-10UF,4V,20%,X6S,E15A"
					( Origin gPackager )
				)
				( objectStatus "C3A3" )
				( pin "a"
					( attribute "PN" "1"
						( Origin gPackager )
					)
					( objectStatus "C3A3.1" )
				)
				( pin "b"
					( attribute "PN" "2"
						( Origin gPackager )
					)
					( objectStatus "C3A3.2" )
				)
			)
			( gate "@baseboard_fab2_lib.baseboard_fab2(sch_1):page234_i129"
				( attribute "BOM_COST" "PVPP_KLM_VR"
					( Origin gFrontEnd )
				)
				( attribute "CDS_LIB" "mstr_discrete"
					( Origin gPackager )
				)
				( attribute "CDS_LOCATION" "C4B5"
					( Origin gPackager )
				)
				( attribute "CDS_SEC" "1"
					( Origin gPackager )
				)
				( attribute "FIN" "VR_1P2"
					( Origin gFrontEnd )
				)
				( attribute "LOCATION" "C4B5"
					( Origin gFrontEnd )
				)
				( attribute "MATERIAL" "EMPTY"
					( Origin gFrontEnd )
				)
				( attribute "PACK_TYPE" "0402LF"
					( Origin gFrontEnd )
				)
				( attribute "PART_NUMBER" "A36096-046"
					( Origin gFrontEnd )
				)
				( attribute "PHYS_PAGE" "234"
					( Origin gFrontEnd )
				)
				( attribute "REUSE_ID" "1"
					( Origin gFrontEnd )
				)
				( attribute "ROOM" "PVPP_KLM_VR"
					( Origin gFrontEnd )
				)
				( attribute "ROT" "2"
					( Origin gFrontEnd )
				)
				( attribute "SEC" "1"
					( Origin gPackager )
				)
				( attribute "TOLERANCE" "10%"
					( Origin gFrontEnd )
				)
				( attribute "VALUE" "1000PF"
					( Origin gFrontEnd )
				)
				( attribute "VER" "1"
					( Origin gFrontEnd )
				)
				( attribute "VOLTAGE" "50V"
					( Units "uVoltage" "V" 1.000000)
					( Origin gFrontEnd )
				)
				( attribute "XY" "(-6300,2400)"
					( Origin gFrontEnd )
				)
				( attribute "CHIPS_PART_NAME" "CAP"
					( Origin gPackager )
				)
				( attribute "CDS_PART_NAME" "CAP_0402LF-1000PF,50V,10%,EMPTA"
					( Origin gPackager )
				)
				( objectStatus "C4B5" )
				( pin "a"
					( attribute "PN" "1"
						( Origin gPackager )
					)
					( objectStatus "C4B5.1" )
				)
				( pin "b"
					( attribute "PN" "2"
						( Origin gPackager )
					)
					( objectStatus "C4B5.2" )
				)
			)
			( gate "@baseboard_fab2_lib.baseboard_fab2(sch_1):page234_i130"
				( attribute "BOM_COST" "PVPP_KLM_VR"
					( Origin gFrontEnd )
				)
				( attribute "CDS_LIB" "mstr_discrete"
					( Origin gPackager )
				)
				( attribute "CDS_LOCATION" "C4B1"
					( Origin gPackager )
				)
				( attribute "CDS_SEC" "1"
					( Origin gPackager )
				)
				( attribute "LOCATION" "C4B1"
					( Origin gFrontEnd )
				)
				( attribute "MATERIAL" "X6S"
					( Origin gFrontEnd )
				)
				( attribute "PACK_TYPE" "1210"
					( Origin gFrontEnd )
				)
				( attribute "PART_NUMBER" "D38464-007"
					( Origin gFrontEnd )
				)
				( attribute "PHYS_PAGE" "234"
					( Origin gFrontEnd )
				)
				( attribute "ROOM" "PVPP_KLM_VR"
					( Origin gFrontEnd )
				)
				( attribute "ROT" "0"
					( Origin gFrontEnd )
				)
				( attribute "SEC" "1"
					( Origin gPackager )
				)
				( attribute "TOLERANCE" "20%"
					( Origin gFrontEnd )
				)
				( attribute "VALUE" "47UF"
					( Origin gFrontEnd )
				)
				( attribute "VER" "1"
					( Origin gFrontEnd )
				)
				( attribute "VOLTAGE" "16V"
					( Units "uVoltage" "V" 1.000000)
					( Origin gFrontEnd )
				)
				( attribute "XY" "(-7275,4150)"
					( Origin gFrontEnd )
				)
				( attribute "CHIPS_PART_NAME" "CAP"
					( Origin gPackager )
				)
				( attribute "CDS_PART_NAME" "CAP_1210-47UF,16V,20%,X6S,D384A"
					( Origin gPackager )
				)
				( objectStatus "C4B1" )
				( pin "a"
					( attribute "PN" "1"
						( Origin gPackager )
					)
					( objectStatus "C4B1.1" )
				)
				( pin "b"
					( attribute "PN" "2"
						( Origin gPackager )
					)
					( objectStatus "C4B1.2" )
				)
			)
			( gate "@baseboard_fab2_lib.baseboard_fab2(sch_1):page234_i139"
				( attribute "BOM_COST" "PVPP_KLM_VR"
					( Origin gFrontEnd )
				)
				( attribute "CDS_LIB" "mstr_discrete"
					( Origin gPackager )
				)
				( attribute "CDS_LOCATION" "C4B8"
					( Origin gPackager )
				)
				( attribute "CDS_SEC" "1"
					( Origin gPackager )
				)
				( attribute "LOCATION" "C4B8"
					( Origin gFrontEnd )
				)
				( attribute "MATERIAL" "X7R"
					( Origin gFrontEnd )
				)
				( attribute "PACK_TYPE" "0402LF"
					( Origin gFrontEnd )
				)
				( attribute "PART_NUMBER" "A36096-046"
					( Origin gFrontEnd )
				)
				( attribute "PHYS_PAGE" "234"
					( Origin gFrontEnd )
				)
				( attribute "REUSE_ID" "17"
					( Origin gFrontEnd )
				)
				( attribute "ROOM" "PVPP_KLM_VR"
					( Origin gFrontEnd )
				)
				( attribute "ROT" "0"
					( Origin gFrontEnd )
				)
				( attribute "SEC" "1"
					( Origin gPackager )
				)
				( attribute "TOLERANCE" "10%"
					( Origin gFrontEnd )
				)
				( attribute "VALUE" "1000PF"
					( Origin gFrontEnd )
				)
				( attribute "VER" "1"
					( Origin gFrontEnd )
				)
				( attribute "VOLTAGE" "50V"
					( Units "uVoltage" "V" 1.000000)
					( Origin gFrontEnd )
				)
				( attribute "XY" "(-3875,725)"
					( Origin gFrontEnd )
				)
				( attribute "CHIPS_PART_NAME" "CAP"
					( Origin gPackager )
				)
				( attribute "CDS_PART_NAME" "CAP_0402LF-1000PF,50V,10%,X7R,A"
					( Origin gPackager )
				)
				( objectStatus "C4B8" )
				( pin "a"
					( attribute "PN" "1"
						( Origin gPackager )
					)
					( objectStatus "C4B8.1" )
				)
				( pin "b"
					( attribute "PN" "2"
						( Origin gPackager )
					)
					( objectStatus "C4B8.2" )
				)
			)
			( gate "@baseboard_fab2_lib.baseboard_fab2(sch_1):page234_i140"
				( attribute "BOM_COST" "PVPP_KLM_VR"
					( Origin gFrontEnd )
				)
				( attribute "CDS_LIB" "mstr_discrete"
					( Origin gPackager )
				)
				( attribute "CDS_LOCATION" "R4B6"
					( Origin gPackager )
				)
				( attribute "CDS_SEC" "1"
					( Origin gPackager )
				)
				( attribute "LOCATION" "R4B6"
					( Origin gFrontEnd )
				)
				( attribute "MATERIAL" "CHIP"
					( Origin gFrontEnd )
				)
				( attribute "PACK_TYPE" "0402"
					( Origin gFrontEnd )
				)
				( attribute "PART_NUMBER" "G21796-242"
					( Origin gFrontEnd )
				)
				( attribute "PHYS_PAGE" "234"
					( Origin gFrontEnd )
				)
				( attribute "ROOM" "PVPP_KLM_VR"
					( Origin gFrontEnd )
				)
				( attribute "ROT" "2"
					( Origin gFrontEnd )
				)
				( attribute "SEC" "1"
					( Origin gFrontEnd )
				)
				( attribute "SEC_TYPE" "0402"
					( Origin gFrontEnd )
				)
				( attribute "TOLERANCE" "1.0%"
					( Origin gFrontEnd )
				)
				( attribute "VALUE" "7.87K"
					( Origin gFrontEnd )
				)
				( attribute "VER" "2"
					( Origin gFrontEnd )
				)
				( attribute "WATTAGE" "1/16W"
					( Origin gFrontEnd )
				)
				( attribute "XY" "(-4750,1650)"
					( Origin gFrontEnd )
				)
				( attribute "CHIPS_PART_NAME" "RES"
					( Origin gPackager )
				)
				( attribute "CDS_PART_NAME" "RES_0402-7.87K,1.0%,1/16W,CHIPA"
					( Origin gPackager )
				)
				( objectStatus "R4B6" )
				( pin "a"
					( attribute "PN" "1"
						( Origin gPackager )
					)
					( objectStatus "R4B6.1" )
				)
				( pin "b"
					( attribute "PN" "2"
						( Origin gPackager )
					)
					( objectStatus "R4B6.2" )
				)
			)
			( gate "@baseboard_fab2_lib.baseboard_fab2(sch_1):page234_i143"
				( attribute "BOM_COST" "PVPP_KLM_VR"
					( Origin gFrontEnd )
				)
				( attribute "CDS_LIB" "mstr_discrete"
					( Origin gPackager )
				)
				( attribute "CDS_LOCATION" "R4B10"
					( Origin gPackager )
				)
				( attribute "CDS_SEC" "1"
					( Origin gPackager )
				)
				( attribute "LOCATION" "R4B10"
					( Origin gFrontEnd )
				)
				( attribute "MATERIAL" "CHIP"
					( Origin gFrontEnd )
				)
				( attribute "PACK_TYPE" "0402"
					( Origin gFrontEnd )
				)
				( attribute "PART_NUMBER" "G21796-026"
					( Origin gFrontEnd )
				)
				( attribute "PHYS_PAGE" "234"
					( Origin gFrontEnd )
				)
				( attribute "REUSE_ID" "21"
					( Origin gFrontEnd )
				)
				( attribute "ROOM" "PVPP_KLM_VR"
					( Origin gFrontEnd )
				)
				( attribute "ROT" "0"
					( Origin gFrontEnd )
				)
				( attribute "SEC" "1"
					( Origin gFrontEnd )
				)
				( attribute "SEC_TYPE" "0402"
					( Origin gFrontEnd )
				)
				( attribute "TOLERANCE" "1%"
					( Origin gFrontEnd )
				)
				( attribute "VALUE" "1.00K"
					( Origin gFrontEnd )
				)
				( attribute "VER" "2"
					( Origin gFrontEnd )
				)
				( attribute "WATTAGE" "1/16W"
					( Origin gFrontEnd )
				)
				( attribute "XY" "(-4225,1250)"
					( Origin gFrontEnd )
				)
				( attribute "CHIPS_PART_NAME" "RES"
					( Origin gPackager )
				)
				( attribute "CDS_PART_NAME" "RES_0402-1.00K,1%,1/16W,CHIP,GA"
					( Origin gPackager )
				)
				( objectStatus "R4B10" )
				( pin "a"
					( attribute "PN" "1"
						( Origin gPackager )
					)
					( objectStatus "R4B10.1" )
				)
				( pin "b"
					( attribute "PN" "2"
						( Origin gPackager )
					)
					( objectStatus "R4B10.2" )
				)
			)
			( gate "@baseboard_fab2_lib.baseboard_fab2(sch_1):page234_i144"
				( attribute "BOM_COST" "PVPP_KLM_VR"
					( Origin gFrontEnd )
				)
				( attribute "CDS_LIB" "mstr_discrete"
					( Origin gPackager )
				)
				( attribute "CDS_LOCATION" "C6L12"
					( Origin gPackager )
				)
				( attribute "CDS_SEC" "1"
					( Origin gPackager )
				)
				( attribute "LOCATION" "C6L12"
					( Origin gFrontEnd )
				)
				( attribute "MATERIAL" "X6S"
					( Origin gFrontEnd )
				)
				( attribute "PACK_TYPE" "0603"
					( Origin gFrontEnd )
				)
				( attribute "PART_NUMBER" "E15431-003"
					( Origin gFrontEnd )
				)
				( attribute "PHYS_PAGE" "234"
					( Origin gFrontEnd )
				)
				( attribute "REUSE_ID" "26"
					( Origin gFrontEnd )
				)
				( attribute "ROOM" "PVPP_KLM_VR"
					( Origin gFrontEnd )
				)
				( attribute "ROT" "0"
					( Origin gFrontEnd )
				)
				( attribute "SEC" "1"
					( Origin gFrontEnd )
				)
				( attribute "SEC_TYPE" "0603"
					( Origin gFrontEnd )
				)
				( attribute "TOLERANCE" "10%"
					( Origin gFrontEnd )
				)
				( attribute "VALUE" "4.7UF"
					( Origin gFrontEnd )
				)
				( attribute "VER" "1"
					( Origin gFrontEnd )
				)
				( attribute "VOLTAGE" "6.3V"
					( Units "uVoltage" "V" 1.000000)
					( Origin gFrontEnd )
				)
				( attribute "XY" "(-5600,2400)"
					( Origin gFrontEnd )
				)
				( attribute "CHIPS_PART_NAME" "CAP"
					( Origin gPackager )
				)
				( attribute "CDS_PART_NAME" "CAP_0603-4.7UF,6.3V,10%,X6S,E1A"
					( Origin gPackager )
				)
				( objectStatus "C6L12" )
				( pin "a"
					( attribute "PN" "1"
						( Origin gPackager )
					)
					( objectStatus "C6L12.1" )
				)
				( pin "b"
					( attribute "PN" "2"
						( Origin gPackager )
					)
					( objectStatus "C6L12.2" )
				)
			)
			( gate "@baseboard_fab2_lib.baseboard_fab2(sch_1):page234_i146"
				( attribute "BOM_COST" "PVPP_KLM_VR"
					( Origin gFrontEnd )
				)
				( attribute "CDS_LIB" "mstr_discrete"
					( Origin gPackager )
				)
				( attribute "CDS_LOCATION" "C4B6"
					( Origin gPackager )
				)
				( attribute "CDS_SEC" "1"
					( Origin gPackager )
				)
				( attribute "LOCATION" "C4B6"
					( Origin gFrontEnd )
				)
				( attribute "MATERIAL" "X7R"
					( Origin gFrontEnd )
				)
				( attribute "PACK_TYPE" "0402"
					( Origin gFrontEnd )
				)
				( attribute "PART_NUMBER" "A36096-129"
					( Origin gFrontEnd )
				)
				( attribute "PHYS_PAGE" "234"
					( Origin gFrontEnd )
				)
				( attribute "REUSE_ID" "26"
					( Origin gFrontEnd )
				)
				( attribute "ROOM" "PVPP_KLM_VR"
					( Origin gFrontEnd )
				)
				( attribute "ROT" "0"
					( Origin gFrontEnd )
				)
				( attribute "SEC" "1"
					( Origin gFrontEnd )
				)
				( attribute "SEC_TYPE" "0402"
					( Origin gFrontEnd )
				)
				( attribute "TOLERANCE" "10%"
					( Origin gFrontEnd )
				)
				( attribute "VALUE" "0.027UF"
					( Origin gFrontEnd )
				)
				( attribute "VER" "1"
					( Origin gFrontEnd )
				)
				( attribute "VOLTAGE" "16V"
					( Units "uVoltage" "V" 1.000000)
					( Origin gFrontEnd )
				)
				( attribute "XY" "(-5075,2175)"
					( Origin gFrontEnd )
				)
				( attribute "CHIPS_PART_NAME" "CAP"
					( Origin gPackager )
				)
				( attribute "CDS_PART_NAME" "CAP_0402-0.027UF,16V,10%,X7R,AA"
					( Origin gPackager )
				)
				( objectStatus "C4B6" )
				( pin "a"
					( attribute "PN" "1"
						( Origin gPackager )
					)
					( objectStatus "C4B6.1" )
				)
				( pin "b"
					( attribute "PN" "2"
						( Origin gPackager )
					)
					( objectStatus "C4B6.2" )
				)
			)
			( gate "@baseboard_fab2_lib.baseboard_fab2(sch_1):page234_i152"
				( attribute "BOM_COST" "PVPP_KLM_VR"
					( Origin gFrontEnd )
				)
				( attribute "CDS_LIB" "mstr_discrete"
					( Origin gPackager )
				)
				( attribute "CDS_LOCATION" "C6L11"
					( Origin gPackager )
				)
				( attribute "CDS_SEC" "1"
					( Origin gPackager )
				)
				( attribute "FIN" "VR_1P2"
					( Origin gFrontEnd )
				)
				( attribute "LOCATION" "C6L11"
					( Origin gFrontEnd )
				)
				( attribute "MATERIAL" "X6S"
					( Origin gFrontEnd )
				)
				( attribute "PACK_TYPE" "0402"
					( Origin gFrontEnd )
				)
				( attribute "PART_NUMBER" "D97712-011"
					( Origin gFrontEnd )
				)
				( attribute "PHYS_PAGE" "234"
					( Origin gFrontEnd )
				)
				( attribute "REUSE_ID" "1"
					( Origin gFrontEnd )
				)
				( attribute "ROOM" "PVPP_KLM_VR"
					( Origin gFrontEnd )
				)
				( attribute "ROT" "0"
					( Origin gFrontEnd )
				)
				( attribute "SEC" "1"
					( Origin gPackager )
				)
				( attribute "TOLERANCE" "10%"
					( Origin gFrontEnd )
				)
				( attribute "VALUE" "1.0UF"
					( Origin gFrontEnd )
				)
				( attribute "VER" "1"
					( Origin gFrontEnd )
				)
				( attribute "VOLTAGE" "16V"
					( Units "uVoltage" "V" 1.000000)
					( Origin gFrontEnd )
				)
				( attribute "XY" "(-4950,4150)"
					( Origin gFrontEnd )
				)
				( attribute "CHIPS_PART_NAME" "CAP"
					( Origin gPackager )
				)
				( attribute "CDS_PART_NAME" "CAP_0402-1.0UF,16V,10%,X6S,D97A"
					( Origin gPackager )
				)
				( objectStatus "C6L11" )
				( pin "a"
					( attribute "PN" "1"
						( Origin gPackager )
					)
					( objectStatus "C6L11.1" )
				)
				( pin "b"
					( attribute "PN" "2"
						( Origin gPackager )
					)
					( objectStatus "C6L11.2" )
				)
			)
			( gate "@baseboard_fab2_lib.baseboard_fab2(sch_1):page234_i154"
				( attribute "CDS_LIB" "mstr_discrete"
					( Origin gPackager )
				)
				( attribute "CDS_LOCATION" "FB4A1"
					( Origin gPackager )
				)
				( attribute "CDS_SEC" "1"
					( Origin gPackager )
				)
				( attribute "LOCATION" "FB4A1"
					( Origin gFrontEnd )
				)
				( attribute "MATERIAL" "FB"
					( Origin gFrontEnd )
				)
				( attribute "PACK_TYPE" "SM"
					( Origin gFrontEnd )
				)
				( attribute "PART_NUMBER" "656554-051"
					( Origin gFrontEnd )
				)
				( attribute "PHYS_PAGE" "234"
					( Origin gFrontEnd )
				)
				( attribute "ROOM" "PVPP_KLM_VR"
					( Origin gFrontEnd )
				)
				( attribute "ROT" "0"
					( Origin gFrontEnd )
				)
				( attribute "SEC" "1"
					( Origin gFrontEnd )
				)
				( attribute "SEC_TYPE" "SM"
					( Origin gFrontEnd )
				)
				( attribute "TOLERANCE" "1%"
					( Origin gFrontEnd )
				)
				( attribute "VALUE" "22"
					( Origin gFrontEnd )
				)
				( attribute "VER" "1"
					( Origin gFrontEnd )
				)
				( attribute "XY" "(-7500,4300)"
					( Origin gFrontEnd )
				)
				( attribute "CHIPS_PART_NAME" "FERRITE"
					( Origin gPackager )
				)
				( attribute "CDS_PART_NAME" "FERRITE_SM-22,FB,656554-051"
					( Origin gPackager )
				)
				( objectStatus "FB4A1" )
				( pin "a"
					( attribute "PN" "1"
						( Origin gPackager )
					)
					( objectStatus "FB4A1.1" )
				)
				( pin "b"
					( attribute "PN" "2"
						( Origin gPackager )
					)
					( objectStatus "FB4A1.2" )
				)
			)
			( gate "@baseboard_fab2_lib.baseboard_fab2(sch_1):page234_i155"
				( attribute "BOM_COST" "PVPP_KLM_VR"
					( Origin gFrontEnd )
				)
				( attribute "CDS_LIB" "mstr_discrete"
					( Origin gPackager )
				)
				( attribute "CDS_LOCATION" "R4B13"
					( Origin gPackager )
				)
				( attribute "CDS_SEC" "1"
					( Origin gPackager )
				)
				( attribute "LOCATION" "R4B13"
					( Origin gFrontEnd )
				)
				( attribute "MATERIAL" "CHIP"
					( Origin gFrontEnd )
				)
				( attribute "PACK_TYPE" "0402"
					( Origin gFrontEnd )
				)
				( attribute "PART_NUMBER" "G21497-005"
					( Origin gFrontEnd )
				)
				( attribute "PHYS_PAGE" "234"
					( Origin gFrontEnd )
				)
				( attribute "REUSE_ID" "13"
					( Origin gFrontEnd )
				)
				( attribute "ROOM" "PVPP_KLM_VR"
					( Origin gFrontEnd )
				)
				( attribute "ROT" "0"
					( Origin gFrontEnd )
				)
				( attribute "SEC" "1"
					( Origin gPackager )
				)
				( attribute "TOLERANCE" "5%"
					( Origin gFrontEnd )
				)
				( attribute "VALUE" "0.0"
					( Origin gFrontEnd )
				)
				( attribute "VER" "1"
					( Origin gFrontEnd )
				)
				( attribute "WATTAGE" "1/16W"
					( Origin gFrontEnd )
				)
				( attribute "XY" "(-4075,4200)"
					( Origin gFrontEnd )
				)
				( attribute "CHIPS_PART_NAME" "RES"
					( Origin gPackager )
				)
				( attribute "CDS_PART_NAME" "RES_0402-0.0,5%,1/16W,CHIP,G21A"
					( Origin gPackager )
				)
				( objectStatus "R4B13" )
				( pin "a"
					( attribute "PN" "1"
						( Origin gPackager )
					)
					( objectStatus "R4B13.1" )
				)
				( pin "b"
					( attribute "PN" "2"
						( Origin gPackager )
					)
					( objectStatus "R4B13.2" )
				)
			)
			( gate "@baseboard_fab2_lib.baseboard_fab2(sch_1):page234_i162"
				( attribute "BOM_COST" "PVPP_KLM_VR"
					( Origin gFrontEnd )
				)
				( attribute "CDS_LIB" "mstr_discrete"
					( Origin gPackager )
				)
				( attribute "CDS_LOCATION" "R4A7"
					( Origin gPackager )
				)
				( attribute "CDS_SEC" "1"
					( Origin gPackager )
				)
				( attribute "LOCATION" "R4A7"
					( Origin gFrontEnd )
				)
				( attribute "MATERIAL" "EMPTY"
					( Origin gFrontEnd )
				)
				( attribute "PACK_TYPE" "0402"
					( Origin gFrontEnd )
				)
				( attribute "PART_NUMBER" "G21497-016"
					( Origin gFrontEnd )
				)
				( attribute "PHYS_PAGE" "234"
					( Origin gFrontEnd )
				)
				( attribute "REUSE_ID" "29"
					( Origin gFrontEnd )
				)
				( attribute "ROOM" "PVPP_KLM_VR"
					( Origin gFrontEnd )
				)
				( attribute "ROT" "0"
					( Origin gFrontEnd )
				)
				( attribute "SEC" "1"
					( Origin gPackager )
				)
				( attribute "TOLERANCE" "5%"
					( Origin gFrontEnd )
				)
				( attribute "VALUE" "2.2"
					( Origin gFrontEnd )
				)
				( attribute "VER" "2"
					( Origin gFrontEnd )
				)
				( attribute "WATTAGE" "1/16W"
					( Origin gFrontEnd )
				)
				( attribute "XY" "(-2650,3350)"
					( Origin gFrontEnd )
				)
				( attribute "CHIPS_PART_NAME" "RES"
					( Origin gPackager )
				)
				( attribute "CDS_PART_NAME" "RES_0402-2.2,5%,1/16W,EMPTY,G2A"
					( Origin gPackager )
				)
				( objectStatus "R4A7" )
				( pin "a"
					( attribute "PN" "1"
						( Origin gPackager )
					)
					( objectStatus "R4A7.1" )
				)
				( pin "b"
					( attribute "PN" "2"
						( Origin gPackager )
					)
					( objectStatus "R4A7.2" )
				)
			)
			( gate "@baseboard_fab2_lib.baseboard_fab2(sch_1):page234_i163"
				( attribute "BOM_COST" "PVPP_KLM_VR"
					( Origin gFrontEnd )
				)
				( attribute "CDS_LIB" "mstr_discrete"
					( Origin gPackager )
				)
				( attribute "CDS_LOCATION" "C4A16"
					( Origin gPackager )
				)
				( attribute "CDS_SEC" "1"
					( Origin gPackager )
				)
				( attribute "LOCATION" "C4A16"
					( Origin gFrontEnd )
				)
				( attribute "MATERIAL" "EMPTY"
					( Origin gFrontEnd )
				)
				( attribute "PACK_TYPE" "0402LF"
					( Origin gFrontEnd )
				)
				( attribute "PART_NUMBER" "A36096-091"
					( Origin gFrontEnd )
				)
				( attribute "PHYS_PAGE" "234"
					( Origin gFrontEnd )
				)
				( attribute "REUSE_ID" "26"
					( Origin gFrontEnd )
				)
				( attribute "ROOM" "PVPP_KLM_VR"
					( Origin gFrontEnd )
				)
				( attribute "ROT" "0"
					( Origin gFrontEnd )
				)
				( attribute "SEC" "1"
					( Origin gPackager )
				)
				( attribute "TOLERANCE" "10%"
					( Origin gFrontEnd )
				)
				( attribute "VALUE" "3300PF"
					( Origin gFrontEnd )
				)
				( attribute "VER" "1"
					( Origin gFrontEnd )
				)
				( attribute "VOLTAGE" "50V"
					( Units "uVoltage" "V" 1.000000)
					( Origin gFrontEnd )
				)
				( attribute "XY" "(-2650,3700)"
					( Origin gFrontEnd )
				)
				( attribute "CHIPS_PART_NAME" "CAP"
					( Origin gPackager )
				)
				( attribute "CDS_PART_NAME" "CAP_0402LF-3300PF,50V,10%,EMPTA"
					( Origin gPackager )
				)
				( objectStatus "C4A16" )
				( pin "a"
					( attribute "PN" "1"
						( Origin gPackager )
					)
					( objectStatus "C4A16.1" )
				)
				( pin "b"
					( attribute "PN" "2"
						( Origin gPackager )
					)
					( objectStatus "C4A16.2" )
				)
			)
			( gate "@baseboard_fab2_lib.baseboard_fab2(sch_1):page234_i164"
				( attribute "BOM_COST" "PVPP_KLM_VR"
					( Origin gFrontEnd )
				)
				( attribute "CDS_LIB" "mstr_discrete"
					( Origin gPackager )
				)
				( attribute "CDS_LOCATION" "L4A1"
					( Origin gPackager )
				)
				( attribute "CDS_SEC" "1"
					( Origin gPackager )
				)
				( attribute "LOCATION" "L4A1"
					( Origin gFrontEnd )
				)
				( attribute "MATERIAL" "IND"
					( Origin gFrontEnd )
				)
				( attribute "PACK_TYPE" "SM"
					( Origin gFrontEnd )
				)
				( attribute "PART_NUMBER" "E13358-018"
					( Origin gFrontEnd )
				)
				( attribute "PHYS_PAGE" "234"
					( Origin gFrontEnd )
				)
				( attribute "REUSE_ID" "30"
					( Origin gFrontEnd )
				)
				( attribute "ROOM" "PVPP_KLM_VR"
					( Origin gFrontEnd )
				)
				( attribute "ROT" "0"
					( Origin gFrontEnd )
				)
				( attribute "SEC" "1"
					( Origin gPackager )
				)
				( attribute "TOLERANCE" "1%"
					( Origin gFrontEnd )
				)
				( attribute "VALUE" "0.47UH"
					( Origin gFrontEnd )
				)
				( attribute "VER" "1"
					( Origin gFrontEnd )
				)
				( attribute "XY" "(-2300,3850)"
					( Origin gFrontEnd )
				)
				( attribute "CHIPS_PART_NAME" "INDUCTOR"
					( Origin gPackager )
				)
				( attribute "CDS_PART_NAME" "INDUCTOR_SM-0.47UH,IND,E13358-A"
					( Origin gPackager )
				)
				( objectStatus "L4A1" )
				( pin "ina"
					( attribute "PN" "1"
						( Origin gPackager )
					)
					( objectStatus "L4A1.1" )
				)
				( pin "inb"
					( attribute "PN" "2"
						( Origin gPackager )
					)
					( objectStatus "L4A1.2" )
				)
			)
			( gate "@baseboard_fab2_lib.baseboard_fab2(sch_1):page234_i167"
				( attribute "BOM_COST" "PVPP_KLM_VR"
					( Origin gFrontEnd )
				)
				( attribute "CDS_LIB" "mstr_discrete"
					( Origin gPackager )
				)
				( attribute "CDS_LOCATION" "C3B3"
					( Origin gPackager )
				)
				( attribute "CDS_SEC" "1"
					( Origin gPackager )
				)
				( attribute "LOCATION" "C3B3"
					( Origin gFrontEnd )
				)
				( attribute "MATERIAL" "POSCAP"
					( Origin gFrontEnd )
				)
				( attribute "PACK_TYPE" "7343LF"
					( Origin gFrontEnd )
				)
				( attribute "PART_NUMBER" "724613-042"
					( Origin gFrontEnd )
				)
				( attribute "PHYS_PAGE" "234"
					( Origin gFrontEnd )
				)
				( attribute "REUSE_ID" "28"
					( Origin gFrontEnd )
				)
				( attribute "ROOM" "PVPP_KLM_VR"
					( Origin gFrontEnd )
				)
				( attribute "ROT" "0"
					( Origin gFrontEnd )
				)
				( attribute "SEC" "1"
					( Origin gPackager )
				)
				( attribute "TOLERANCE" "20%"
					( Origin gFrontEnd )
				)
				( attribute "VALUE" "330UF"
					( Origin gFrontEnd )
				)
				( attribute "VER" "1"
					( Origin gFrontEnd )
				)
				( attribute "VOLTAGE" "6.3V"
					( Units "uVoltage" "V" 1.000000)
					( Origin gFrontEnd )
				)
				( attribute "XY" "(-1750,3675)"
					( Origin gFrontEnd )
				)
				( attribute "CHIPS_PART_NAME" "CAPP"
					( Origin gPackager )
				)
				( attribute "CDS_PART_NAME" "CAPP_7343LF-330UF,6.3V,20%,POSA"
					( Origin gPackager )
				)
				( objectStatus "C3B3" )
				( pin "a"
					( attribute "PN" "1"
						( Origin gPackager )
					)
					( objectStatus "C3B3.1" )
				)
				( pin "b"
					( attribute "PN" "2"
						( Origin gPackager )
					)
					( objectStatus "C3B3.2" )
				)
			)
			( gate "@baseboard_fab2_lib.baseboard_fab2(sch_1):page234_i177"
				( attribute "BOM_COST" "PVPP_KLM_VR"
					( Origin gFrontEnd )
				)
				( attribute "CDS_LIB" "mstr_discrete"
					( Origin gPackager )
				)
				( attribute "CDS_LOCATION" "C4B3"
					( Origin gPackager )
				)
				( attribute "CDS_SEC" "1"
					( Origin gPackager )
				)
				( attribute "LOCATION" "C4B3"
					( Origin gFrontEnd )
				)
				( attribute "MATERIAL" "X6S"
					( Origin gFrontEnd )
				)
				( attribute "PACK_TYPE" "0805"
					( Origin gFrontEnd )
				)
				( attribute "PART_NUMBER" "C95333-006"
					( Origin gFrontEnd )
				)
				( attribute "PHYS_PAGE" "234"
					( Origin gFrontEnd )
				)
				( attribute "REUSE_ID" "33"
					( Origin gFrontEnd )
				)
				( attribute "ROOM" "PVPP_KLM_VR"
					( Origin gFrontEnd )
				)
				( attribute "ROT" "0"
					( Origin gFrontEnd )
				)
				( attribute "SEC" "1"
					( Origin gPackager )
				)
				( attribute "TOLERANCE" "20%"
					( Origin gFrontEnd )
				)
				( attribute "VALUE" "47UF"
					( Origin gFrontEnd )
				)
				( attribute "VER" "1"
					( Origin gFrontEnd )
				)
				( attribute "VOLTAGE" "4V"
					( Units "uVoltage" "V" 1.000000)
					( Origin gFrontEnd )
				)
				( attribute "XY" "(-1150,3675)"
					( Origin gFrontEnd )
				)
				( attribute "CHIPS_PART_NAME" "CAP"
					( Origin gPackager )
				)
				( attribute "CDS_PART_NAME" "CAP_0805-47UF,4V,20%,X6S,C9533A"
					( Origin gPackager )
				)
				( objectStatus "C4B3" )
				( pin "a"
					( attribute "PN" "1"
						( Origin gPackager )
					)
					( objectStatus "C4B3.1" )
				)
				( pin "b"
					( attribute "PN" "2"
						( Origin gPackager )
					)
					( objectStatus "C4B3.2" )
				)
			)
			( gate "@baseboard_fab2_lib.baseboard_fab2(sch_1):page234_i180"
				( attribute "BOM_COST" "PVPP_KLM_VR"
					( Origin gFrontEnd )
				)
				( attribute "CDS_LIB" "mstr_discrete"
					( Origin gPackager )
				)
				( attribute "CDS_LOCATION" "C4B2"
					( Origin gPackager )
				)
				( attribute "CDS_SEC" "1"
					( Origin gPackager )
				)
				( attribute "LOCATION" "C4B2"
					( Origin gFrontEnd )
				)
				( attribute "MATERIAL" "X6S"
					( Origin gFrontEnd )
				)
				( attribute "PACK_TYPE" "0805"
					( Origin gFrontEnd )
				)
				( attribute "PART_NUMBER" "C95333-006"
					( Origin gFrontEnd )
				)
				( attribute "PHYS_PAGE" "234"
					( Origin gFrontEnd )
				)
				( attribute "REUSE_ID" "33"
					( Origin gFrontEnd )
				)
				( attribute "ROOM" "PVPP_KLM_VR"
					( Origin gFrontEnd )
				)
				( attribute "ROT" "0"
					( Origin gFrontEnd )
				)
				( attribute "SEC" "1"
					( Origin gPackager )
				)
				( attribute "TOLERANCE" "20%"
					( Origin gFrontEnd )
				)
				( attribute "VALUE" "47UF"
					( Origin gFrontEnd )
				)
				( attribute "VER" "1"
					( Origin gFrontEnd )
				)
				( attribute "VOLTAGE" "4V"
					( Units "uVoltage" "V" 1.000000)
					( Origin gFrontEnd )
				)
				( attribute "XY" "(-850,3650)"
					( Origin gFrontEnd )
				)
				( attribute "CHIPS_PART_NAME" "CAP"
					( Origin gPackager )
				)
				( attribute "CDS_PART_NAME" "CAP_0805-47UF,4V,20%,X6S,C9533A"
					( Origin gPackager )
				)
				( objectStatus "C4B2" )
				( pin "a"
					( attribute "PN" "1"
						( Origin gPackager )
					)
					( objectStatus "C4B2.1" )
				)
				( pin "b"
					( attribute "PN" "2"
						( Origin gPackager )
					)
					( objectStatus "C4B2.2" )
				)
			)
			( gate "@baseboard_fab2_lib.baseboard_fab2(sch_1):page234_i182"
				( attribute "BOM_COST" "PVPP_KLM_VR"
					( Origin gFrontEnd )
				)
				( attribute "CDS_LIB" "mstr_discrete"
					( Origin gPackager )
				)
				( attribute "CDS_LOCATION" "C4B15"
					( Origin gPackager )
				)
				( attribute "CDS_SEC" "1"
					( Origin gPackager )
				)
				( attribute "LOCATION" "C4B15"
					( Origin gFrontEnd )
				)
				( attribute "MATERIAL" "X7R"
					( Origin gFrontEnd )
				)
				( attribute "PACK_TYPE" "0603LF"
					( Origin gFrontEnd )
				)
				( attribute "PART_NUMBER" "602433-020"
					( Origin gFrontEnd )
				)
				( attribute "PHYS_PAGE" "234"
					( Origin gFrontEnd )
				)
				( attribute "REUSE_ID" "27"
					( Origin gFrontEnd )
				)
				( attribute "ROOM" "PVPP_KLM_VR"
					( Origin gFrontEnd )
				)
				( attribute "ROT" "2"
					( Origin gFrontEnd )
				)
				( attribute "SEC" "1"
					( Origin gPackager )
				)
				( attribute "TOLERANCE" "10%"
					( Origin gFrontEnd )
				)
				( attribute "VALUE" "0.1UF"
					( Origin gFrontEnd )
				)
				( attribute "VER" "2"
					( Origin gFrontEnd )
				)
				( attribute "VOLTAGE" "25V"
					( Units "uVoltage" "V" 1.000000)
					( Origin gFrontEnd )
				)
				( attribute "XY" "(-3375,4200)"
					( Origin gFrontEnd )
				)
				( attribute "CHIPS_PART_NAME" "CAP"
					( Origin gPackager )
				)
				( attribute "CDS_PART_NAME" "CAP_0603LF-0.1UF,25V,10%,X7R,6A"
					( Origin gPackager )
				)
				( objectStatus "C4B15" )
				( pin "a"
					( attribute "PN" "1"
						( Origin gPackager )
					)
					( objectStatus "C4B15.1" )
				)
				( pin "b"
					( attribute "PN" "2"
						( Origin gPackager )
					)
					( objectStatus "C4B15.2" )
				)
			)
			( gate "@baseboard_fab2_lib.baseboard_fab2(sch_1):page234_i183"
				( attribute "BOM_COST" "PVPP_KLM_VR"
					( Origin gFrontEnd )
				)
				( attribute "CDS_LIB" "mstr_discrete"
					( Origin gPackager )
				)
				( attribute "CDS_LOCATION" "R4B2"
					( Origin gPackager )
				)
				( attribute "CDS_SEC" "1"
					( Origin gPackager )
				)
				( attribute "LOCATION" "R4B2"
					( Origin gFrontEnd )
				)
				( attribute "MATERIAL" "CHIP"
					( Origin gFrontEnd )
				)
				( attribute "PACK_TYPE" "0603"
					( Origin gFrontEnd )
				)
				( attribute "PART_NUMBER" "G22026-003"
					( Origin gFrontEnd )
				)
				( attribute "PHYS_PAGE" "234"
					( Origin gFrontEnd )
				)
				( attribute "REUSE_ID" "34"
					( Origin gFrontEnd )
				)
				( attribute "ROOM" "PVPP_KLM_VR"
					( Origin gFrontEnd )
				)
				( attribute "ROT" "0"
					( Origin gFrontEnd )
				)
				( attribute "SEC" "1"
					( Origin gPackager )
				)
				( attribute "TOLERANCE" "1%"
					( Origin gFrontEnd )
				)
				( attribute "VALUE" "120.0"
					( Origin gFrontEnd )
				)
				( attribute "VER" "2"
					( Origin gFrontEnd )
				)
				( attribute "WATTAGE" "1/10W"
					( Origin gFrontEnd )
				)
				( attribute "XY" "(-2075,3675)"
					( Origin gFrontEnd )
				)
				( attribute "CHIPS_PART_NAME" "RES"
					( Origin gPackager )
				)
				( attribute "CDS_PART_NAME" "RES_0603-120.0,1%,1/10W,CHIP,GA"
					( Origin gPackager )
				)
				( objectStatus "R4B2" )
				( pin "a"
					( attribute "PN" "1"
						( Origin gPackager )
					)
					( objectStatus "R4B2.1" )
				)
				( pin "b"
					( attribute "PN" "2"
						( Origin gPackager )
					)
					( objectStatus "R4B2.2" )
				)
			)
			( gate "@baseboard_fab2_lib.baseboard_fab2(sch_1):page234_i184"
				( attribute "CDS_LIB" "mstr_vreg"
					( Origin gPackager )
				)
				( attribute "CDS_LMAN_SYM_OUTLINE" "-450,850,450,-900"
					( Origin gPackager )
				)
				( attribute "CDS_LOCATION" "EU4A3"
					( Origin gPackager )
				)
				( attribute "CDS_SEC" "1"
					( Origin gPackager )
				)
				( attribute "LOCATION" "EU4A3"
					( Origin gFrontEnd )
				)
				( attribute "MATERIAL" "IC"
					( Origin gFrontEnd )
				)
				( attribute "PACK_TYPE" "SM"
					( Origin gFrontEnd )
				)
				( attribute "PART_NUMBER" "H86355-001"
					( Origin gFrontEnd )
				)
				( attribute "PHYS_PAGE" "234"
					( Origin gFrontEnd )
				)
				( attribute "ROT" "0"
					( Origin gFrontEnd )
				)
				( attribute "SEC" "1"
					( Origin gFrontEnd )
				)
				( attribute "SEC_TYPE" "SM"
					( Origin gFrontEnd )
				)
				( attribute "VER" "1"
					( Origin gFrontEnd )
				)
				( attribute "XY" "(-3800,2875)"
					( Origin gFrontEnd )
				)
				( attribute "CHIPS_PART_NAME" "NCP3232L"
					( Origin gPackager )
				)
				( attribute "CDS_PART_NAME" "NCP3232L_SM-IC,H86355-001"
					( Origin gPackager )
				)
				( objectStatus "EU4A3" )
				( pin "agnd"
					( attribute "PN" "5"
						( Origin gPackager )
					)
					( objectStatus "EU4A3.5" )
				)
				( pin "bst"
					( attribute "PN" "36"
						( Origin gPackager )
					)
					( objectStatus "EU4A3.36" )
				)
				( pin "comp"
					( attribute "PN" "3"
						( Origin gPackager )
					)
					( objectStatus "EU4A3.3" )
				)
				( pin "en"
					( attribute "PN" "40"
						( Origin gPackager )
					)
					( objectStatus "EU4A3.40" )
				)
				( pin "fb"
					( attribute "PN" "2"
						( Origin gPackager )
					)
					( objectStatus "EU4A3.2" )
				)
				( pin "gnd"
					( attribute "PN" "41"
						( Origin gPackager )
					)
					( objectStatus "EU4A3.41" )
				)
				( pin "iset"
					( attribute "PN" "4"
						( Origin gPackager )
					)
					( objectStatus "EU4A3.4" )
				)
				( pin "ots"
					( attribute "PN" "6"
						( Origin gPackager )
					)
					( objectStatus "EU4A3.6" )
				)
				( pin "pg"
					( attribute "PN" "7"
						( Origin gPackager )
					)
					( objectStatus "EU4A3.7" )
				)
				( pin "pgnd(0)"
					( attribute "PN" "16"
						( Origin gPackager )
					)
					( objectStatus "EU4A3.16" )
				)
				( pin "pgnd(1)"
					( attribute "PN" "17"
						( Origin gPackager )
					)
					( objectStatus "EU4A3.17" )
				)
				( pin "pgnd(2)"
					( attribute "PN" "18"
						( Origin gPackager )
					)
					( objectStatus "EU4A3.18" )
				)
				( pin "pgnd(3)"
					( attribute "PN" "19"
						( Origin gPackager )
					)
					( objectStatus "EU4A3.19" )
				)
				( pin "pgnd(4)"
					( attribute "PN" "20"
						( Origin gPackager )
					)
					( objectStatus "EU4A3.20" )
				)
				( pin "pgnd(5)"
					( attribute "PN" "21"
						( Origin gPackager )
					)
					( objectStatus "EU4A3.21" )
				)
				( pin "pgnd(6)"
					( attribute "PN" "22"
						( Origin gPackager )
					)
					( objectStatus "EU4A3.22" )
				)
				( pin "pgnd(7)"
					( attribute "PN" "23"
						( Origin gPackager )
					)
					( objectStatus "EU4A3.23" )
				)
				( pin "pgnd(8)"
					( attribute "PN" "24"
						( Origin gPackager )
					)
					( objectStatus "EU4A3.24" )
				)
				( pin "pgnd(9)"
					( attribute "PN" "25"
						( Origin gPackager )
					)
					( objectStatus "EU4A3.25" )
				)
				( pin "pgnd(10)"
					( attribute "PN" "26"
						( Origin gPackager )
					)
					( objectStatus "EU4A3.26" )
				)
				( pin "pgnd(11)"
					( attribute "PN" "27"
						( Origin gPackager )
					)
					( objectStatus "EU4A3.27" )
				)
				( pin "pgnd(12)"
					( attribute "PN" "28"
						( Origin gPackager )
					)
					( objectStatus "EU4A3.28" )
				)
				( pin "pgnd(13)"
					( attribute "PN" "37"
						( Origin gPackager )
					)
					( objectStatus "EU4A3.37" )
				)
				( pin "ss"
					( attribute "PN" "1"
						( Origin gPackager )
					)
					( objectStatus "EU4A3.1" )
				)
				( pin "vb"
					( attribute "PN" "38"
						( Origin gPackager )
					)
					( objectStatus "EU4A3.38" )
				)
				( pin "vcc"
					( attribute "PN" "39"
						( Origin gPackager )
					)
					( objectStatus "EU4A3.39" )
				)
				( pin "vin(0)"
					( attribute "PN" "8"
						( Origin gPackager )
					)
					( objectStatus "EU4A3.8" )
				)
				( pin "vin(1)"
					( attribute "PN" "9"
						( Origin gPackager )
					)
					( objectStatus "EU4A3.9" )
				)
				( pin "vin(2)"
					( attribute "PN" "10"
						( Origin gPackager )
					)
					( objectStatus "EU4A3.10" )
				)
				( pin "vin(3)"
					( attribute "PN" "11"
						( Origin gPackager )
					)
					( objectStatus "EU4A3.11" )
				)
				( pin "vin(4)"
					( attribute "PN" "12"
						( Origin gPackager )
					)
					( objectStatus "EU4A3.12" )
				)
				( pin "vin(5)"
					( attribute "PN" "13"
						( Origin gPackager )
					)
					( objectStatus "EU4A3.13" )
				)
				( pin "vin(6)"
					( attribute "PN" "14"
						( Origin gPackager )
					)
					( objectStatus "EU4A3.14" )
				)
				( pin "vin(7)"
					( attribute "PN" "42"
						( Origin gPackager )
					)
					( objectStatus "EU4A3.42" )
				)
				( pin "vsw"
					( attribute "PN" "35"
						( Origin gPackager )
					)
					( objectStatus "EU4A3.35" )
				)
				( pin "vswh(0)"
					( attribute "PN" "15"
						( Origin gPackager )
					)
					( objectStatus "EU4A3.15" )
				)
				( pin "vswh(1)"
					( attribute "PN" "29"
						( Origin gPackager )
					)
					( objectStatus "EU4A3.29" )
				)
				( pin "vswh(2)"
					( attribute "PN" "30"
						( Origin gPackager )
					)
					( objectStatus "EU4A3.30" )
				)
				( pin "vswh(3)"
					( attribute "PN" "31"
						( Origin gPackager )
					)
					( objectStatus "EU4A3.31" )
				)
				( pin "vswh(4)"
					( attribute "PN" "32"
						( Origin gPackager )
					)
					( objectStatus "EU4A3.32" )
				)
				( pin "vswh(5)"
					( attribute "PN" "33"
						( Origin gPackager )
					)
					( objectStatus "EU4A3.33" )
				)
				( pin "vswh(6)"
					( attribute "PN" "34"
						( Origin gPackager )
					)
					( objectStatus "EU4A3.34" )
				)
				( pin "vswh(7)"
					( attribute "PN" "43"
						( Origin gPackager )
					)
					( objectStatus "EU4A3.43" )
				)
			)
			( gate "@baseboard_fab2_lib.baseboard_fab2(sch_1):page234_i199"
				( attribute "CDS_LIB" "dev_discrete"
					( Origin gPackager )
				)
				( attribute "CDS_LOCATION" "C4A20"
					( Origin gPackager )
				)
				( attribute "CDS_SEC" "1"
					( Origin gPackager )
				)
				( attribute "LOCATION" "C4A20"
					( Origin gFrontEnd )
				)
				( attribute "MATERIAL" "X7R"
					( Origin gFrontEnd )
				)
				( attribute "PACK_TYPE" "0402V"
					( Origin gFrontEnd )
				)
				( attribute "PART_NUMBER" "A36096-030"
					( Origin gFrontEnd )
				)
				( attribute "PHYS_PAGE" "234"
					( Origin gFrontEnd )
				)
				( attribute "ROT" "0"
					( Origin gFrontEnd )
				)
				( attribute "SEC" "1"
					( Origin gFrontEnd )
				)
				( attribute "SEC_TYPE" "0402V"
					( Origin gFrontEnd )
				)
				( attribute "TOLERANCE" "10%"
					( Origin gFrontEnd )
				)
				( attribute "VALUE" "0.1UF"
					( Origin gFrontEnd )
				)
				( attribute "VER" "1"
					( Origin gFrontEnd )
				)
				( attribute "VOLTAGE" "16V"
					( Units "uVoltage" "V" 1.000000)
					( Origin gFrontEnd )
				)
				( attribute "XY" "(-5175,3525)"
					( Origin gFrontEnd )
				)
				( attribute "CHIPS_PART_NAME" "CAP_A"
					( Origin gPackager )
				)
				( attribute "CDS_PART_NAME" "CAP_A_0402V-0.1UF,16V,10%,X7R,A"
					( Origin gPackager )
				)
				( objectStatus "C4A20" )
				( pin "a"
					( attribute "PN" "1"
						( Origin gPackager )
					)
					( objectStatus "C4A20.1" )
				)
				( pin "b"
					( attribute "PN" "2"
						( Origin gPackager )
					)
					( objectStatus "C4A20.2" )
				)
			)
			( gate "@baseboard_fab2_lib.baseboard_fab2(sch_1):page234_i201"
				( attribute "CDS_LIB" "mstr_discrete"
					( Origin gPackager )
				)
				( attribute "CDS_LOCATION" "R4B7"
					( Origin gPackager )
				)
				( attribute "CDS_SEC" "1"
					( Origin gPackager )
				)
				( attribute "LOCATION" "R4B7"
					( Origin gFrontEnd )
				)
				( attribute "MATERIAL" "CHIP"
					( Origin gFrontEnd )
				)
				( attribute "PACK_TYPE" "0402"
					( Origin gFrontEnd )
				)
				( attribute "PART_NUMBER" "G21796-250"
					( Origin gFrontEnd )
				)
				( attribute "PHYS_PAGE" "234"
					( Origin gFrontEnd )
				)
				( attribute "ROOM" "PVPP_KLM_VR"
					( Origin gFrontEnd )
				)
				( attribute "ROT" "0"
					( Origin gFrontEnd )
				)
				( attribute "SEC" "1"
					( Origin gFrontEnd )
				)
				( attribute "SEC_TYPE" "0402"
					( Origin gFrontEnd )
				)
				( attribute "TOLERANCE" "1.0%"
					( Origin gFrontEnd )
				)
				( attribute "VALUE" "22.1"
					( Origin gFrontEnd )
				)
				( attribute "VER" "1"
					( Origin gFrontEnd )
				)
				( attribute "WATTAGE" "1/16W"
					( Origin gFrontEnd )
				)
				( attribute "XY" "(-3350,975)"
					( Origin gFrontEnd )
				)
				( attribute "CHIPS_PART_NAME" "RES"
					( Origin gPackager )
				)
				( attribute "CDS_PART_NAME" "RES_0402-22.1,1.0%,1/16W,CHIP,A"
					( Origin gPackager )
				)
				( objectStatus "R4B7" )
				( pin "a"
					( attribute "PN" "1"
						( Origin gPackager )
					)
					( objectStatus "R4B7.1" )
				)
				( pin "b"
					( attribute "PN" "2"
						( Origin gPackager )
					)
					( objectStatus "R4B7.2" )
				)
			)
			( gate "@baseboard_fab2_lib.baseboard_fab2(sch_1):page234_i202"
				( attribute "CDS_LIB" "mstr_discrete"
					( Origin gPackager )
				)
				( attribute "CDS_LOCATION" "C6L10"
					( Origin gPackager )
				)
				( attribute "CDS_SEC" "1"
					( Origin gPackager )
				)
				( attribute "LOCATION" "C6L10"
					( Origin gFrontEnd )
				)
				( attribute "MATERIAL" "X6S"
					( Origin gFrontEnd )
				)
				( attribute "PACK_TYPE" "0805"
					( Origin gFrontEnd )
				)
				( attribute "PART_NUMBER" "C95333-007"
					( Origin gFrontEnd )
				)
				( attribute "PHYS_PAGE" "234"
					( Origin gFrontEnd )
				)
				( attribute "ROT" "0"
					( Origin gFrontEnd )
				)
				( attribute "SEC" "1"
					( Origin gFrontEnd )
				)
				( attribute "SEC_TYPE" "0805"
					( Origin gFrontEnd )
				)
				( attribute "TOLERANCE" "10%"
					( Origin gFrontEnd )
				)
				( attribute "VALUE" "10UF"
					( Origin gFrontEnd )
				)
				( attribute "VER" "1"
					( Origin gFrontEnd )
				)
				( attribute "VOLTAGE" "16V"
					( Units "uVoltage" "V" 1.000000)
					( Origin gFrontEnd )
				)
				( attribute "XY" "(-6875,4100)"
					( Origin gFrontEnd )
				)
				( attribute "CHIPS_PART_NAME" "CAP"
					( Origin gPackager )
				)
				( attribute "CDS_PART_NAME" "CAP_0805-10UF,16V,10%,X6S,C953A"
					( Origin gPackager )
				)
				( objectStatus "C6L10" )
				( pin "a"
					( attribute "PN" "1"
						( Origin gPackager )
					)
					( objectStatus "C6L10.1" )
				)
				( pin "b"
					( attribute "PN" "2"
						( Origin gPackager )
					)
					( objectStatus "C6L10.2" )
				)
			)
			( gate "@baseboard_fab2_lib.baseboard_fab2(sch_1):page234_i203"
				( attribute "CDS_LIB" "mstr_discrete"
					( Origin gPackager )
				)
				( attribute "CDS_LOCATION" "C6M3"
					( Origin gPackager )
				)
				( attribute "CDS_SEC" "1"
					( Origin gPackager )
				)
				( attribute "LOCATION" "C6M3"
					( Origin gFrontEnd )
				)
				( attribute "MATERIAL" "X6S"
					( Origin gFrontEnd )
				)
				( attribute "PACK_TYPE" "0805"
					( Origin gFrontEnd )
				)
				( attribute "PART_NUMBER" "C95333-007"
					( Origin gFrontEnd )
				)
				( attribute "PHYS_PAGE" "234"
					( Origin gFrontEnd )
				)
				( attribute "ROT" "0"
					( Origin gFrontEnd )
				)
				( attribute "SEC" "1"
					( Origin gFrontEnd )
				)
				( attribute "SEC_TYPE" "0805"
					( Origin gFrontEnd )
				)
				( attribute "TOLERANCE" "10%"
					( Origin gFrontEnd )
				)
				( attribute "VALUE" "10UF"
					( Origin gFrontEnd )
				)
				( attribute "VER" "1"
					( Origin gFrontEnd )
				)
				( attribute "VOLTAGE" "16V"
					( Units "uVoltage" "V" 1.000000)
					( Origin gFrontEnd )
				)
				( attribute "XY" "(-6375,4100)"
					( Origin gFrontEnd )
				)
				( attribute "CHIPS_PART_NAME" "CAP"
					( Origin gPackager )
				)
				( attribute "CDS_PART_NAME" "CAP_0805-10UF,16V,10%,X6S,C953A"
					( Origin gPackager )
				)
				( objectStatus "C6M3" )
				( pin "a"
					( attribute "PN" "1"
						( Origin gPackager )
					)
					( objectStatus "C6M3.1" )
				)
				( pin "b"
					( attribute "PN" "2"
						( Origin gPackager )
					)
					( objectStatus "C6M3.2" )
				)
			)
			( gate "@baseboard_fab2_lib.baseboard_fab2(sch_1):page234_i204"
				( attribute "CDS_LIB" "mstr_discrete"
					( Origin gPackager )
				)
				( attribute "CDS_LOCATION" "C6M5"
					( Origin gPackager )
				)
				( attribute "CDS_SEC" "1"
					( Origin gPackager )
				)
				( attribute "LOCATION" "C6M5"
					( Origin gFrontEnd )
				)
				( attribute "MATERIAL" "X6S"
					( Origin gFrontEnd )
				)
				( attribute "PACK_TYPE" "0805"
					( Origin gFrontEnd )
				)
				( attribute "PART_NUMBER" "C95333-007"
					( Origin gFrontEnd )
				)
				( attribute "PHYS_PAGE" "234"
					( Origin gFrontEnd )
				)
				( attribute "ROT" "0"
					( Origin gFrontEnd )
				)
				( attribute "SEC" "1"
					( Origin gFrontEnd )
				)
				( attribute "SEC_TYPE" "0805"
					( Origin gFrontEnd )
				)
				( attribute "TOLERANCE" "10%"
					( Origin gFrontEnd )
				)
				( attribute "VALUE" "10UF"
					( Origin gFrontEnd )
				)
				( attribute "VER" "1"
					( Origin gFrontEnd )
				)
				( attribute "VOLTAGE" "16V"
					( Units "uVoltage" "V" 1.000000)
					( Origin gFrontEnd )
				)
				( attribute "XY" "(-5925,4100)"
					( Origin gFrontEnd )
				)
				( attribute "CHIPS_PART_NAME" "CAP"
					( Origin gPackager )
				)
				( attribute "CDS_PART_NAME" "CAP_0805-10UF,16V,10%,X6S,C953A"
					( Origin gPackager )
				)
				( objectStatus "C6M5" )
				( pin "a"
					( attribute "PN" "1"
						( Origin gPackager )
					)
					( objectStatus "C6M5.1" )
				)
				( pin "b"
					( attribute "PN" "2"
						( Origin gPackager )
					)
					( objectStatus "C6M5.2" )
				)
			)
			( gate "@baseboard_fab2_lib.baseboard_fab2(sch_1):page234_i205"
				( attribute "CDS_LIB" "mstr_discrete"
					( Origin gPackager )
				)
				( attribute "CDS_LOCATION" "C4A19"
					( Origin gPackager )
				)
				( attribute "CDS_SEC" "1"
					( Origin gPackager )
				)
				( attribute "LOCATION" "C4A19"
					( Origin gFrontEnd )
				)
				( attribute "MATERIAL" "X6S"
					( Origin gFrontEnd )
				)
				( attribute "PACK_TYPE" "0805"
					( Origin gFrontEnd )
				)
				( attribute "PART_NUMBER" "C95333-007"
					( Origin gFrontEnd )
				)
				( attribute "PHYS_PAGE" "234"
					( Origin gFrontEnd )
				)
				( attribute "ROT" "0"
					( Origin gFrontEnd )
				)
				( attribute "SEC" "1"
					( Origin gFrontEnd )
				)
				( attribute "SEC_TYPE" "0805"
					( Origin gFrontEnd )
				)
				( attribute "TOLERANCE" "10%"
					( Origin gFrontEnd )
				)
				( attribute "VALUE" "10UF"
					( Origin gFrontEnd )
				)
				( attribute "VER" "1"
					( Origin gFrontEnd )
				)
				( attribute "VOLTAGE" "16V"
					( Units "uVoltage" "V" 1.000000)
					( Origin gFrontEnd )
				)
				( attribute "XY" "(-5475,4100)"
					( Origin gFrontEnd )
				)
				( attribute "CHIPS_PART_NAME" "CAP"
					( Origin gPackager )
				)
				( attribute "CDS_PART_NAME" "CAP_0805-10UF,16V,10%,X6S,C953A"
					( Origin gPackager )
				)
				( objectStatus "C4A19" )
				( pin "a"
					( attribute "PN" "1"
						( Origin gPackager )
					)
					( objectStatus "C4A19.1" )
				)
				( pin "b"
					( attribute "PN" "2"
						( Origin gPackager )
					)
					( objectStatus "C4A19.2" )
				)
			)
			( gate "@baseboard_fab2_lib.baseboard_fab2(sch_1):page234_i210"
				( attribute "CDS_LIB" "mstr_discrete"
					( Origin gPackager )
				)
				( attribute "CDS_LOCATION" "C6L8"
					( Origin gPackager )
				)
				( attribute "CDS_SEC" "1"
					( Origin gPackager )
				)
				( attribute "LOCATION" "C6L8"
					( Origin gFrontEnd )
				)
				( attribute "MATERIAL" "POSCAP"
					( Origin gFrontEnd )
				)
				( attribute "PACK_TYPE" "7343"
					( Origin gFrontEnd )
				)
				( attribute "PART_NUMBER" "724613-067"
					( Origin gFrontEnd )
				)
				( attribute "PHYS_PAGE" "234"
					( Origin gFrontEnd )
				)
				( attribute "ROT" "0"
					( Origin gFrontEnd )
				)
				( attribute "SEC" "1"
					( Origin gFrontEnd )
				)
				( attribute "SEC_TYPE" "7343"
					( Origin gFrontEnd )
				)
				( attribute "TOLERANCE" "20%"
					( Origin gFrontEnd )
				)
				( attribute "VALUE" "220UF"
					( Origin gFrontEnd )
				)
				( attribute "VER" "1"
					( Origin gFrontEnd )
				)
				( attribute "VOLTAGE" "4V"
					( Units "uVoltage" "V" 1.000000)
					( Origin gFrontEnd )
				)
				( attribute "XY" "(-1425,3675)"
					( Origin gFrontEnd )
				)
				( attribute "CHIPS_PART_NAME" "CAPP"
					( Origin gPackager )
				)
				( attribute "CDS_PART_NAME" "CAPP_7343-220UF,4V,20%,POSCAP,A"
					( Origin gPackager )
				)
				( objectStatus "C6L8" )
				( pin "a"
					( attribute "PN" "1"
						( Origin gPackager )
					)
					( objectStatus "C6L8.1" )
				)
				( pin "b"
					( attribute "PN" "2"
						( Origin gPackager )
					)
					( objectStatus "C6L8.2" )
				)
			)
			( gate "@baseboard_fab2_lib.baseboard_fab2(sch_1):page234_i211"
				( attribute "BOM_COST" "PVPP_KLM_VR"
					( Origin gFrontEnd )
				)
				( attribute "CDS_LIB" "mstr_discrete"
					( Origin gPackager )
				)
				( attribute "CDS_LOCATION" "C4B9"
					( Origin gPackager )
				)
				( attribute "CDS_SEC" "1"
					( Origin gPackager )
				)
				( attribute "LOCATION" "C4B9"
					( Origin gFrontEnd )
				)
				( attribute "MATERIAL" "X7R"
					( Origin gFrontEnd )
				)
				( attribute "PACK_TYPE" "0402LF"
					( Origin gFrontEnd )
				)
				( attribute "PART_NUMBER" "A36096-075"
					( Origin gFrontEnd )
				)
				( attribute "PHYS_PAGE" "234"
					( Origin gFrontEnd )
				)
				( attribute "REUSE_ID" "27"
					( Origin gFrontEnd )
				)
				( attribute "ROOM" "PVPP_KLM_VR"
					( Origin gFrontEnd )
				)
				( attribute "ROT" "2"
					( Origin gFrontEnd )
				)
				( attribute "SEC" "1"
					( Origin gFrontEnd )
				)
				( attribute "SEC_TYPE" "0402LF"
					( Origin gFrontEnd )
				)
				( attribute "TOLERANCE" "10%"
					( Origin gFrontEnd )
				)
				( attribute "VALUE" "2200PF"
					( Origin gFrontEnd )
				)
				( attribute "VER" "2"
					( Origin gFrontEnd )
				)
				( attribute "VOLTAGE" "50V"
					( Units "uVoltage" "V" 1.000000)
					( Origin gFrontEnd )
				)
				( attribute "XY" "(-2850,2450)"
					( Origin gFrontEnd )
				)
				( attribute "CHIPS_PART_NAME" "CAP"
					( Origin gPackager )
				)
				( attribute "CDS_PART_NAME" "CAP_0402LF-2200PF,50V,10%,X7R,A"
					( Origin gPackager )
				)
				( objectStatus "C4B9" )
				( pin "a"
					( attribute "PN" "1"
						( Origin gPackager )
					)
					( objectStatus "C4B9.1" )
				)
				( pin "b"
					( attribute "PN" "2"
						( Origin gPackager )
					)
					( objectStatus "C4B9.2" )
				)
			)
			( gate "@baseboard_fab2_lib.baseboard_fab2(sch_1):page234_i212"
				( attribute "BOM_COST" "PVPP_KLM_VR"
					( Origin gFrontEnd )
				)
				( attribute "CDS_LIB" "mstr_discrete"
					( Origin gPackager )
				)
				( attribute "CDS_LOCATION" "C4B4"
					( Origin gPackager )
				)
				( attribute "CDS_SEC" "1"
					( Origin gPackager )
				)
				( attribute "LOCATION" "C4B4"
					( Origin gFrontEnd )
				)
				( attribute "MATERIAL" "COG"
					( Origin gFrontEnd )
				)
				( attribute "PACK_TYPE" "0402LF"
					( Origin gFrontEnd )
				)
				( attribute "PART_NUMBER" "A36095-026"
					( Origin gFrontEnd )
				)
				( attribute "PHYS_PAGE" "234"
					( Origin gFrontEnd )
				)
				( attribute "REUSE_ID" "27"
					( Origin gFrontEnd )
				)
				( attribute "ROOM" "PVPP_KLM_VR"
					( Origin gFrontEnd )
				)
				( attribute "ROT" "2"
					( Origin gFrontEnd )
				)
				( attribute "SEC" "1"
					( Origin gFrontEnd )
				)
				( attribute "SEC_TYPE" "0402LF"
					( Origin gFrontEnd )
				)
				( attribute "TOLERANCE" "5%"
					( Origin gFrontEnd )
				)
				( attribute "VALUE" "100.0PF"
					( Origin gFrontEnd )
				)
				( attribute "VER" "2"
					( Origin gFrontEnd )
				)
				( attribute "VOLTAGE" "50V"
					( Units "uVoltage" "V" 1.000000)
					( Origin gFrontEnd )
				)
				( attribute "XY" "(-2425,2825)"
					( Origin gFrontEnd )
				)
				( attribute "CHIPS_PART_NAME" "CAP"
					( Origin gPackager )
				)
				( attribute "CDS_PART_NAME" "CAP_0402LF-100.0PF,50V,5%,COG,A"
					( Origin gPackager )
				)
				( objectStatus "C4B4" )
				( pin "a"
					( attribute "PN" "1"
						( Origin gPackager )
					)
					( objectStatus "C4B4.1" )
				)
				( pin "b"
					( attribute "PN" "2"
						( Origin gPackager )
					)
					( objectStatus "C4B4.2" )
				)
			)
			( gate "@baseboard_fab2_lib.baseboard_fab2(sch_1):page234_i213"
				( attribute "BOM_COST" "PVPP_KLM_VR"
					( Origin gFrontEnd )
				)
				( attribute "CDS_LIB" "mstr_discrete"
					( Origin gPackager )
				)
				( attribute "CDS_LOCATION" "R4B8"
					( Origin gPackager )
				)
				( attribute "CDS_SEC" "1"
					( Origin gPackager )
				)
				( attribute "LOCATION" "R4B8"
					( Origin gFrontEnd )
				)
				( attribute "MATERIAL" "CHIP"
					( Origin gFrontEnd )
				)
				( attribute "PACK_TYPE" "0402"
					( Origin gFrontEnd )
				)
				( attribute "PART_NUMBER" "G21796-242"
					( Origin gFrontEnd )
				)
				( attribute "PHYS_PAGE" "234"
					( Origin gFrontEnd )
				)
				( attribute "REUSE_ID" "13"
					( Origin gFrontEnd )
				)
				( attribute "ROOM" "PVPP_KLM_VR"
					( Origin gFrontEnd )
				)
				( attribute "ROT" "0"
					( Origin gFrontEnd )
				)
				( attribute "SEC" "1"
					( Origin gFrontEnd )
				)
				( attribute "SEC_TYPE" "0402"
					( Origin gFrontEnd )
				)
				( attribute "TOLERANCE" "1.0%"
					( Origin gFrontEnd )
				)
				( attribute "VALUE" "7.87K"
					( Origin gFrontEnd )
				)
				( attribute "VER" "1"
					( Origin gFrontEnd )
				)
				( attribute "WATTAGE" "1/16W"
					( Origin gFrontEnd )
				)
				( attribute "XY" "(-2150,2450)"
					( Origin gFrontEnd )
				)
				( attribute "CHIPS_PART_NAME" "RES"
					( Origin gPackager )
				)
				( attribute "CDS_PART_NAME" "RES_0402-7.87K,1.0%,1/16W,CHIPA"
					( Origin gPackager )
				)
				( objectStatus "R4B8" )
				( pin "a"
					( attribute "PN" "1"
						( Origin gPackager )
					)
					( objectStatus "R4B8.1" )
				)
				( pin "b"
					( attribute "PN" "2"
						( Origin gPackager )
					)
					( objectStatus "R4B8.2" )
				)
			)
			( gate "@baseboard_fab2_lib.baseboard_fab2(sch_1):page234_i214"
				( attribute "CDS_LIB" "mstr_discrete"
					( Origin gPackager )
				)
				( attribute "CDS_LOCATION" "R4B3"
					( Origin gPackager )
				)
				( attribute "CDS_SEC" "1"
					( Origin gPackager )
				)
				( attribute "LOCATION" "R4B3"
					( Origin gFrontEnd )
				)
				( attribute "MATERIAL" "CHIP"
					( Origin gFrontEnd )
				)
				( attribute "PACK_TYPE" "0402"
					( Origin gFrontEnd )
				)
				( attribute "PART_NUMBER" "G21497-005"
					( Origin gFrontEnd )
				)
				( attribute "PHYS_PAGE" "234"
					( Origin gFrontEnd )
				)
				( attribute "ROOM" "PVPP_KLM_VR"
					( Origin gFrontEnd )
				)
				( attribute "ROT" "5"
					( Origin gFrontEnd )
				)
				( attribute "SEC" "1"
					( Origin gFrontEnd )
				)
				( attribute "SEC_TYPE" "0402"
					( Origin gFrontEnd )
				)
				( attribute "SPOF" "TRUE"
					( Origin gFrontEnd )
				)
				( attribute "TOLERANCE" "5%"
					( Origin gFrontEnd )
				)
				( attribute "VALUE" "0.0"
					( Origin gFrontEnd )
				)
				( attribute "VER" "1"
					( Origin gFrontEnd )
				)
				( attribute "WATTAGE" "1/16W"
					( Origin gFrontEnd )
				)
				( attribute "XY" "(-1350,2925)"
					( Origin gFrontEnd )
				)
				( attribute "CHIPS_PART_NAME" "RES"
					( Origin gPackager )
				)
				( attribute "CDS_PART_NAME" "RES_0402-0.0,5%,1/16W,CHIP,G21A"
					( Origin gPackager )
				)
				( objectStatus "R4B3" )
				( pin "a"
					( attribute "PN" "1"
						( Origin gPackager )
					)
					( objectStatus "R4B3.1" )
				)
				( pin "b"
					( attribute "PN" "2"
						( Origin gPackager )
					)
					( objectStatus "R4B3.2" )
				)
			)
			( gate "@baseboard_fab2_lib.baseboard_fab2(sch_1):page234_i215"
				( attribute "BOM_COST" "PVPP_KLM_VR"
					( Origin gFrontEnd )
				)
				( attribute "CDS_LIB" "mstr_discrete"
					( Origin gPackager )
				)
				( attribute "CDS_LOCATION" "R4B5"
					( Origin gPackager )
				)
				( attribute "CDS_SEC" "1"
					( Origin gPackager )
				)
				( attribute "LOCATION" "R4B5"
					( Origin gFrontEnd )
				)
				( attribute "MATERIAL" "CHIP"
					( Origin gFrontEnd )
				)
				( attribute "PACK_TYPE" "0402"
					( Origin gFrontEnd )
				)
				( attribute "PART_NUMBER" "G21796-040"
					( Origin gFrontEnd )
				)
				( attribute "PHYS_PAGE" "234"
					( Origin gFrontEnd )
				)
				( attribute "REUSE_ID" "9"
					( Origin gFrontEnd )
				)
				( attribute "ROOM" "PVPP_KLM_VR"
					( Origin gFrontEnd )
				)
				( attribute "ROT" "0"
					( Origin gFrontEnd )
				)
				( attribute "SEC" "1"
					( Origin gPackager )
				)
				( attribute "SPOF" "TRUE"
					( Origin gFrontEnd )
				)
				( attribute "TOLERANCE" "1%"
					( Origin gFrontEnd )
				)
				( attribute "VALUE" "20.0K"
					( Origin gFrontEnd )
				)
				( attribute "VER" "2"
					( Origin gFrontEnd )
				)
				( attribute "WATTAGE" "1/16W"
					( Origin gFrontEnd )
				)
				( attribute "XY" "(-1350,2175)"
					( Origin gFrontEnd )
				)
				( attribute "CHIPS_PART_NAME" "RES"
					( Origin gPackager )
				)
				( attribute "CDS_PART_NAME" "RES_0402-20.0K,1%,1/16W,CHIP,GA"
					( Origin gPackager )
				)
				( objectStatus "R4B5" )
				( pin "a"
					( attribute "PN" "1"
						( Origin gPackager )
					)
					( objectStatus "R4B5.1" )
				)
				( pin "b"
					( attribute "PN" "2"
						( Origin gPackager )
					)
					( objectStatus "R4B5.2" )
				)
			)
			( gate "@baseboard_fab2_lib.baseboard_fab2(sch_1):page234_i216"
				( attribute "BOM_COST" "PVPP_KLM_VR"
					( Origin gFrontEnd )
				)
				( attribute "CDS_LIB" "mstr_discrete"
					( Origin gPackager )
				)
				( attribute "CDS_LOCATION" "R4B4"
					( Origin gPackager )
				)
				( attribute "CDS_SEC" "1"
					( Origin gPackager )
				)
				( attribute "LOCATION" "R4B4"
					( Origin gFrontEnd )
				)
				( attribute "MATERIAL" "CHIP"
					( Origin gFrontEnd )
				)
				( attribute "PACK_TYPE" "0402"
					( Origin gFrontEnd )
				)
				( attribute "PART_NUMBER" "G21796-146"
					( Origin gFrontEnd )
				)
				( attribute "PHYS_PAGE" "234"
					( Origin gFrontEnd )
				)
				( attribute "REUSE_ID" "7"
					( Origin gFrontEnd )
				)
				( attribute "ROOM" "PVPP_KLM_VR"
					( Origin gFrontEnd )
				)
				( attribute "ROT" "0"
					( Origin gFrontEnd )
				)
				( attribute "SEC" "1"
					( Origin gPackager )
				)
				( attribute "SPOF" "TRUE"
					( Origin gFrontEnd )
				)
				( attribute "TOLERANCE" "1%"
					( Origin gFrontEnd )
				)
				( attribute "VALUE" "6.34K"
					( Origin gFrontEnd )
				)
				( attribute "VER" "2"
					( Origin gFrontEnd )
				)
				( attribute "WATTAGE" "1/16W"
					( Origin gFrontEnd )
				)
				( attribute "XY" "(-1350,1550)"
					( Origin gFrontEnd )
				)
				( attribute "CHIPS_PART_NAME" "RES"
					( Origin gPackager )
				)
				( attribute "CDS_PART_NAME" "RES_0402-6.34K,1%,1/16W,CHIP,GA"
					( Origin gPackager )
				)
				( objectStatus "R4B4" )
				( pin "a"
					( attribute "PN" "1"
						( Origin gPackager )
					)
					( objectStatus "R4B4.1" )
				)
				( pin "b"
					( attribute "PN" "2"
						( Origin gPackager )
					)
					( objectStatus "R4B4.2" )
				)
			)
			( gate "@baseboard_fab2_lib.baseboard_fab2(sch_1):page234_i218"
				( attribute "BOM_COST" "PVPP_KLM_VR"
					( Origin gFrontEnd )
				)
				( attribute "CDS_LIB" "mstr_discrete"
					( Origin gPackager )
				)
				( attribute "CDS_LOCATION" "C4B7"
					( Origin gPackager )
				)
				( attribute "CDS_SEC" "1"
					( Origin gPackager )
				)
				( attribute "LOCATION" "C4B7"
					( Origin gFrontEnd )
				)
				( attribute "MATERIAL" "X7R"
					( Origin gFrontEnd )
				)
				( attribute "PACK_TYPE" "0402LF"
					( Origin gFrontEnd )
				)
				( attribute "PART_NUMBER" "A36096-075"
					( Origin gFrontEnd )
				)
				( attribute "PHYS_PAGE" "234"
					( Origin gFrontEnd )
				)
				( attribute "REUSE_ID" "26"
					( Origin gFrontEnd )
				)
				( attribute "ROOM" "PVPP_KLM_VR"
					( Origin gFrontEnd )
				)
				( attribute "ROT" "0"
					( Origin gFrontEnd )
				)
				( attribute "SEC" "1"
					( Origin gFrontEnd )
				)
				( attribute "SEC_TYPE" "0402LF"
					( Origin gFrontEnd )
				)
				( attribute "SPOF" "TRUE"
					( Origin gFrontEnd )
				)
				( attribute "TOLERANCE" "10%"
					( Origin gFrontEnd )
				)
				( attribute "VALUE" "2200PF"
					( Origin gFrontEnd )
				)
				( attribute "VER" "1"
					( Origin gFrontEnd )
				)
				( attribute "VOLTAGE" "50V"
					( Units "uVoltage" "V" 1.000000)
					( Origin gFrontEnd )
				)
				( attribute "XY" "(-1025,2075)"
					( Origin gFrontEnd )
				)
				( attribute "CHIPS_PART_NAME" "CAP"
					( Origin gPackager )
				)
				( attribute "CDS_PART_NAME" "CAP_0402LF-2200PF,50V,10%,X7R,A"
					( Origin gPackager )
				)
				( objectStatus "C4B7" )
				( pin "a"
					( attribute "PN" "1"
						( Origin gPackager )
					)
					( objectStatus "C4B7.1" )
				)
				( pin "b"
					( attribute "PN" "2"
						( Origin gPackager )
					)
					( objectStatus "C4B7.2" )
				)
			)
			( gate "@baseboard_fab2_lib.baseboard_fab2(sch_1):page234_i219"
				( attribute "BOM_COST" "PVPP_KLM_VR"
					( Origin gFrontEnd )
				)
				( attribute "CDS_LIB" "mstr_discrete"
					( Origin gPackager )
				)
				( attribute "CDS_LOCATION" "R4B9"
					( Origin gPackager )
				)
				( attribute "CDS_SEC" "1"
					( Origin gPackager )
				)
				( attribute "LOCATION" "R4B9"
					( Origin gFrontEnd )
				)
				( attribute "MATERIAL" "CHIP"
					( Origin gFrontEnd )
				)
				( attribute "PACK_TYPE" "0402"
					( Origin gFrontEnd )
				)
				( attribute "PART_NUMBER" "G85996-004"
					( Origin gFrontEnd )
				)
				( attribute "PHYS_PAGE" "234"
					( Origin gFrontEnd )
				)
				( attribute "REUSE_ID" "9"
					( Origin gFrontEnd )
				)
				( attribute "ROOM" "PVPP_KLM_VR"
					( Origin gFrontEnd )
				)
				( attribute "ROT" "0"
					( Origin gFrontEnd )
				)
				( attribute "SEC" "1"
					( Origin gFrontEnd )
				)
				( attribute "SEC_TYPE" "0402"
					( Origin gFrontEnd )
				)
				( attribute "SPOF" "TRUE"
					( Origin gFrontEnd )
				)
				( attribute "TOLERANCE" "0.1%"
					( Origin gFrontEnd )
				)
				( attribute "VALUE" "1.0K"
					( Origin gFrontEnd )
				)
				( attribute "VER" "2"
					( Origin gFrontEnd )
				)
				( attribute "WATTAGE" "1/16W"
					( Origin gFrontEnd )
				)
				( attribute "XY" "(-1025,2625)"
					( Origin gFrontEnd )
				)
				( attribute "CHIPS_PART_NAME" "RES"
					( Origin gPackager )
				)
				( attribute "CDS_PART_NAME" "RES_0402-1.0K,0.1%,1/16W,CHIP,A"
					( Origin gPackager )
				)
				( objectStatus "R4B9" )
				( pin "a"
					( attribute "PN" "1"
						( Origin gPackager )
					)
					( objectStatus "R4B9.1" )
				)
				( pin "b"
					( attribute "PN" "2"
						( Origin gPackager )
					)
					( objectStatus "R4B9.2" )
				)
			)
			( gate "@baseboard_fab2_lib.baseboard_fab2(sch_1):page234_i220"
				( attribute "CDS_LIB" "mstr_discrete"
					( Origin gPackager )
				)
				( attribute "CDS_LOCATION" "R4B1"
					( Origin gPackager )
				)
				( attribute "CDS_SEC" "1"
					( Origin gPackager )
				)
				( attribute "LOCATION" "R4B1"
					( Origin gFrontEnd )
				)
				( attribute "MATERIAL" "CHIP"
					( Origin gFrontEnd )
				)
				( attribute "PACK_TYPE" "0402"
					( Origin gFrontEnd )
				)
				( attribute "PART_NUMBER" "G21497-005"
					( Origin gFrontEnd )
				)
				( attribute "PHYS_PAGE" "234"
					( Origin gFrontEnd )
				)
				( attribute "ROOM" "PVCCIN_CPU0_VR"
					( Origin gFrontEnd )
				)
				( attribute "ROT" "0"
					( Origin gFrontEnd )
				)
				( attribute "SEC" "1"
					( Origin gPackager )
				)
				( attribute "TOLERANCE" "5%"
					( Origin gFrontEnd )
				)
				( attribute "VALUE" "0.0"
					( Origin gFrontEnd )
				)
				( attribute "VER" "1"
					( Origin gFrontEnd )
				)
				( attribute "WATTAGE" "1/16W"
					( Origin gFrontEnd )
				)
				( attribute "XY" "(-5925,2825)"
					( Origin gFrontEnd )
				)
				( attribute "CHIPS_PART_NAME" "RES"
					( Origin gPackager )
				)
				( attribute "CDS_PART_NAME" "RES_0402-0.0,5%,1/16W,CHIP,G21A"
					( Origin gPackager )
				)
				( objectStatus "R4B1" )
				( pin "a"
					( attribute "PN" "1"
						( Origin gPackager )
					)
					( objectStatus "R4B1.1" )
				)
				( pin "b"
					( attribute "PN" "2"
						( Origin gPackager )
					)
					( objectStatus "R4B1.2" )
				)
			)
			( gate "@baseboard_fab2_lib.baseboard_fab2(sch_1):page235_i143"
				( attribute "CDS_LIB" "dev_discrete"
					( Origin gPackager )
				)
				( attribute "CDS_LOCATION" "C8A7"
					( Origin gPackager )
				)
				( attribute "CDS_SEC" "1"
					( Origin gPackager )
				)
				( attribute "LOCATION" "C8A7"
					( Origin gFrontEnd )
				)
				( attribute "MATERIAL" "X6S"
					( Origin gFrontEnd )
				)
				( attribute "PACK_TYPE" "0402V"
					( Origin gFrontEnd )
				)
				( attribute "PART_NUMBER" "D97712-004"
					( Origin gFrontEnd )
				)
				( attribute "PHYS_PAGE" "235"
					( Origin gFrontEnd )
				)
				( attribute "ROOM" "PVNN_PCH_STBY"
					( Origin gFrontEnd )
				)
				( attribute "ROT" "0"
					( Origin gFrontEnd )
				)
				( attribute "SEC" "1"
					( Origin gFrontEnd )
				)
				( attribute "SEC_TYPE" "0402V"
					( Origin gFrontEnd )
				)
				( attribute "TOLERANCE" "10%"
					( Origin gFrontEnd )
				)
				( attribute "VALUE" "1.0UF"
					( Origin gFrontEnd )
				)
				( attribute "VER" "1"
					( Origin gFrontEnd )
				)
				( attribute "VOLTAGE" "6.3V"
					( Units "uVoltage" "V" 1.000000)
					( Origin gFrontEnd )
				)
				( attribute "XY" "(-8800,1925)"
					( Origin gFrontEnd )
				)
				( attribute "CHIPS_PART_NAME" "CAP_A"
					( Origin gPackager )
				)
				( attribute "CDS_PART_NAME" "CAP_A_0402V-1.0UF,6.3V,10%,X6SA"
					( Origin gPackager )
				)
				( objectStatus "C8A7" )
				( pin "a"
					( attribute "PN" "1"
						( Origin gPackager )
					)
					( objectStatus "C8A7.1" )
				)
				( pin "b"
					( attribute "PN" "2"
						( Origin gPackager )
					)
					( objectStatus "C8A7.2" )
				)
			)
			( gate "@baseboard_fab2_lib.baseboard_fab2(sch_1):page235_i145"
				( attribute "CDS_LIB" "dev_discrete"
					( Origin gPackager )
				)
				( attribute "CDS_LOCATION" "C8A8"
					( Origin gPackager )
				)
				( attribute "CDS_SEC" "1"
					( Origin gPackager )
				)
				( attribute "LOCATION" "C8A8"
					( Origin gFrontEnd )
				)
				( attribute "MATERIAL" "X7R"
					( Origin gFrontEnd )
				)
				( attribute "PACK_TYPE" "0402V"
					( Origin gFrontEnd )
				)
				( attribute "PART_NUMBER" "A36096-030"
					( Origin gFrontEnd )
				)
				( attribute "PHYS_PAGE" "235"
					( Origin gFrontEnd )
				)
				( attribute "ROOM" "PVNN_PCH_STBY"
					( Origin gFrontEnd )
				)
				( attribute "ROT" "0"
					( Origin gFrontEnd )
				)
				( attribute "SEC" "1"
					( Origin gFrontEnd )
				)
				( attribute "SEC_TYPE" "0402V"
					( Origin gFrontEnd )
				)
				( attribute "TOLERANCE" "10%"
					( Origin gFrontEnd )
				)
				( attribute "VALUE" "0.1UF"
					( Origin gFrontEnd )
				)
				( attribute "VER" "1"
					( Origin gFrontEnd )
				)
				( attribute "VOLTAGE" "16V"
					( Units "uVoltage" "V" 1.000000)
					( Origin gFrontEnd )
				)
				( attribute "XY" "(-9200,1975)"
					( Origin gFrontEnd )
				)
				( attribute "CHIPS_PART_NAME" "CAP_A"
					( Origin gPackager )
				)
				( attribute "CDS_PART_NAME" "CAP_A_0402V-0.1UF,16V,10%,X7R,A"
					( Origin gPackager )
				)
				( objectStatus "C8A8" )
				( pin "a"
					( attribute "PN" "1"
						( Origin gPackager )
					)
					( objectStatus "C8A8.1" )
				)
				( pin "b"
					( attribute "PN" "2"
						( Origin gPackager )
					)
					( objectStatus "C8A8.2" )
				)
			)
			( gate "@baseboard_fab2_lib.baseboard_fab2(sch_1):page235_i147"
				( attribute "CDS_LIB" "mstr_discrete"
					( Origin gPackager )
				)
				( attribute "CDS_LOCATION" "R2L16"
					( Origin gPackager )
				)
				( attribute "CDS_SEC" "1"
					( Origin gPackager )
				)
				( attribute "LOCATION" "R2L16"
					( Origin gFrontEnd )
				)
				( attribute "MATERIAL" "CHIP"
					( Origin gFrontEnd )
				)
				( attribute "PACK_TYPE" "0402"
					( Origin gFrontEnd )
				)
				( attribute "PART_NUMBER" "G21796-250"
					( Origin gFrontEnd )
				)
				( attribute "PHYS_PAGE" "235"
					( Origin gFrontEnd )
				)
				( attribute "ROOM" "PVNN_PCH_STBY"
					( Origin gFrontEnd )
				)
				( attribute "ROT" "0"
					( Origin gFrontEnd )
				)
				( attribute "SEC" "1"
					( Origin gFrontEnd )
				)
				( attribute "SEC_TYPE" "0402"
					( Origin gFrontEnd )
				)
				( attribute "TOLERANCE" "1.0%"
					( Origin gFrontEnd )
				)
				( attribute "VALUE" "22.1"
					( Origin gFrontEnd )
				)
				( attribute "VER" "1"
					( Origin gFrontEnd )
				)
				( attribute "WATTAGE" "1/16W"
					( Origin gFrontEnd )
				)
				( attribute "XY" "(-7100,4500)"
					( Origin gFrontEnd )
				)
				( attribute "CHIPS_PART_NAME" "RES"
					( Origin gPackager )
				)
				( attribute "CDS_PART_NAME" "RES_0402-22.1,1.0%,1/16W,CHIP,A"
					( Origin gPackager )
				)
				( objectStatus "R2L16" )
				( pin "a"
					( attribute "PN" "1"
						( Origin gPackager )
					)
					( objectStatus "R2L16.1" )
				)
				( pin "b"
					( attribute "PN" "2"
						( Origin gPackager )
					)
					( objectStatus "R2L16.2" )
				)
			)
			( gate "@baseboard_fab2_lib.baseboard_fab2(sch_1):page235_i148"
				( attribute "CDS_LIB" "mstr_discrete"
					( Origin gPackager )
				)
				( attribute "CDS_LOCATION" "R2L24"
					( Origin gPackager )
				)
				( attribute "CDS_SEC" "1"
					( Origin gPackager )
				)
				( attribute "LOCATION" "R2L24"
					( Origin gFrontEnd )
				)
				( attribute "MATERIAL" "EMPTY"
					( Origin gFrontEnd )
				)
				( attribute "PACK_TYPE" "0402"
					( Origin gFrontEnd )
				)
				( attribute "PART_NUMBER" "G21796-311"
					( Origin gFrontEnd )
				)
				( attribute "PHYS_PAGE" "235"
					( Origin gFrontEnd )
				)
				( attribute "ROOM" "PVNN_PCH_STBY"
					( Origin gFrontEnd )
				)
				( attribute "ROT" "0"
					( Origin gFrontEnd )
				)
				( attribute "SEC" "1"
					( Origin gFrontEnd )
				)
				( attribute "SEC_TYPE" "0402"
					( Origin gFrontEnd )
				)
				( attribute "TOLERANCE" "1.0%"
					( Origin gFrontEnd )
				)
				( attribute "VALUE" "2.26K"
					( Origin gFrontEnd )
				)
				( attribute "VER" "2"
					( Origin gFrontEnd )
				)
				( attribute "WATTAGE" "1/16W"
					( Origin gFrontEnd )
				)
				( attribute "XY" "(-8525,4800)"
					( Origin gFrontEnd )
				)
				( attribute "CHIPS_PART_NAME" "RES"
					( Origin gPackager )
				)
				( attribute "CDS_PART_NAME" "RES_0402-2.26K,1.0%,1/16W,EMPTA"
					( Origin gPackager )
				)
				( objectStatus "R2L24" )
				( pin "a"
					( attribute "PN" "1"
						( Origin gPackager )
					)
					( objectStatus "R2L24.1" )
				)
				( pin "b"
					( attribute "PN" "2"
						( Origin gPackager )
					)
					( objectStatus "R2L24.2" )
				)
			)
			( gate "@baseboard_fab2_lib.baseboard_fab2(sch_1):page235_i149"
				( attribute "CDS_LIB" "mstr_discrete"
					( Origin gPackager )
				)
				( attribute "CDS_LOCATION" "R8A6"
					( Origin gPackager )
				)
				( attribute "CDS_SEC" "1"
					( Origin gPackager )
				)
				( attribute "LOCATION" "R8A6"
					( Origin gFrontEnd )
				)
				( attribute "MATERIAL" "CHIP"
					( Origin gFrontEnd )
				)
				( attribute "PACK_TYPE" "0402"
					( Origin gFrontEnd )
				)
				( attribute "PART_NUMBER" "G21796-026"
					( Origin gFrontEnd )
				)
				( attribute "PHYS_PAGE" "235"
					( Origin gFrontEnd )
				)
				( attribute "ROOM" "PVNN_PCH_STBY"
					( Origin gFrontEnd )
				)
				( attribute "ROT" "0"
					( Origin gFrontEnd )
				)
				( attribute "SEC" "1"
					( Origin gFrontEnd )
				)
				( attribute "SEC_TYPE" "0402"
					( Origin gFrontEnd )
				)
				( attribute "TOLERANCE" "1%"
					( Origin gFrontEnd )
				)
				( attribute "VALUE" "1.00K"
					( Origin gFrontEnd )
				)
				( attribute "VER" "2"
					( Origin gFrontEnd )
				)
				( attribute "WATTAGE" "1/16W"
					( Origin gFrontEnd )
				)
				( attribute "XY" "(-9025,4875)"
					( Origin gFrontEnd )
				)
				( attribute "CHIPS_PART_NAME" "RES"
					( Origin gPackager )
				)
				( attribute "CDS_PART_NAME" "RES_0402-1.00K,1%,1/16W,CHIP,GA"
					( Origin gPackager )
				)
				( objectStatus "R8A6" )
				( pin "a"
					( attribute "PN" "1"
						( Origin gPackager )
					)
					( objectStatus "R8A6.1" )
				)
				( pin "b"
					( attribute "PN" "2"
						( Origin gPackager )
					)
					( objectStatus "R8A6.2" )
				)
			)
			( gate "@baseboard_fab2_lib.baseboard_fab2(sch_1):page235_i151"
				( attribute "CDS_LIB" "dev_discrete"
					( Origin gPackager )
				)
				( attribute "CDS_LOCATION" "C2L8"
					( Origin gPackager )
				)
				( attribute "CDS_SEC" "1"
					( Origin gPackager )
				)
				( attribute "LOCATION" "C2L8"
					( Origin gFrontEnd )
				)
				( attribute "MATERIAL" "X6S"
					( Origin gFrontEnd )
				)
				( attribute "PACK_TYPE" "0402V"
					( Origin gFrontEnd )
				)
				( attribute "PART_NUMBER" "D97712-004"
					( Origin gFrontEnd )
				)
				( attribute "PHYS_PAGE" "235"
					( Origin gFrontEnd )
				)
				( attribute "ROOM" "PVNN_PCH_STBY"
					( Origin gFrontEnd )
				)
				( attribute "ROT" "0"
					( Origin gFrontEnd )
				)
				( attribute "SEC" "1"
					( Origin gFrontEnd )
				)
				( attribute "SEC_TYPE" "0402V"
					( Origin gFrontEnd )
				)
				( attribute "TOLERANCE" "10%"
					( Origin gFrontEnd )
				)
				( attribute "VALUE" "1.0UF"
					( Origin gFrontEnd )
				)
				( attribute "VER" "1"
					( Origin gFrontEnd )
				)
				( attribute "VOLTAGE" "6.3V"
					( Units "uVoltage" "V" 1.000000)
					( Origin gFrontEnd )
				)
				( attribute "XY" "(-9750,5075)"
					( Origin gFrontEnd )
				)
				( attribute "CHIPS_PART_NAME" "CAP_A"
					( Origin gPackager )
				)
				( attribute "CDS_PART_NAME" "CAP_A_0402V-1.0UF,6.3V,10%,X6SA"
					( Origin gPackager )
				)
				( objectStatus "C2L8" )
				( pin "a"
					( attribute "PN" "1"
						( Origin gPackager )
					)
					( objectStatus "C2L8.1" )
				)
				( pin "b"
					( attribute "PN" "2"
						( Origin gPackager )
					)
					( objectStatus "C2L8.2" )
				)
			)
			( gate "@baseboard_fab2_lib.baseboard_fab2(sch_1):page235_i153"
				( attribute "CDS_LIB" "mstr_discrete"
					( Origin gPackager )
				)
				( attribute "CDS_LOCATION" "C2L2"
					( Origin gPackager )
				)
				( attribute "CDS_SEC" "1"
					( Origin gPackager )
				)
				( attribute "LOCATION" "C2L2"
					( Origin gFrontEnd )
				)
				( attribute "MATERIAL" "X7R"
					( Origin gFrontEnd )
				)
				( attribute "NO_XNET_CONNECTION" "1"
					( Origin gFrontEnd )
				)
				( attribute "PACK_TYPE" "0402LF"
					( Origin gFrontEnd )
				)
				( attribute "PART_NUMBER" "A36096-050"
					( Origin gFrontEnd )
				)
				( attribute "PHYS_PAGE" "235"
					( Origin gFrontEnd )
				)
				( attribute "ROOM" "PVNN_PCH_STBY"
					( Origin gFrontEnd )
				)
				( attribute "ROT" "0"
					( Origin gFrontEnd )
				)
				( attribute "SEC" "1"
					( Origin gFrontEnd )
				)
				( attribute "SEC_TYPE" "0402LF"
					( Origin gFrontEnd )
				)
				( attribute "TOLERANCE" "10%"
					( Origin gFrontEnd )
				)
				( attribute "VALUE" "220PF"
					( Origin gFrontEnd )
				)
				( attribute "VER" "1"
					( Origin gFrontEnd )
				)
				( attribute "VOLTAGE" "50V"
					( Units "uVoltage" "V" 1.000000)
					( Origin gFrontEnd )
				)
				( attribute "XY" "(-12475,2075)"
					( Origin gFrontEnd )
				)
				( attribute "CHIPS_PART_NAME" "CAP"
					( Origin gPackager )
				)
				( attribute "CDS_PART_NAME" "CAP_0402LF-220PF,50V,10%,X7R,AA"
					( Origin gPackager )
				)
				( objectStatus "C2L2" )
				( pin "a"
					( attribute "PN" "1"
						( Origin gPackager )
					)
					( objectStatus "C2L2.1" )
				)
				( pin "b"
					( attribute "PN" "2"
						( Origin gPackager )
					)
					( objectStatus "C2L2.2" )
				)
			)
			( gate "@baseboard_fab2_lib.baseboard_fab2(sch_1):page235_i154"
				( attribute "CDS_LIB" "mstr_discrete"
					( Origin gPackager )
				)
				( attribute "CDS_LOCATION" "R2L8"
					( Origin gPackager )
				)
				( attribute "CDS_SEC" "1"
					( Origin gPackager )
				)
				( attribute "LOCATION" "R2L8"
					( Origin gFrontEnd )
				)
				( attribute "MATERIAL" "CHIP"
					( Origin gFrontEnd )
				)
				( attribute "PACK_TYPE" "0603"
					( Origin gFrontEnd )
				)
				( attribute "PART_NUMBER" "G22026-041"
					( Origin gFrontEnd )
				)
				( attribute "PHYS_PAGE" "235"
					( Origin gFrontEnd )
				)
				( attribute "ROOM" "PVNN_PCH_STBY"
					( Origin gFrontEnd )
				)
				( attribute "ROT" "0"
					( Origin gFrontEnd )
				)
				( attribute "SEC" "1"
					( Origin gFrontEnd )
				)
				( attribute "SEC_TYPE" "0603"
					( Origin gFrontEnd )
				)
				( attribute "TOLERANCE" "1%"
					( Origin gFrontEnd )
				)
				( attribute "VALUE" "10.0"
					( Origin gFrontEnd )
				)
				( attribute "VER" "1"
					( Origin gFrontEnd )
				)
				( attribute "WATTAGE" "1/10W"
					( Origin gFrontEnd )
				)
				( attribute "XY" "(-12675,2225)"
					( Origin gFrontEnd )
				)
				( attribute "CHIPS_PART_NAME" "RES"
					( Origin gPackager )
				)
				( attribute "CDS_PART_NAME" "RES_0603-10.0,1%,1/10W,CHIP,G2A"
					( Origin gPackager )
				)
				( objectStatus "R2L8" )
				( pin "a"
					( attribute "PN" "1"
						( Origin gPackager )
					)
					( objectStatus "R2L8.1" )
				)
				( pin "b"
					( attribute "PN" "2"
						( Origin gPackager )
					)
					( objectStatus "R2L8.2" )
				)
			)
			( gate "@baseboard_fab2_lib.baseboard_fab2(sch_1):page235_i159"
				( attribute "CDS_LIB" "mstr_discrete"
					( Origin gPackager )
				)
				( attribute "CDS_LOCATION" "R2L14"
					( Origin gPackager )
				)
				( attribute "CDS_SEC" "1"
					( Origin gPackager )
				)
				( attribute "LOCATION" "R2L14"
					( Origin gFrontEnd )
				)
				( attribute "MATERIAL" "CHIP"
					( Origin gFrontEnd )
				)
				( attribute "PACK_TYPE" "0402"
					( Origin gFrontEnd )
				)
				( attribute "PART_NUMBER" "G21497-005"
					( Origin gFrontEnd )
				)
				( attribute "PHYS_PAGE" "235"
					( Origin gFrontEnd )
				)
				( attribute "ROOM" "PVNN_PCH_STBY"
					( Origin gFrontEnd )
				)
				( attribute "ROT" "0"
					( Origin gFrontEnd )
				)
				( attribute "SEC" "1"
					( Origin gFrontEnd )
				)
				( attribute "SEC_TYPE" "0402"
					( Origin gFrontEnd )
				)
				( attribute "TOLERANCE" "5%"
					( Origin gFrontEnd )
				)
				( attribute "VALUE" "0.0"
					( Origin gFrontEnd )
				)
				( attribute "VER" "2"
					( Origin gFrontEnd )
				)
				( attribute "WATTAGE" "1/16W"
					( Origin gFrontEnd )
				)
				( attribute "XY" "(-10450,5425)"
					( Origin gFrontEnd )
				)
				( attribute "CHIPS_PART_NAME" "RES"
					( Origin gPackager )
				)
				( attribute "CDS_PART_NAME" "RES_0402-0.0,5%,1/16W,CHIP,G21A"
					( Origin gPackager )
				)
				( objectStatus "R2L14" )
				( pin "a"
					( attribute "PN" "1"
						( Origin gPackager )
					)
					( objectStatus "R2L14.1" )
				)
				( pin "b"
					( attribute "PN" "2"
						( Origin gPackager )
					)
					( objectStatus "R2L14.2" )
				)
			)
			( gate "@baseboard_fab2_lib.baseboard_fab2(sch_1):page235_i165"
				( attribute "CDS_LIB" "mstr_discrete"
					( Origin gPackager )
				)
				( attribute "CDS_LOCATION" "R8A4"
					( Origin gPackager )
				)
				( attribute "CDS_SEC" "1"
					( Origin gPackager )
				)
				( attribute "LOCATION" "R8A4"
					( Origin gFrontEnd )
				)
				( attribute "MATERIAL" "CHIP"
					( Origin gFrontEnd )
				)
				( attribute "PACK_TYPE" "0402"
					( Origin gFrontEnd )
				)
				( attribute "PART_NUMBER" "G21796-160"
					( Origin gFrontEnd )
				)
				( attribute "PHYS_PAGE" "235"
					( Origin gFrontEnd )
				)
				( attribute "ROOM" "PVNN_PCH_STBY"
					( Origin gFrontEnd )
				)
				( attribute "ROT" "0"
					( Origin gFrontEnd )
				)
				( attribute "SEC" "1"
					( Origin gFrontEnd )
				)
				( attribute "SEC_TYPE" "0402"
					( Origin gFrontEnd )
				)
				( attribute "TOLERANCE" "1%"
					( Origin gFrontEnd )
				)
				( attribute "VALUE" "100.0K"
					( Origin gFrontEnd )
				)
				( attribute "VER" "2"
					( Origin gFrontEnd )
				)
				( attribute "WATTAGE" "1/16W"
					( Origin gFrontEnd )
				)
				( attribute "XY" "(-12325,5500)"
					( Origin gFrontEnd )
				)
				( attribute "CHIPS_PART_NAME" "RES"
					( Origin gPackager )
				)
				( attribute "CDS_PART_NAME" "RES_0402-100.0K,1%,1/16W,CHIP,B"
					( Origin gPackager )
				)
				( objectStatus "R8A4" )
				( pin "a"
					( attribute "PN" "1"
						( Origin gPackager )
					)
					( objectStatus "R8A4.1" )
				)
				( pin "b"
					( attribute "PN" "2"
						( Origin gPackager )
					)
					( objectStatus "R8A4.2" )
				)
			)
			( gate "@baseboard_fab2_lib.baseboard_fab2(sch_1):page235_i166"
				( attribute "CDS_LIB" "mstr_discrete"
					( Origin gPackager )
				)
				( attribute "CDS_LOCATION" "R2L10"
					( Origin gPackager )
				)
				( attribute "CDS_SEC" "1"
					( Origin gPackager )
				)
				( attribute "LOCATION" "R2L10"
					( Origin gFrontEnd )
				)
				( attribute "MATERIAL" "CHIP"
					( Origin gFrontEnd )
				)
				( attribute "PACK_TYPE" "0402"
					( Origin gFrontEnd )
				)
				( attribute "PART_NUMBER" "G21796-003"
					( Origin gFrontEnd )
				)
				( attribute "PHYS_PAGE" "235"
					( Origin gFrontEnd )
				)
				( attribute "ROOM" "PVNN_PCH_STBY"
					( Origin gFrontEnd )
				)
				( attribute "ROT" "0"
					( Origin gFrontEnd )
				)
				( attribute "SEC" "1"
					( Origin gFrontEnd )
				)
				( attribute "SEC_TYPE" "0402"
					( Origin gFrontEnd )
				)
				( attribute "TOLERANCE" "1%"
					( Origin gFrontEnd )
				)
				( attribute "VALUE" "1.5K"
					( Origin gFrontEnd )
				)
				( attribute "VER" "2"
					( Origin gFrontEnd )
				)
				( attribute "WATTAGE" "1/16W"
					( Origin gFrontEnd )
				)
				( attribute "XY" "(-12325,5175)"
					( Origin gFrontEnd )
				)
				( attribute "CHIPS_PART_NAME" "RES"
					( Origin gPackager )
				)
				( attribute "CDS_PART_NAME" "RES_0402-1.5K,1%,1/16W,CHIP,G2A"
					( Origin gPackager )
				)
				( objectStatus "R2L10" )
				( pin "a"
					( attribute "PN" "1"
						( Origin gPackager )
					)
					( objectStatus "R2L10.1" )
				)
				( pin "b"
					( attribute "PN" "2"
						( Origin gPackager )
					)
					( objectStatus "R2L10.2" )
				)
			)
			( gate "@baseboard_fab2_lib.baseboard_fab2(sch_1):page235_i167"
				( attribute "CDS_LIB" "mstr_discrete"
					( Origin gPackager )
				)
				( attribute "CDS_LOCATION" "C8A3"
					( Origin gPackager )
				)
				( attribute "CDS_SEC" "1"
					( Origin gPackager )
				)
				( attribute "LOCATION" "C8A3"
					( Origin gFrontEnd )
				)
				( attribute "MATERIAL" "X7R"
					( Origin gFrontEnd )
				)
				( attribute "PACK_TYPE" "0402LF"
					( Origin gFrontEnd )
				)
				( attribute "PART_NUMBER" "A36096-046"
					( Origin gFrontEnd )
				)
				( attribute "PHYS_PAGE" "235"
					( Origin gFrontEnd )
				)
				( attribute "ROOM" "PVNN_PCH_STBY"
					( Origin gFrontEnd )
				)
				( attribute "ROT" "2"
					( Origin gFrontEnd )
				)
				( attribute "SEC" "1"
					( Origin gFrontEnd )
				)
				( attribute "SEC_TYPE" "0402LF"
					( Origin gFrontEnd )
				)
				( attribute "TOLERANCE" "10%"
					( Origin gFrontEnd )
				)
				( attribute "VALUE" "1000PF"
					( Origin gFrontEnd )
				)
				( attribute "VER" "1"
					( Origin gFrontEnd )
				)
				( attribute "VOLTAGE" "50V"
					( Units "uVoltage" "V" 1.000000)
					( Origin gFrontEnd )
				)
				( attribute "XY" "(-12550,5175)"
					( Origin gFrontEnd )
				)
				( attribute "CHIPS_PART_NAME" "CAP"
					( Origin gPackager )
				)
				( attribute "CDS_PART_NAME" "CAP_0402LF-1000PF,50V,10%,X7R,A"
					( Origin gPackager )
				)
				( objectStatus "C8A3" )
				( pin "a"
					( attribute "PN" "1"
						( Origin gPackager )
					)
					( objectStatus "C8A3.1" )
				)
				( pin "b"
					( attribute "PN" "2"
						( Origin gPackager )
					)
					( objectStatus "C8A3.2" )
				)
			)
			( gate "@baseboard_fab2_lib.baseboard_fab2(sch_1):page235_i169"
				( attribute "CDS_LIB" "dev_discrete"
					( Origin gPackager )
				)
				( attribute "CDS_LOCATION" "C2L11"
					( Origin gPackager )
				)
				( attribute "CDS_SEC" "1"
					( Origin gPackager )
				)
				( attribute "LOCATION" "C2L11"
					( Origin gFrontEnd )
				)
				( attribute "MATERIAL" "X7R"
					( Origin gFrontEnd )
				)
				( attribute "PACK_TYPE" "0402V"
					( Origin gFrontEnd )
				)
				( attribute "PART_NUMBER" "A36096-030"
					( Origin gFrontEnd )
				)
				( attribute "PHYS_PAGE" "235"
					( Origin gFrontEnd )
				)
				( attribute "ROOM" "PVNN_PCH_STBY"
					( Origin gFrontEnd )
				)
				( attribute "ROT" "0"
					( Origin gFrontEnd )
				)
				( attribute "SEC" "1"
					( Origin gFrontEnd )
				)
				( attribute "SEC_TYPE" "0402V"
					( Origin gFrontEnd )
				)
				( attribute "TOLERANCE" "10%"
					( Origin gFrontEnd )
				)
				( attribute "VALUE" "0.1UF"
					( Origin gFrontEnd )
				)
				( attribute "VER" "1"
					( Origin gFrontEnd )
				)
				( attribute "VOLTAGE" "16V"
					( Units "uVoltage" "V" 1.000000)
					( Origin gFrontEnd )
				)
				( attribute "XY" "(-10150,5075)"
					( Origin gFrontEnd )
				)
				( attribute "CHIPS_PART_NAME" "CAP_A"
					( Origin gPackager )
				)
				( attribute "CDS_PART_NAME" "CAP_A_0402V-0.1UF,16V,10%,X7R,A"
					( Origin gPackager )
				)
				( objectStatus "C2L11" )
				( pin "a"
					( attribute "PN" "1"
						( Origin gPackager )
					)
					( objectStatus "C2L11.1" )
				)
				( pin "b"
					( attribute "PN" "2"
						( Origin gPackager )
					)
					( objectStatus "C2L11.2" )
				)
			)
			( gate "@baseboard_fab2_lib.baseboard_fab2(sch_1):page235_i172"
				( attribute "CDS_LIB" "mstr_discrete"
					( Origin gPackager )
				)
				( attribute "CDS_LOCATION" "R8A8"
					( Origin gPackager )
				)
				( attribute "CDS_SEC" "1"
					( Origin gPackager )
				)
				( attribute "LOCATION" "R8A8"
					( Origin gFrontEnd )
				)
				( attribute "MATERIAL" "CHIP"
					( Origin gFrontEnd )
				)
				( attribute "PACK_TYPE" "0402"
					( Origin gFrontEnd )
				)
				( attribute "PART_NUMBER" "G21796-173"
					( Origin gFrontEnd )
				)
				( attribute "PHYS_PAGE" "235"
					( Origin gFrontEnd )
				)
				( attribute "ROOM" "PVNN_PCH_STBY"
					( Origin gFrontEnd )
				)
				( attribute "ROT" "0"
					( Origin gFrontEnd )
				)
				( attribute "SEC" "1"
					( Origin gPackager )
				)
				( attribute "TOLERANCE" "1%"
					( Origin gFrontEnd )
				)
				( attribute "VALUE" "20.0"
					( Origin gFrontEnd )
				)
				( attribute "VER" "1"
					( Origin gFrontEnd )
				)
				( attribute "WATTAGE" "1/16W"
					( Origin gFrontEnd )
				)
				( attribute "XY" "(-11075,3350)"
					( Origin gFrontEnd )
				)
				( attribute "CHIPS_PART_NAME" "RES"
					( Origin gPackager )
				)
				( attribute "CDS_PART_NAME" "RES_0402-20.0,1%,1/16W,CHIP,G2A"
					( Origin gPackager )
				)
				( objectStatus "R8A8" )
				( pin "a"
					( attribute "PN" "1"
						( Origin gPackager )
					)
					( objectStatus "R8A8.1" )
				)
				( pin "b"
					( attribute "PN" "2"
						( Origin gPackager )
					)
					( objectStatus "R8A8.2" )
				)
			)
			( gate "@baseboard_fab2_lib.baseboard_fab2(sch_1):page235_i173"
				( attribute "CDS_LIB" "mstr_discrete"
					( Origin gPackager )
				)
				( attribute "CDS_LOCATION" "R8A9"
					( Origin gPackager )
				)
				( attribute "CDS_SEC" "1"
					( Origin gPackager )
				)
				( attribute "LOCATION" "R8A9"
					( Origin gFrontEnd )
				)
				( attribute "MATERIAL" "CHIP"
					( Origin gFrontEnd )
				)
				( attribute "PACK_TYPE" "0402"
					( Origin gFrontEnd )
				)
				( attribute "PART_NUMBER" "G21796-173"
					( Origin gFrontEnd )
				)
				( attribute "PHYS_PAGE" "235"
					( Origin gFrontEnd )
				)
				( attribute "ROOM" "PVNN_PCH_STBY"
					( Origin gFrontEnd )
				)
				( attribute "ROT" "0"
					( Origin gFrontEnd )
				)
				( attribute "SEC" "1"
					( Origin gPackager )
				)
				( attribute "TOLERANCE" "1%"
					( Origin gFrontEnd )
				)
				( attribute "VALUE" "20.0"
					( Origin gFrontEnd )
				)
				( attribute "VER" "1"
					( Origin gFrontEnd )
				)
				( attribute "WATTAGE" "1/16W"
					( Origin gFrontEnd )
				)
				( attribute "XY" "(-11400,3300)"
					( Origin gFrontEnd )
				)
				( attribute "CHIPS_PART_NAME" "RES"
					( Origin gPackager )
				)
				( attribute "CDS_PART_NAME" "RES_0402-20.0,1%,1/16W,CHIP,G2A"
					( Origin gPackager )
				)
				( objectStatus "R8A9" )
				( pin "a"
					( attribute "PN" "1"
						( Origin gPackager )
					)
					( objectStatus "R8A9.1" )
				)
				( pin "b"
					( attribute "PN" "2"
						( Origin gPackager )
					)
					( objectStatus "R8A9.2" )
				)
			)
			( gate "@baseboard_fab2_lib.baseboard_fab2(sch_1):page235_i176"
				( attribute "CDS_LIB" "mstr_discrete"
					( Origin gPackager )
				)
				( attribute "CDS_LOCATION" "R2L9"
					( Origin gPackager )
				)
				( attribute "CDS_SEC" "1"
					( Origin gPackager )
				)
				( attribute "LOCATION" "R2L9"
					( Origin gFrontEnd )
				)
				( attribute "MATERIAL" "CHIP"
					( Origin gFrontEnd )
				)
				( attribute "PACK_TYPE" "0402"
					( Origin gFrontEnd )
				)
				( attribute "PART_NUMBER" "G21796-082"
					( Origin gFrontEnd )
				)
				( attribute "PHYS_PAGE" "235"
					( Origin gFrontEnd )
				)
				( attribute "ROOM" "PVNN_PCH_STBY"
					( Origin gFrontEnd )
				)
				( attribute "ROT" "0"
					( Origin gFrontEnd )
				)
				( attribute "SEC" "1"
					( Origin gFrontEnd )
				)
				( attribute "SEC_TYPE" "0402"
					( Origin gFrontEnd )
				)
				( attribute "TOLERANCE" "1%"
					( Origin gFrontEnd )
				)
				( attribute "VALUE" "4.02K"
					( Origin gFrontEnd )
				)
				( attribute "VER" "2"
					( Origin gFrontEnd )
				)
				( attribute "WATTAGE" "1/16W"
					( Origin gFrontEnd )
				)
				( attribute "XY" "(-10750,2250)"
					( Origin gFrontEnd )
				)
				( attribute "CHIPS_PART_NAME" "RES"
					( Origin gPackager )
				)
				( attribute "CDS_PART_NAME" "RES_0402-4.02K,1%,1/16W,CHIP,GA"
					( Origin gPackager )
				)
				( objectStatus "R2L9" )
				( pin "a"
					( attribute "PN" "1"
						( Origin gPackager )
					)
					( objectStatus "R2L9.1" )
				)
				( pin "b"
					( attribute "PN" "2"
						( Origin gPackager )
					)
					( objectStatus "R2L9.2" )
				)
			)
			( gate "@baseboard_fab2_lib.baseboard_fab2(sch_1):page235_i209"
				( attribute "CDS_LIB" "mstr_discrete"
					( Origin gPackager )
				)
				( attribute "CDS_LOCATION" "C8A2"
					( Origin gPackager )
				)
				( attribute "CDS_SEC" "1"
					( Origin gPackager )
				)
				( attribute "LOCATION" "C8A2"
					( Origin gFrontEnd )
				)
				( attribute "MATERIAL" "X7R"
					( Origin gFrontEnd )
				)
				( attribute "NO_XNET_CONNECTION" "1"
					( Origin gFrontEnd )
				)
				( attribute "PACK_TYPE" "0402LF"
					( Origin gFrontEnd )
				)
				( attribute "PART_NUMBER" "A36096-050"
					( Origin gFrontEnd )
				)
				( attribute "PHYS_PAGE" "235"
					( Origin gFrontEnd )
				)
				( attribute "ROOM" "PVNN_PCH_STBY"
					( Origin gFrontEnd )
				)
				( attribute "ROT" "0"
					( Origin gFrontEnd )
				)
				( attribute "SEC" "1"
					( Origin gFrontEnd )
				)
				( attribute "SEC_TYPE" "0402LF"
					( Origin gFrontEnd )
				)
				( attribute "TOLERANCE" "10%"
					( Origin gFrontEnd )
				)
				( attribute "VALUE" "220PF"
					( Origin gFrontEnd )
				)
				( attribute "VER" "1"
					( Origin gFrontEnd )
				)
				( attribute "VOLTAGE" "50V"
					( Units "uVoltage" "V" 1.000000)
					( Origin gFrontEnd )
				)
				( attribute "XY" "(-12375,2600)"
					( Origin gFrontEnd )
				)
				( attribute "CHIPS_PART_NAME" "CAP"
					( Origin gPackager )
				)
				( attribute "CDS_PART_NAME" "CAP_0402LF-220PF,50V,10%,X7R,AA"
					( Origin gPackager )
				)
				( objectStatus "C8A2" )
				( pin "a"
					( attribute "PN" "1"
						( Origin gPackager )
					)
					( objectStatus "C8A2.1" )
				)
				( pin "b"
					( attribute "PN" "2"
						( Origin gPackager )
					)
					( objectStatus "C8A2.2" )
				)
			)
			( gate "@baseboard_fab2_lib.baseboard_fab2(sch_1):page235_i210"
				( attribute "CDS_LIB" "mstr_discrete"
					( Origin gPackager )
				)
				( attribute "CDS_LOCATION" "R8A1"
					( Origin gPackager )
				)
				( attribute "CDS_SEC" "1"
					( Origin gPackager )
				)
				( attribute "LOCATION" "R8A1"
					( Origin gFrontEnd )
				)
				( attribute "MATERIAL" "CHIP"
					( Origin gFrontEnd )
				)
				( attribute "NO_XNET_CONNECTION" "1"
					( Origin gFrontEnd )
				)
				( attribute "PACK_TYPE" "0402"
					( Origin gFrontEnd )
				)
				( attribute "PART_NUMBER" "G21796-066"
					( Origin gFrontEnd )
				)
				( attribute "PHYS_PAGE" "235"
					( Origin gFrontEnd )
				)
				( attribute "ROOM" "PVNN_PCH_STBY"
					( Origin gFrontEnd )
				)
				( attribute "ROT" "0"
					( Origin gFrontEnd )
				)
				( attribute "SEC" "1"
					( Origin gFrontEnd )
				)
				( attribute "SEC_TYPE" "0402"
					( Origin gFrontEnd )
				)
				( attribute "TOLERANCE" "1%"
					( Origin gFrontEnd )
				)
				( attribute "VALUE" "10.0"
					( Origin gFrontEnd )
				)
				( attribute "VER" "1"
					( Origin gFrontEnd )
				)
				( attribute "WATTAGE" "1/16W"
					( Origin gFrontEnd )
				)
				( attribute "XY" "(-12675,2750)"
					( Origin gFrontEnd )
				)
				( attribute "CHIPS_PART_NAME" "RES"
					( Origin gPackager )
				)
				( attribute "CDS_PART_NAME" "RES_0402-10.0,1%,1/16W,CHIP,G2A"
					( Origin gPackager )
				)
				( objectStatus "R8A1" )
				( pin "a"
					( attribute "PN" "1"
						( Origin gPackager )
					)
					( objectStatus "R8A1.1" )
				)
				( pin "b"
					( attribute "PN" "2"
						( Origin gPackager )
					)
					( objectStatus "R8A1.2" )
				)
			)
			( gate "@baseboard_fab2_lib.baseboard_fab2(sch_1):page235_i216"
				( attribute "CDS_LIB" "mstr_discrete"
					( Origin gPackager )
				)
				( attribute "CDS_LOCATION" "R8A5"
					( Origin gPackager )
				)
				( attribute "CDS_SEC" "1"
					( Origin gPackager )
				)
				( attribute "LOCATION" "R8A5"
					( Origin gFrontEnd )
				)
				( attribute "MATERIAL" "CHIP"
					( Origin gFrontEnd )
				)
				( attribute "PACK_TYPE" "0402"
					( Origin gFrontEnd )
				)
				( attribute "PART_NUMBER" "G21796-026"
					( Origin gFrontEnd )
				)
				( attribute "PHYS_PAGE" "235"
					( Origin gFrontEnd )
				)
				( attribute "ROT" "0"
					( Origin gFrontEnd )
				)
				( attribute "SEC" "1"
					( Origin gPackager )
				)
				( attribute "TOLERANCE" "1%"
					( Origin gFrontEnd )
				)
				( attribute "VALUE" "1.00K"
					( Origin gFrontEnd )
				)
				( attribute "VER" "2"
					( Origin gFrontEnd )
				)
				( attribute "WATTAGE" "1/16W"
					( Origin gFrontEnd )
				)
				( attribute "XY" "(-8200,4875)"
					( Origin gFrontEnd )
				)
				( attribute "CHIPS_PART_NAME" "RES"
					( Origin gPackager )
				)
				( attribute "CDS_PART_NAME" "RES_0402-1.00K,1%,1/16W,CHIP,GA"
					( Origin gPackager )
				)
				( objectStatus "R8A5" )
				( pin "a"
					( attribute "PN" "1"
						( Origin gPackager )
					)
					( objectStatus "R8A5.1" )
				)
				( pin "b"
					( attribute "PN" "2"
						( Origin gPackager )
					)
					( objectStatus "R8A5.2" )
				)
			)
			( gate "@baseboard_fab2_lib.baseboard_fab2(sch_1):page235_i217"
				( attribute "CDS_LIB" "mstr_discrete"
					( Origin gPackager )
				)
				( attribute "CDS_LOCATION" "R8A2"
					( Origin gPackager )
				)
				( attribute "CDS_SEC" "1"
					( Origin gPackager )
				)
				( attribute "LOCATION" "R8A2"
					( Origin gFrontEnd )
				)
				( attribute "MATERIAL" "CHIP"
					( Origin gFrontEnd )
				)
				( attribute "PACK_TYPE" "0402"
					( Origin gFrontEnd )
				)
				( attribute "PART_NUMBER" "G21796-180"
					( Origin gFrontEnd )
				)
				( attribute "PHYS_PAGE" "235"
					( Origin gFrontEnd )
				)
				( attribute "ROT" "0"
					( Origin gFrontEnd )
				)
				( attribute "SEC" "1"
					( Origin gPackager )
				)
				( attribute "TOLERANCE" "1%"
					( Origin gFrontEnd )
				)
				( attribute "VALUE" "2.67K"
					( Origin gFrontEnd )
				)
				( attribute "VER" "2"
					( Origin gFrontEnd )
				)
				( attribute "WATTAGE" "1/16W"
					( Origin gFrontEnd )
				)
				( attribute "XY" "(-10375,2275)"
					( Origin gFrontEnd )
				)
				( attribute "CHIPS_PART_NAME" "RES"
					( Origin gPackager )
				)
				( attribute "CDS_PART_NAME" "RES_0402-2.67K,1%,1/16W,CHIP,GA"
					( Origin gPackager )
				)
				( objectStatus "R8A2" )
				( pin "a"
					( attribute "PN" "1"
						( Origin gPackager )
					)
					( objectStatus "R8A2.1" )
				)
				( pin "b"
					( attribute "PN" "2"
						( Origin gPackager )
					)
					( objectStatus "R8A2.2" )
				)
			)
			( gate "@baseboard_fab2_lib.baseboard_fab2(sch_1):page235_i218"
				( attribute "CDS_LIB" "mstr_discrete"
					( Origin gPackager )
				)
				( attribute "CDS_LOCATION" "C8A9"
					( Origin gPackager )
				)
				( attribute "CDS_SEC" "1"
					( Origin gPackager )
				)
				( attribute "LOCATION" "C8A9"
					( Origin gFrontEnd )
				)
				( attribute "MATERIAL" "X7R"
					( Origin gFrontEnd )
				)
				( attribute "PACK_TYPE" "0402LF"
					( Origin gFrontEnd )
				)
				( attribute "PART_NUMBER" "A36096-046"
					( Origin gFrontEnd )
				)
				( attribute "PHYS_PAGE" "235"
					( Origin gFrontEnd )
				)
				( attribute "ROOM" "PVNN_PCH_STBY"
					( Origin gFrontEnd )
				)
				( attribute "ROT" "0"
					( Origin gFrontEnd )
				)
				( attribute "SEC" "1"
					( Origin gFrontEnd )
				)
				( attribute "SEC_TYPE" "0402LF"
					( Origin gFrontEnd )
				)
				( attribute "TOLERANCE" "10%"
					( Origin gFrontEnd )
				)
				( attribute "VALUE" "1000PF"
					( Origin gFrontEnd )
				)
				( attribute "VER" "1"
					( Origin gFrontEnd )
				)
				( attribute "VOLTAGE" "50V"
					( Units "uVoltage" "V" 1.000000)
					( Origin gFrontEnd )
				)
				( attribute "XY" "(-8000,4325)"
					( Origin gFrontEnd )
				)
				( attribute "CHIPS_PART_NAME" "CAP"
					( Origin gPackager )
				)
				( attribute "CDS_PART_NAME" "CAP_0402LF-1000PF,50V,10%,X7R,A"
					( Origin gPackager )
				)
				( objectStatus "C8A9" )
				( pin "a"
					( attribute "PN" "1"
						( Origin gPackager )
					)
					( objectStatus "C8A9.1" )
				)
				( pin "b"
					( attribute "PN" "2"
						( Origin gPackager )
					)
					( objectStatus "C8A9.2" )
				)
			)
			( gate "@baseboard_fab2_lib.baseboard_fab2(sch_1):page235_i221"
				( attribute "CDS_LIB" "mstr_discrete"
					( Origin gPackager )
				)
				( attribute "CDS_LOCATION" "R2L17"
					( Origin gPackager )
				)
				( attribute "CDS_SEC" "1"
					( Origin gPackager )
				)
				( attribute "LOCATION" "R2L17"
					( Origin gFrontEnd )
				)
				( attribute "MATERIAL" "CHIP"
					( Origin gFrontEnd )
				)
				( attribute "PACK_TYPE" "0402"
					( Origin gFrontEnd )
				)
				( attribute "PART_NUMBER" "G21497-005"
					( Origin gFrontEnd )
				)
				( attribute "PHYS_PAGE" "235"
					( Origin gFrontEnd )
				)
				( attribute "ROOM" "PVCCIN_CPU0_VR"
					( Origin gFrontEnd )
				)
				( attribute "ROT" "0"
					( Origin gFrontEnd )
				)
				( attribute "SEC" "1"
					( Origin gFrontEnd )
				)
				( attribute "SEC_TYPE" "0402"
					( Origin gFrontEnd )
				)
				( attribute "TOLERANCE" "5%"
					( Origin gFrontEnd )
				)
				( attribute "VALUE" "0.0"
					( Origin gFrontEnd )
				)
				( attribute "VER" "1"
					( Origin gFrontEnd )
				)
				( attribute "WATTAGE" "1/16W"
					( Origin gFrontEnd )
				)
				( attribute "XY" "(-11800,4150)"
					( Origin gFrontEnd )
				)
				( attribute "CHIPS_PART_NAME" "RES"
					( Origin gPackager )
				)
				( attribute "CDS_PART_NAME" "RES_0402-0.0,5%,1/16W,CHIP,G21A"
					( Origin gPackager )
				)
				( objectStatus "R2L17" )
				( pin "a"
					( attribute "PN" "1"
						( Origin gPackager )
					)
					( objectStatus "R2L17.1" )
				)
				( pin "b"
					( attribute "PN" "2"
						( Origin gPackager )
					)
					( objectStatus "R2L17.2" )
				)
			)
			( gate "@baseboard_fab2_lib.baseboard_fab2(sch_1):page235_i222"
				( attribute "BOM_COST" "SM_CONTROLLER"
					( Origin gFrontEnd )
				)
				( attribute "CDS_LIB" "mstr_discrete"
					( Origin gPackager )
				)
				( attribute "CDS_LOCATION" "R8A7"
					( Origin gPackager )
				)
				( attribute "CDS_SEC" "1"
					( Origin gPackager )
				)
				( attribute "LOCATION" "R8A7"
					( Origin gFrontEnd )
				)
				( attribute "MATERIAL" "EMPTY"
					( Origin gFrontEnd )
				)
				( attribute "PACK_TYPE" "0402"
					( Origin gFrontEnd )
				)
				( attribute "PART_NUMBER" "G21796-010"
					( Origin gFrontEnd )
				)
				( attribute "PHYS_PAGE" "235"
					( Origin gFrontEnd )
				)
				( attribute "ROOM" "BMC"
					( Origin gFrontEnd )
				)
				( attribute "ROT" "0"
					( Origin gFrontEnd )
				)
				( attribute "SEC" "1"
					( Origin gFrontEnd )
				)
				( attribute "SEC_TYPE" "0402"
					( Origin gFrontEnd )
				)
				( attribute "TOLERANCE" "1%"
					( Origin gFrontEnd )
				)
				( attribute "VALUE" "100.0K"
					( Origin gFrontEnd )
				)
				( attribute "VER" "2"
					( Origin gFrontEnd )
				)
				( attribute "WATTAGE" "1/16W"
					( Origin gFrontEnd )
				)
				( attribute "XY" "(-11175,5075)"
					( Origin gFrontEnd )
				)
				( attribute "CHIPS_PART_NAME" "RES"
					( Origin gPackager )
				)
				( attribute "CDS_PART_NAME" "RES_0402-100.0K,1%,1/16W,EMPTYA"
					( Origin gPackager )
				)
				( objectStatus "R8A7" )
				( pin "a"
					( attribute "PN" "1"
						( Origin gPackager )
					)
					( objectStatus "R8A7.1" )
				)
				( pin "b"
					( attribute "PN" "2"
						( Origin gPackager )
					)
					( objectStatus "R8A7.2" )
				)
			)
			( gate "@baseboard_fab2_lib.baseboard_fab2(sch_1):page235_i224"
				( attribute "CDS_LIB" "mstr_discrete"
					( Origin gPackager )
				)
				( attribute "CDS_LOCATION" "R2L1"
					( Origin gPackager )
				)
				( attribute "CDS_SEC" "1"
					( Origin gPackager )
				)
				( attribute "LOCATION" "R2L1"
					( Origin gFrontEnd )
				)
				( attribute "MATERIAL" "CHIP"
					( Origin gFrontEnd )
				)
				( attribute "PACK_TYPE" "0402"
					( Origin gFrontEnd )
				)
				( attribute "PART_NUMBER" "G21497-005"
					( Origin gFrontEnd )
				)
				( attribute "PHYS_PAGE" "235"
					( Origin gFrontEnd )
				)
				( attribute "ROOM" "PVCCIN_CPU0_VR"
					( Origin gFrontEnd )
				)
				( attribute "ROT" "0"
					( Origin gFrontEnd )
				)
				( attribute "SEC" "1"
					( Origin gFrontEnd )
				)
				( attribute "SEC_TYPE" "0402"
					( Origin gFrontEnd )
				)
				( attribute "TOLERANCE" "5%"
					( Origin gFrontEnd )
				)
				( attribute "VALUE" "0.0"
					( Origin gFrontEnd )
				)
				( attribute "VER" "1"
					( Origin gFrontEnd )
				)
				( attribute "WATTAGE" "1/16W"
					( Origin gFrontEnd )
				)
				( attribute "XY" "(-12350,4650)"
					( Origin gFrontEnd )
				)
				( attribute "CHIPS_PART_NAME" "RES"
					( Origin gPackager )
				)
				( attribute "CDS_PART_NAME" "RES_0402-0.0,5%,1/16W,CHIP,G21A"
					( Origin gPackager )
				)
				( objectStatus "R2L1" )
				( pin "a"
					( attribute "PN" "1"
						( Origin gPackager )
					)
					( objectStatus "R2L1.1" )
				)
				( pin "b"
					( attribute "PN" "2"
						( Origin gPackager )
					)
					( objectStatus "R2L1.2" )
				)
			)
			( gate "@baseboard_fab2_lib.baseboard_fab2(sch_1):page235_i225"
				( attribute "CDS_LIB" "mstr_discrete"
					( Origin gPackager )
				)
				( attribute "CDS_LOCATION" "R2L7"
					( Origin gPackager )
				)
				( attribute "CDS_SEC" "1"
					( Origin gPackager )
				)
				( attribute "LOCATION" "R2L7"
					( Origin gFrontEnd )
				)
				( attribute "MATERIAL" "CHIP"
					( Origin gFrontEnd )
				)
				( attribute "PACK_TYPE" "0402"
					( Origin gFrontEnd )
				)
				( attribute "PART_NUMBER" "G21497-005"
					( Origin gFrontEnd )
				)
				( attribute "PHYS_PAGE" "235"
					( Origin gFrontEnd )
				)
				( attribute "ROOM" "PVCCIN_CPU0_VR"
					( Origin gFrontEnd )
				)
				( attribute "ROT" "0"
					( Origin gFrontEnd )
				)
				( attribute "SEC" "1"
					( Origin gPackager )
				)
				( attribute "TOLERANCE" "5%"
					( Origin gFrontEnd )
				)
				( attribute "VALUE" "0.0"
					( Origin gFrontEnd )
				)
				( attribute "VER" "1"
					( Origin gFrontEnd )
				)
				( attribute "WATTAGE" "1/16W"
					( Origin gFrontEnd )
				)
				( attribute "XY" "(-11525,2925)"
					( Origin gFrontEnd )
				)
				( attribute "CHIPS_PART_NAME" "RES"
					( Origin gPackager )
				)
				( attribute "CDS_PART_NAME" "RES_0402-0.0,5%,1/16W,CHIP,G21A"
					( Origin gPackager )
				)
				( objectStatus "R2L7" )
				( pin "a"
					( attribute "PN" "1"
						( Origin gPackager )
					)
					( objectStatus "R2L7.1" )
				)
				( pin "b"
					( attribute "PN" "2"
						( Origin gPackager )
					)
					( objectStatus "R2L7.2" )
				)
			)
			( gate "@baseboard_fab2_lib.baseboard_fab2(sch_1):page235_i229"
				( attribute "CDS_LIB" "mstr_controller"
					( Origin gPackager )
				)
				( attribute "CDS_LMAN_SYM_OUTLINE" "-400,850,400,-850"
					( Origin gPackager )
				)
				( attribute "CDS_LOCATION" "EU8A1"
					( Origin gPackager )
				)
				( attribute "CDS_SEC" "1"
					( Origin gPackager )
				)
				( attribute "LOCATION" "EU8A1"
					( Origin gFrontEnd )
				)
				( attribute "MATERIAL" "IC"
					( Origin gFrontEnd )
				)
				( attribute "PACK_TYPE" "QFN"
					( Origin gFrontEnd )
				)
				( attribute "PART_NUMBER" "H89187-001"
					( Origin gFrontEnd )
				)
				( attribute "PHYS_PAGE" "235"
					( Origin gFrontEnd )
				)
				( attribute "ROT" "0"
					( Origin gFrontEnd )
				)
				( attribute "SEC" "1"
					( Origin gFrontEnd )
				)
				( attribute "SEC_TYPE" "QFN"
					( Origin gFrontEnd )
				)
				( attribute "VER" "1"
					( Origin gFrontEnd )
				)
				( attribute "XY" "(-9725,3750)"
					( Origin gFrontEnd )
				)
				( attribute "CHIPS_PART_NAME" "PXE1110B"
					( Origin gPackager )
				)
				( attribute "CDS_PART_NAME" "PXE1110B_QFN-IC,H89187-001"
					( Origin gPackager )
				)
				( objectStatus "EU8A1" )
				( pin "airef1"
					( attribute "PN" "21"
						( Origin gPackager )
					)
					( objectStatus "EU8A1.21" )
				)
				( pin "aisen1"
					( attribute "PN" "22"
						( Origin gPackager )
					)
					( objectStatus "EU8A1.22" )
				)
				( pin "apwm1"
					( attribute "PN" "5"
						( Origin gPackager )
					)
					( objectStatus "EU8A1.5" )
				)
				( pin "atsen"
					( attribute "PN" "35"
						( Origin gPackager )
					)
					( objectStatus "EU8A1.35" )
				)
				( pin "avref"
					( attribute "PN" "20"
						( Origin gPackager )
					)
					( objectStatus "EU8A1.20" )
				)
				( pin "avren"
					( attribute "PN" "10"
						( Origin gPackager )
					)
					( objectStatus "EU8A1.10" )
				)
				( pin "avrrdy"
					( attribute "PN" "9"
						( Origin gPackager )
					)
					( objectStatus "EU8A1.9" )
				)
				( pin "avsen"
					( attribute "PN" "19"
						( Origin gPackager )
					)
					( objectStatus "EU8A1.19" )
				)
				( pin "biref1"
					( attribute "PN" "25"
						( Origin gPackager )
					)
					( objectStatus "EU8A1.25" )
				)
				( pin "bisen1"
					( attribute "PN" "26"
						( Origin gPackager )
					)
					( objectStatus "EU8A1.26" )
				)
				( pin "bpwm1"
					( attribute "PN" "3"
						( Origin gPackager )
					)
					( objectStatus "EU8A1.3" )
				)
				( pin "btsen"
					( attribute "PN" "34"
						( Origin gPackager )
					)
					( objectStatus "EU8A1.34" )
				)
				( pin "bvref"
					( attribute "PN" "30"
						( Origin gPackager )
					)
					( objectStatus "EU8A1.30" )
				)
				( pin "bvsen"
					( attribute "PN" "29"
						( Origin gPackager )
					)
					( objectStatus "EU8A1.29" )
				)
				( pin "dnc(0)"
					( attribute "PN" "1"
						( Origin gPackager )
					)
					( objectStatus "EU8A1.1" )
				)
				( pin "dnc(1)"
					( attribute "PN" "2"
						( Origin gPackager )
					)
					( objectStatus "EU8A1.2" )
				)
				( pin "dnc(2)"
					( attribute "PN" "4"
						( Origin gPackager )
					)
					( objectStatus "EU8A1.4" )
				)
				( pin "dnc(3)"
					( attribute "PN" "24"
						( Origin gPackager )
					)
					( objectStatus "EU8A1.24" )
				)
				( pin "dnc(4)"
					( attribute "PN" "28"
						( Origin gPackager )
					)
					( objectStatus "EU8A1.28" )
				)
				( pin "gnd(0)"
					( attribute "PN" "27"
						( Origin gPackager )
					)
					( objectStatus "EU8A1.27" )
				)
				( pin "gnd(1)"
					( attribute "PN" "23"
						( Origin gPackager )
					)
					( objectStatus "EU8A1.23" )
				)
				( pin "iinsen"
					( attribute "PN" "38"
						( Origin gPackager )
					)
					( objectStatus "EU8A1.38" )
				)
				( pin "mp0"
					( attribute "PN" "13"
						( Origin gPackager )
					)
					( objectStatus "EU8A1.13" )
				)
				( pin "mp1"
					( attribute "PN" "14"
						( Origin gPackager )
					)
					( objectStatus "EU8A1.14" )
				)
				( pin "mp2"
					( attribute "PN" "18"
						( Origin gPackager )
					)
					( objectStatus "EU8A1.18" )
				)
				( pin "mp3"
					( attribute "PN" "31"
						( Origin gPackager )
					)
					( objectStatus "EU8A1.31" )
				)
				( pin "mp4"
					( attribute "PN" "32"
						( Origin gPackager )
					)
					( objectStatus "EU8A1.32" )
				)
				( pin "pinalrt_n"
					( attribute "PN" "12"
						( Origin gPackager )
					)
					( objectStatus "EU8A1.12" )
				)
				( pin "reset_n"
					( attribute "PN" "8"
						( Origin gPackager )
					)
					( objectStatus "EU8A1.8" )
				)
				( pin "scl"
					( attribute "PN" "7"
						( Origin gPackager )
					)
					( objectStatus "EU8A1.7" )
				)
				( pin "sda"
					( attribute "PN" "6"
						( Origin gPackager )
					)
					( objectStatus "EU8A1.6" )
				)
				( pin "thpad"
					( attribute "PN" "41"
						( Origin gPackager )
					)
					( objectStatus "EU8A1.41" )
				)
				( pin "valrt_n"
					( attribute "PN" "17"
						( Origin gPackager )
					)
					( objectStatus "EU8A1.17" )
				)
				( pin "vclk"
					( attribute "PN" "15"
						( Origin gPackager )
					)
					( objectStatus "EU8A1.15" )
				)
				( pin "vd12"
					( attribute "PN" "40"
						( Origin gPackager )
					)
					( objectStatus "EU8A1.40" )
				)
				( pin "vdd"
					( attribute "PN" "39"
						( Origin gPackager )
					)
					( objectStatus "EU8A1.39" )
				)
				( pin "vdio"
					( attribute "PN" "16"
						( Origin gPackager )
					)
					( objectStatus "EU8A1.16" )
				)
				( pin "vinsen"
					( attribute "PN" "37"
						( Origin gPackager )
					)
					( objectStatus "EU8A1.37" )
				)
				( pin "vrhot_n"
					( attribute "PN" "11"
						( Origin gPackager )
					)
					( objectStatus "EU8A1.11" )
				)
				( pin "xaddr1"
					( attribute "PN" "36"
						( Origin gPackager )
					)
					( objectStatus "EU8A1.36" )
				)
				( pin "xaddr2"
					( attribute "PN" "33"
						( Origin gPackager )
					)
					( objectStatus "EU8A1.33" )
				)
			)
			( gate "@baseboard_fab2_lib.baseboard_fab2(sch_1):page235_i235"
				( attribute "BOM_COST" "SM_CONTROLLER"
					( Origin gFrontEnd )
				)
				( attribute "CDS_LIB" "mstr_discrete"
					( Origin gPackager )
				)
				( attribute "CDS_LOCATION" "R2L25"
					( Origin gPackager )
				)
				( attribute "CDS_SEC" "1"
					( Origin gPackager )
				)
				( attribute "LOCATION" "R2L25"
					( Origin gFrontEnd )
				)
				( attribute "MATERIAL" "EMPTY"
					( Origin gFrontEnd )
				)
				( attribute "PACK_TYPE" "0402"
					( Origin gFrontEnd )
				)
				( attribute "PART_NUMBER" "G21796-010"
					( Origin gFrontEnd )
				)
				( attribute "PHYS_PAGE" "235"
					( Origin gFrontEnd )
				)
				( attribute "ROOM" "BMC"
					( Origin gFrontEnd )
				)
				( attribute "ROT" "0"
					( Origin gFrontEnd )
				)
				( attribute "SEC" "1"
					( Origin gPackager )
				)
				( attribute "TOLERANCE" "1%"
					( Origin gFrontEnd )
				)
				( attribute "VALUE" "100.0K"
					( Origin gFrontEnd )
				)
				( attribute "VER" "2"
					( Origin gFrontEnd )
				)
				( attribute "WATTAGE" "1/16W"
					( Origin gFrontEnd )
				)
				( attribute "XY" "(-7775,4875)"
					( Origin gFrontEnd )
				)
				( attribute "CHIPS_PART_NAME" "RES"
					( Origin gPackager )
				)
				( attribute "CDS_PART_NAME" "RES_0402-100.0K,1%,1/16W,EMPTYA"
					( Origin gPackager )
				)
				( objectStatus "R2L25" )
				( pin "a"
					( attribute "PN" "1"
						( Origin gPackager )
					)
					( objectStatus "R2L25.1" )
				)
				( pin "b"
					( attribute "PN" "2"
						( Origin gPackager )
					)
					( objectStatus "R2L25.2" )
				)
			)
			( gate "@baseboard_fab2_lib.baseboard_fab2(sch_1):page235_i236"
				( attribute "BOM_COST" "SM_CONTROLLER"
					( Origin gFrontEnd )
				)
				( attribute "CDS_LIB" "mstr_discrete"
					( Origin gPackager )
				)
				( attribute "CDS_LOCATION" "R2L26"
					( Origin gPackager )
				)
				( attribute "CDS_SEC" "1"
					( Origin gPackager )
				)
				( attribute "LOCATION" "R2L26"
					( Origin gFrontEnd )
				)
				( attribute "MATERIAL" "EMPTY"
					( Origin gFrontEnd )
				)
				( attribute "PACK_TYPE" "0402"
					( Origin gFrontEnd )
				)
				( attribute "PART_NUMBER" "G21796-010"
					( Origin gFrontEnd )
				)
				( attribute "PHYS_PAGE" "235"
					( Origin gFrontEnd )
				)
				( attribute "ROOM" "BMC"
					( Origin gFrontEnd )
				)
				( attribute "ROT" "0"
					( Origin gFrontEnd )
				)
				( attribute "SEC" "1"
					( Origin gPackager )
				)
				( attribute "TOLERANCE" "1%"
					( Origin gFrontEnd )
				)
				( attribute "VALUE" "100.0K"
					( Origin gFrontEnd )
				)
				( attribute "VER" "2"
					( Origin gFrontEnd )
				)
				( attribute "WATTAGE" "1/16W"
					( Origin gFrontEnd )
				)
				( attribute "XY" "(-7450,4950)"
					( Origin gFrontEnd )
				)
				( attribute "CHIPS_PART_NAME" "RES"
					( Origin gPackager )
				)
				( attribute "CDS_PART_NAME" "RES_0402-100.0K,1%,1/16W,EMPTYA"
					( Origin gPackager )
				)
				( objectStatus "R2L26" )
				( pin "a"
					( attribute "PN" "1"
						( Origin gPackager )
					)
					( objectStatus "R2L26.1" )
				)
				( pin "b"
					( attribute "PN" "2"
						( Origin gPackager )
					)
					( objectStatus "R2L26.2" )
				)
			)
			( gate "@baseboard_fab2_lib.baseboard_fab2(sch_1):page236_i9"
				( attribute "BOM_COST" "PROC_VRD_PVCCIO_CPU0"
					( Origin gFrontEnd )
				)
				( attribute "CDS_LIB" "mstr_discrete"
					( Origin gPackager )
				)
				( attribute "CDS_LOCATION" "C7A30"
					( Origin gPackager )
				)
				( attribute "CDS_SEC" "1"
					( Origin gPackager )
				)
				( attribute "LOCATION" "C7A30"
					( Origin gFrontEnd )
				)
				( attribute "MATERIAL" "X6S"
					( Origin gFrontEnd )
				)
				( attribute "PACK_TYPE" "0805LF"
					( Origin gFrontEnd )
				)
				( attribute "PART_NUMBER" "C95333-002"
					( Origin gFrontEnd )
				)
				( attribute "PHYS_PAGE" "236"
					( Origin gFrontEnd )
				)
				( attribute "ROOM" "PVNN_PCH_STBY"
					( Origin gFrontEnd )
				)
				( attribute "ROT" "0"
					( Origin gFrontEnd )
				)
				( attribute "SEC" "1"
					( Origin gFrontEnd )
				)
				( attribute "SEC_TYPE" "0805LF"
					( Origin gFrontEnd )
				)
				( attribute "TOLERANCE" "20%"
					( Origin gFrontEnd )
				)
				( attribute "VALUE" "22UF"
					( Origin gFrontEnd )
				)
				( attribute "VER" "1"
					( Origin gFrontEnd )
				)
				( attribute "VOLTAGE" "4V"
					( Units "uVoltage" "V" 1.000000)
					( Origin gFrontEnd )
				)
				( attribute "XY" "(11575,3750)"
					( Origin gFrontEnd )
				)
				( attribute "CHIPS_PART_NAME" "CAP"
					( Origin gPackager )
				)
				( attribute "CDS_PART_NAME" "CAP_0805LF-22UF,4V,20%,X6S,C95A"
					( Origin gPackager )
				)
				( objectStatus "C7A30" )
				( pin "a"
					( attribute "PN" "1"
						( Origin gPackager )
					)
					( objectStatus "C7A30.1" )
				)
				( pin "b"
					( attribute "PN" "2"
						( Origin gPackager )
					)
					( objectStatus "C7A30.2" )
				)
			)
			( gate "@baseboard_fab2_lib.baseboard_fab2(sch_1):page236_i10"
				( attribute "CDS_LIB" "mstr_discrete"
					( Origin gPackager )
				)
				( attribute "CDS_LOCATION" "L7A2"
					( Origin gPackager )
				)
				( attribute "CDS_SEC" "1"
					( Origin gPackager )
				)
				( attribute "LOCATION" "L7A2"
					( Origin gFrontEnd )
				)
				( attribute "MATERIAL" "IND"
					( Origin gFrontEnd )
				)
				( attribute "PACK_TYPE" "SM"
					( Origin gFrontEnd )
				)
				( attribute "PART_NUMBER" "D92183-036"
					( Origin gFrontEnd )
				)
				( attribute "PHYS_PAGE" "236"
					( Origin gFrontEnd )
				)
				( attribute "ROOM" "PVNN_PCH_STBY"
					( Origin gFrontEnd )
				)
				( attribute "ROT" "0"
					( Origin gFrontEnd )
				)
				( attribute "SEC" "1"
					( Origin gFrontEnd )
				)
				( attribute "SEC_TYPE" "SM"
					( Origin gFrontEnd )
				)
				( attribute "VALUE" "0.3UH"
					( Origin gFrontEnd )
				)
				( attribute "VER" "1"
					( Origin gFrontEnd )
				)
				( attribute "XY" "(11150,3950)"
					( Origin gFrontEnd )
				)
				( attribute "CHIPS_PART_NAME" "INDUCTOR"
					( Origin gPackager )
				)
				( attribute "CDS_PART_NAME" "INDUCTOR_SM-0.3UH,IND,D92183-0A"
					( Origin gPackager )
				)
				( objectStatus "L7A2" )
				( pin "ina"
					( attribute "PN" "1"
						( Origin gPackager )
					)
					( objectStatus "L7A2.1" )
				)
				( pin "inb"
					( attribute "PN" "2"
						( Origin gPackager )
					)
					( objectStatus "L7A2.2" )
				)
			)
			( gate "@baseboard_fab2_lib.baseboard_fab2(sch_1):page236_i14"
				( attribute "CDS_LIB" "mstr_discrete"
					( Origin gPackager )
				)
				( attribute "CDS_LOCATION" "R3L1"
					( Origin gPackager )
				)
				( attribute "CDS_SEC" "1"
					( Origin gPackager )
				)
				( attribute "LOCATION" "R3L1"
					( Origin gFrontEnd )
				)
				( attribute "MATERIAL" "CHIP"
					( Origin gFrontEnd )
				)
				( attribute "PACK_TYPE" "0402"
					( Origin gFrontEnd )
				)
				( attribute "PART_NUMBER" "G21796-090"
					( Origin gFrontEnd )
				)
				( attribute "PHYS_PAGE" "236"
					( Origin gFrontEnd )
				)
				( attribute "ROOM" "PVNN_PCH_STBY"
					( Origin gFrontEnd )
				)
				( attribute "ROT" "0"
					( Origin gFrontEnd )
				)
				( attribute "SEC" "1"
					( Origin gFrontEnd )
				)
				( attribute "SEC_TYPE" "0402"
					( Origin gFrontEnd )
				)
				( attribute "TOLERANCE" "1%"
					( Origin gFrontEnd )
				)
				( attribute "VALUE" "1.0"
					( Origin gFrontEnd )
				)
				( attribute "VER" "1"
					( Origin gFrontEnd )
				)
				( attribute "WATTAGE" "1/16W"
					( Origin gFrontEnd )
				)
				( attribute "XY" "(7175,5025)"
					( Origin gFrontEnd )
				)
				( attribute "CHIPS_PART_NAME" "RES"
					( Origin gPackager )
				)
				( attribute "CDS_PART_NAME" "RES_0402-1.0,1%,1/16W,CHIP,G21A"
					( Origin gPackager )
				)
				( objectStatus "R3L1" )
				( pin "a"
					( attribute "PN" "1"
						( Origin gPackager )
					)
					( objectStatus "R3L1.1" )
				)
				( pin "b"
					( attribute "PN" "2"
						( Origin gPackager )
					)
					( objectStatus "R3L1.2" )
				)
			)
			( gate "@baseboard_fab2_lib.baseboard_fab2(sch_1):page236_i16"
				( attribute "CDS_LIB" "mstr_discrete"
					( Origin gPackager )
				)
				( attribute "CDS_LOCATION" "C7A8"
					( Origin gPackager )
				)
				( attribute "CDS_SEC" "1"
					( Origin gPackager )
				)
				( attribute "LOCATION" "C7A8"
					( Origin gFrontEnd )
				)
				( attribute "MATERIAL" "X7R"
					( Origin gFrontEnd )
				)
				( attribute "PACK_TYPE" "0402"
					( Origin gFrontEnd )
				)
				( attribute "PART_NUMBER" "A36096-155"
					( Origin gFrontEnd )
				)
				( attribute "PHYS_PAGE" "236"
					( Origin gFrontEnd )
				)
				( attribute "ROOM" "PVNN_PCH_STBY"
					( Origin gFrontEnd )
				)
				( attribute "ROT" "0"
					( Origin gFrontEnd )
				)
				( attribute "SEC" "1"
					( Origin gFrontEnd )
				)
				( attribute "SEC_TYPE" "0402"
					( Origin gFrontEnd )
				)
				( attribute "TOLERANCE" "10%"
					( Origin gFrontEnd )
				)
				( attribute "VALUE" "0.22UF"
					( Origin gFrontEnd )
				)
				( attribute "VER" "1"
					( Origin gFrontEnd )
				)
				( attribute "VOLTAGE" "16V"
					( Units "uVoltage" "V" 1.000000)
					( Origin gFrontEnd )
				)
				( attribute "XY" "(7750,4550)"
					( Origin gFrontEnd )
				)
				( attribute "CHIPS_PART_NAME" "CAP"
					( Origin gPackager )
				)
				( attribute "CDS_PART_NAME" "CAP_0402-0.22UF,16V,10%,X7R,A3A"
					( Origin gPackager )
				)
				( objectStatus "C7A8" )
				( pin "a"
					( attribute "PN" "1"
						( Origin gPackager )
					)
					( objectStatus "C7A8.1" )
				)
				( pin "b"
					( attribute "PN" "2"
						( Origin gPackager )
					)
					( objectStatus "C7A8.2" )
				)
			)
			( gate "@baseboard_fab2_lib.baseboard_fab2(sch_1):page236_i17"
				( attribute "CDS_LIB" "dev_discrete"
					( Origin gPackager )
				)
				( attribute "CDS_LOCATION" "C3L1"
					( Origin gPackager )
				)
				( attribute "CDS_SEC" "1"
					( Origin gPackager )
				)
				( attribute "LOCATION" "C3L1"
					( Origin gFrontEnd )
				)
				( attribute "MATERIAL" "X6S"
					( Origin gFrontEnd )
				)
				( attribute "PACK_TYPE" "0402V"
					( Origin gFrontEnd )
				)
				( attribute "PART_NUMBER" "D97712-004"
					( Origin gFrontEnd )
				)
				( attribute "PHYS_PAGE" "236"
					( Origin gFrontEnd )
				)
				( attribute "ROOM" "PVNN_PCH_STBY"
					( Origin gFrontEnd )
				)
				( attribute "ROT" "2"
					( Origin gFrontEnd )
				)
				( attribute "SEC" "1"
					( Origin gFrontEnd )
				)
				( attribute "SEC_TYPE" "0402V"
					( Origin gFrontEnd )
				)
				( attribute "TOLERANCE" "10%"
					( Origin gFrontEnd )
				)
				( attribute "VALUE" "1.0UF"
					( Origin gFrontEnd )
				)
				( attribute "VER" "1"
					( Origin gFrontEnd )
				)
				( attribute "VOLTAGE" "6.3V"
					( Units "uVoltage" "V" 1.000000)
					( Origin gFrontEnd )
				)
				( attribute "XY" "(7625,4550)"
					( Origin gFrontEnd )
				)
				( attribute "CHIPS_PART_NAME" "CAP_A"
					( Origin gPackager )
				)
				( attribute "CDS_PART_NAME" "CAP_A_0402V-1.0UF,6.3V,10%,X6SA"
					( Origin gPackager )
				)
				( objectStatus "C3L1" )
				( pin "a"
					( attribute "PN" "1"
						( Origin gPackager )
					)
					( objectStatus "C3L1.1" )
				)
				( pin "b"
					( attribute "PN" "2"
						( Origin gPackager )
					)
					( objectStatus "C3L1.2" )
				)
			)
			( gate "@baseboard_fab2_lib.baseboard_fab2(sch_1):page236_i19"
				( attribute "CDS_LIB" "mstr_discrete"
					( Origin gPackager )
				)
				( attribute "CDS_LOCATION" "C7A6"
					( Origin gPackager )
				)
				( attribute "CDS_SEC" "1"
					( Origin gPackager )
				)
				( attribute "LOCATION" "C7A6"
					( Origin gFrontEnd )
				)
				( attribute "MATERIAL" "X6S"
					( Origin gFrontEnd )
				)
				( attribute "PACK_TYPE" "0402"
					( Origin gFrontEnd )
				)
				( attribute "PART_NUMBER" "D97712-011"
					( Origin gFrontEnd )
				)
				( attribute "PHYS_PAGE" "236"
					( Origin gFrontEnd )
				)
				( attribute "ROOM" "P1V05_PCH_STBY_VR"
					( Origin gFrontEnd )
				)
				( attribute "ROT" "0"
					( Origin gFrontEnd )
				)
				( attribute "SEC" "1"
					( Origin gFrontEnd )
				)
				( attribute "SEC_TYPE" "0402"
					( Origin gFrontEnd )
				)
				( attribute "TOLERANCE" "10%"
					( Origin gFrontEnd )
				)
				( attribute "VALUE" "1.0UF"
					( Origin gFrontEnd )
				)
				( attribute "VER" "1"
					( Origin gFrontEnd )
				)
				( attribute "VOLTAGE" "16V"
					( Units "uVoltage" "V" 1.000000)
					( Origin gFrontEnd )
				)
				( attribute "XY" "(6925,4500)"
					( Origin gFrontEnd )
				)
				( attribute "CHIPS_PART_NAME" "CAP"
					( Origin gPackager )
				)
				( attribute "CDS_PART_NAME" "CAP_0402-1.0UF,16V,10%,X6S,D97A"
					( Origin gPackager )
				)
				( objectStatus "C7A6" )
				( pin "a"
					( attribute "PN" "1"
						( Origin gPackager )
					)
					( objectStatus "C7A6.1" )
				)
				( pin "b"
					( attribute "PN" "2"
						( Origin gPackager )
					)
					( objectStatus "C7A6.2" )
				)
			)
			( gate "@baseboard_fab2_lib.baseboard_fab2(sch_1):page236_i20"
				( attribute "CDS_LIB" "dev_discrete"
					( Origin gPackager )
				)
				( attribute "CDS_LOCATION" "C7A39"
					( Origin gPackager )
				)
				( attribute "CDS_SEC" "1"
					( Origin gPackager )
				)
				( attribute "LOCATION" "C7A39"
					( Origin gFrontEnd )
				)
				( attribute "MATERIAL" "X7R"
					( Origin gFrontEnd )
				)
				( attribute "PACK_TYPE" "0402V"
					( Origin gFrontEnd )
				)
				( attribute "PART_NUMBER" "A36096-030"
					( Origin gFrontEnd )
				)
				( attribute "PHYS_PAGE" "236"
					( Origin gFrontEnd )
				)
				( attribute "ROOM" "PVNN_PCH_STBY"
					( Origin gFrontEnd )
				)
				( attribute "ROT" "0"
					( Origin gFrontEnd )
				)
				( attribute "SEC" "1"
					( Origin gFrontEnd )
				)
				( attribute "SEC_TYPE" "0402V"
					( Origin gFrontEnd )
				)
				( attribute "TOLERANCE" "10%"
					( Origin gFrontEnd )
				)
				( attribute "VALUE" "0.1UF"
					( Origin gFrontEnd )
				)
				( attribute "VER" "1"
					( Origin gFrontEnd )
				)
				( attribute "VOLTAGE" "16V"
					( Units "uVoltage" "V" 1.000000)
					( Origin gFrontEnd )
				)
				( attribute "XY" "(6550,4525)"
					( Origin gFrontEnd )
				)
				( attribute "CHIPS_PART_NAME" "CAP_A"
					( Origin gPackager )
				)
				( attribute "CDS_PART_NAME" "CAP_A_0402V-0.1UF,16V,10%,X7R,A"
					( Origin gPackager )
				)
				( objectStatus "C7A39" )
				( pin "a"
					( attribute "PN" "1"
						( Origin gPackager )
					)
					( objectStatus "C7A39.1" )
				)
				( pin "b"
					( attribute "PN" "2"
						( Origin gPackager )
					)
					( objectStatus "C7A39.2" )
				)
			)
			( gate "@baseboard_fab2_lib.baseboard_fab2(sch_1):page236_i21"
				( attribute "CDS_LIB" "mstr_discrete"
					( Origin gPackager )
				)
				( attribute "CDS_LOCATION" "C7A43"
					( Origin gPackager )
				)
				( attribute "CDS_SEC" "1"
					( Origin gPackager )
				)
				( attribute "LOCATION" "C7A43"
					( Origin gFrontEnd )
				)
				( attribute "MATERIAL" "X7R"
					( Origin gFrontEnd )
				)
				( attribute "PACK_TYPE" "0402"
					( Origin gFrontEnd )
				)
				( attribute "PART_NUMBER" "A36096-104"
					( Origin gFrontEnd )
				)
				( attribute "PHYS_PAGE" "236"
					( Origin gFrontEnd )
				)
				( attribute "ROOM" "PVNN_PCH_STBY"
					( Origin gFrontEnd )
				)
				( attribute "ROT" "2"
					( Origin gFrontEnd )
				)
				( attribute "SEC" "1"
					( Origin gFrontEnd )
				)
				( attribute "SEC_TYPE" "0402"
					( Origin gFrontEnd )
				)
				( attribute "SPOF" "TRUE"
					( Origin gFrontEnd )
				)
				( attribute "TOLERANCE" "10%"
					( Origin gFrontEnd )
				)
				( attribute "VALUE" "0.220UF"
					( Origin gFrontEnd )
				)
				( attribute "VER" "1"
					( Origin gFrontEnd )
				)
				( attribute "VOLTAGE" "16V"
					( Units "uVoltage" "V" 1.000000)
					( Origin gFrontEnd )
				)
				( attribute "XY" "(6825,3825)"
					( Origin gFrontEnd )
				)
				( attribute "CHIPS_PART_NAME" "CAP"
					( Origin gPackager )
				)
				( attribute "CDS_PART_NAME" "CAP_0402-0.220UF,16V,10%,X7R,AA"
					( Origin gPackager )
				)
				( objectStatus "C7A43" )
				( pin "a"
					( attribute "PN" "1"
						( Origin gPackager )
					)
					( objectStatus "C7A43.1" )
				)
				( pin "b"
					( attribute "PN" "2"
						( Origin gPackager )
					)
					( objectStatus "C7A43.2" )
				)
			)
			( gate "@baseboard_fab2_lib.baseboard_fab2(sch_1):page236_i22"
				( attribute "CDS_LIB" "mstr_discrete"
					( Origin gPackager )
				)
				( attribute "CDS_LOCATION" "C7A7"
					( Origin gPackager )
				)
				( attribute "CDS_SEC" "1"
					( Origin gPackager )
				)
				( attribute "LOCATION" "C7A7"
					( Origin gFrontEnd )
				)
				( attribute "MATERIAL" "X6S"
					( Origin gFrontEnd )
				)
				( attribute "PACK_TYPE" "0402"
					( Origin gFrontEnd )
				)
				( attribute "PART_NUMBER" "D97712-011"
					( Origin gFrontEnd )
				)
				( attribute "PHYS_PAGE" "236"
					( Origin gFrontEnd )
				)
				( attribute "ROOM" "PVNN_PCH_STBY"
					( Origin gFrontEnd )
				)
				( attribute "ROT" "0"
					( Origin gFrontEnd )
				)
				( attribute "SEC" "1"
					( Origin gFrontEnd )
				)
				( attribute "SEC_TYPE" "0402"
					( Origin gFrontEnd )
				)
				( attribute "TOLERANCE" "10%"
					( Origin gFrontEnd )
				)
				( attribute "VALUE" "1.0UF"
					( Origin gFrontEnd )
				)
				( attribute "VER" "1"
					( Origin gFrontEnd )
				)
				( attribute "VOLTAGE" "16V"
					( Units "uVoltage" "V" 1.000000)
					( Origin gFrontEnd )
				)
				( attribute "XY" "(6300,4500)"
					( Origin gFrontEnd )
				)
				( attribute "CHIPS_PART_NAME" "CAP"
					( Origin gPackager )
				)
				( attribute "CDS_PART_NAME" "CAP_0402-1.0UF,16V,10%,X6S,D97A"
					( Origin gPackager )
				)
				( objectStatus "C7A7" )
				( pin "a"
					( attribute "PN" "1"
						( Origin gPackager )
					)
					( objectStatus "C7A7.1" )
				)
				( pin "b"
					( attribute "PN" "2"
						( Origin gPackager )
					)
					( objectStatus "C7A7.2" )
				)
			)
			( gate "@baseboard_fab2_lib.baseboard_fab2(sch_1):page236_i23"
				( attribute "CDS_LIB" "mstr_discrete"
					( Origin gPackager )
				)
				( attribute "CDS_LOCATION" "C3L12"
					( Origin gPackager )
				)
				( attribute "CDS_SEC" "1"
					( Origin gPackager )
				)
				( attribute "LOCATION" "C3L12"
					( Origin gFrontEnd )
				)
				( attribute "MATERIAL" "X6S"
					( Origin gFrontEnd )
				)
				( attribute "PACK_TYPE" "0805"
					( Origin gFrontEnd )
				)
				( attribute "PART_NUMBER" "C95333-007"
					( Origin gFrontEnd )
				)
				( attribute "PHYS_PAGE" "236"
					( Origin gFrontEnd )
				)
				( attribute "ROOM" "PVNN_PCH_STBY"
					( Origin gFrontEnd )
				)
				( attribute "ROT" "0"
					( Origin gFrontEnd )
				)
				( attribute "SEC" "1"
					( Origin gFrontEnd )
				)
				( attribute "SEC_TYPE" "0805"
					( Origin gFrontEnd )
				)
				( attribute "TOLERANCE" "10%"
					( Origin gFrontEnd )
				)
				( attribute "VALUE" "10UF"
					( Origin gFrontEnd )
				)
				( attribute "VER" "1"
					( Origin gFrontEnd )
				)
				( attribute "VOLTAGE" "16V"
					( Units "uVoltage" "V" 1.000000)
					( Origin gFrontEnd )
				)
				( attribute "XY" "(6050,4525)"
					( Origin gFrontEnd )
				)
				( attribute "CHIPS_PART_NAME" "CAP"
					( Origin gPackager )
				)
				( attribute "CDS_PART_NAME" "CAP_0805-10UF,16V,10%,X6S,C953A"
					( Origin gPackager )
				)
				( objectStatus "C3L12" )
				( pin "a"
					( attribute "PN" "1"
						( Origin gPackager )
					)
					( objectStatus "C3L12.1" )
				)
				( pin "b"
					( attribute "PN" "2"
						( Origin gPackager )
					)
					( objectStatus "C3L12.2" )
				)
			)
			( gate "@baseboard_fab2_lib.baseboard_fab2(sch_1):page236_i24"
				( attribute "CDS_LIB" "mstr_discrete"
					( Origin gPackager )
				)
				( attribute "CDS_LOCATION" "C3L11"
					( Origin gPackager )
				)
				( attribute "CDS_SEC" "1"
					( Origin gPackager )
				)
				( attribute "LOCATION" "C3L11"
					( Origin gFrontEnd )
				)
				( attribute "MATERIAL" "X6S"
					( Origin gFrontEnd )
				)
				( attribute "PACK_TYPE" "0805"
					( Origin gFrontEnd )
				)
				( attribute "PART_NUMBER" "C95333-007"
					( Origin gFrontEnd )
				)
				( attribute "PHYS_PAGE" "236"
					( Origin gFrontEnd )
				)
				( attribute "ROOM" "PVNN_PCH_STBY"
					( Origin gFrontEnd )
				)
				( attribute "ROT" "0"
					( Origin gFrontEnd )
				)
				( attribute "SEC" "1"
					( Origin gFrontEnd )
				)
				( attribute "SEC_TYPE" "0805"
					( Origin gFrontEnd )
				)
				( attribute "TOLERANCE" "10%"
					( Origin gFrontEnd )
				)
				( attribute "VALUE" "10UF"
					( Origin gFrontEnd )
				)
				( attribute "VER" "1"
					( Origin gFrontEnd )
				)
				( attribute "VOLTAGE" "16V"
					( Units "uVoltage" "V" 1.000000)
					( Origin gFrontEnd )
				)
				( attribute "XY" "(5825,4500)"
					( Origin gFrontEnd )
				)
				( attribute "CHIPS_PART_NAME" "CAP"
					( Origin gPackager )
				)
				( attribute "CDS_PART_NAME" "CAP_0805-10UF,16V,10%,X6S,C953A"
					( Origin gPackager )
				)
				( objectStatus "C3L11" )
				( pin "a"
					( attribute "PN" "1"
						( Origin gPackager )
					)
					( objectStatus "C3L11.1" )
				)
				( pin "b"
					( attribute "PN" "2"
						( Origin gPackager )
					)
					( objectStatus "C3L11.2" )
				)
			)
			( gate "@baseboard_fab2_lib.baseboard_fab2(sch_1):page236_i26"
				( attribute "CDS_LIB" "mstr_discrete"
					( Origin gPackager )
				)
				( attribute "CDS_LOCATION" "C3L8"
					( Origin gPackager )
				)
				( attribute "CDS_SEC" "1"
					( Origin gPackager )
				)
				( attribute "LOCATION" "C3L8"
					( Origin gFrontEnd )
				)
				( attribute "MATERIAL" "X6S"
					( Origin gFrontEnd )
				)
				( attribute "PACK_TYPE" "0805"
					( Origin gFrontEnd )
				)
				( attribute "PART_NUMBER" "C95333-007"
					( Origin gFrontEnd )
				)
				( attribute "PHYS_PAGE" "236"
					( Origin gFrontEnd )
				)
				( attribute "ROOM" "PVNN_PCH_STBY"
					( Origin gFrontEnd )
				)
				( attribute "ROT" "0"
					( Origin gFrontEnd )
				)
				( attribute "SEC" "1"
					( Origin gFrontEnd )
				)
				( attribute "SEC_TYPE" "0805"
					( Origin gFrontEnd )
				)
				( attribute "TOLERANCE" "10%"
					( Origin gFrontEnd )
				)
				( attribute "VALUE" "10UF"
					( Origin gFrontEnd )
				)
				( attribute "VER" "1"
					( Origin gFrontEnd )
				)
				( attribute "VOLTAGE" "16V"
					( Units "uVoltage" "V" 1.000000)
					( Origin gFrontEnd )
				)
				( attribute "XY" "(5575,4525)"
					( Origin gFrontEnd )
				)
				( attribute "CHIPS_PART_NAME" "CAP"
					( Origin gPackager )
				)
				( attribute "CDS_PART_NAME" "CAP_0805-10UF,16V,10%,X6S,C953A"
					( Origin gPackager )
				)
				( objectStatus "C3L8" )
				( pin "a"
					( attribute "PN" "1"
						( Origin gPackager )
					)
					( objectStatus "C3L8.1" )
				)
				( pin "b"
					( attribute "PN" "2"
						( Origin gPackager )
					)
					( objectStatus "C3L8.2" )
				)
			)
			( gate "@baseboard_fab2_lib.baseboard_fab2(sch_1):page236_i29"
				( attribute "CDS_LIB" "mstr_discrete"
					( Origin gPackager )
				)
				( attribute "CDS_LOCATION" "C3L9"
					( Origin gPackager )
				)
				( attribute "CDS_SEC" "1"
					( Origin gPackager )
				)
				( attribute "LOCATION" "C3L9"
					( Origin gFrontEnd )
				)
				( attribute "MATERIAL" "X6S"
					( Origin gFrontEnd )
				)
				( attribute "PACK_TYPE" "0805"
					( Origin gFrontEnd )
				)
				( attribute "PART_NUMBER" "C95333-007"
					( Origin gFrontEnd )
				)
				( attribute "PHYS_PAGE" "236"
					( Origin gFrontEnd )
				)
				( attribute "ROOM" "P1V05_PCH_STBY_VR"
					( Origin gFrontEnd )
				)
				( attribute "ROT" "0"
					( Origin gFrontEnd )
				)
				( attribute "SEC" "1"
					( Origin gFrontEnd )
				)
				( attribute "SEC_TYPE" "0805"
					( Origin gFrontEnd )
				)
				( attribute "TOLERANCE" "10%"
					( Origin gFrontEnd )
				)
				( attribute "VALUE" "10UF"
					( Origin gFrontEnd )
				)
				( attribute "VER" "1"
					( Origin gFrontEnd )
				)
				( attribute "VOLTAGE" "16V"
					( Units "uVoltage" "V" 1.000000)
					( Origin gFrontEnd )
				)
				( attribute "XY" "(5600,2825)"
					( Origin gFrontEnd )
				)
				( attribute "CHIPS_PART_NAME" "CAP"
					( Origin gPackager )
				)
				( attribute "CDS_PART_NAME" "CAP_0805-10UF,16V,10%,X6S,C953A"
					( Origin gPackager )
				)
				( objectStatus "C3L9" )
				( pin "a"
					( attribute "PN" "1"
						( Origin gPackager )
					)
					( objectStatus "C3L9.1" )
				)
				( pin "b"
					( attribute "PN" "2"
						( Origin gPackager )
					)
					( objectStatus "C3L9.2" )
				)
			)
			( gate "@baseboard_fab2_lib.baseboard_fab2(sch_1):page236_i31"
				( attribute "CDS_LIB" "mstr_discrete"
					( Origin gPackager )
				)
				( attribute "CDS_LOCATION" "C3L7"
					( Origin gPackager )
				)
				( attribute "CDS_SEC" "1"
					( Origin gPackager )
				)
				( attribute "LOCATION" "C3L7"
					( Origin gFrontEnd )
				)
				( attribute "MATERIAL" "X6S"
					( Origin gFrontEnd )
				)
				( attribute "PACK_TYPE" "0805"
					( Origin gFrontEnd )
				)
				( attribute "PART_NUMBER" "C95333-007"
					( Origin gFrontEnd )
				)
				( attribute "PHYS_PAGE" "236"
					( Origin gFrontEnd )
				)
				( attribute "ROOM" "P1V05_PCH_STBY_VR"
					( Origin gFrontEnd )
				)
				( attribute "ROT" "0"
					( Origin gFrontEnd )
				)
				( attribute "SEC" "1"
					( Origin gFrontEnd )
				)
				( attribute "SEC_TYPE" "0805"
					( Origin gFrontEnd )
				)
				( attribute "TOLERANCE" "10%"
					( Origin gFrontEnd )
				)
				( attribute "VALUE" "10UF"
					( Origin gFrontEnd )
				)
				( attribute "VER" "1"
					( Origin gFrontEnd )
				)
				( attribute "VOLTAGE" "16V"
					( Units "uVoltage" "V" 1.000000)
					( Origin gFrontEnd )
				)
				( attribute "XY" "(5850,2850)"
					( Origin gFrontEnd )
				)
				( attribute "CHIPS_PART_NAME" "CAP"
					( Origin gPackager )
				)
				( attribute "CDS_PART_NAME" "CAP_0805-10UF,16V,10%,X6S,C953A"
					( Origin gPackager )
				)
				( objectStatus "C3L7" )
				( pin "a"
					( attribute "PN" "1"
						( Origin gPackager )
					)
					( objectStatus "C3L7.1" )
				)
				( pin "b"
					( attribute "PN" "2"
						( Origin gPackager )
					)
					( objectStatus "C3L7.2" )
				)
			)
			( gate "@baseboard_fab2_lib.baseboard_fab2(sch_1):page236_i32"
				( attribute "CDS_LIB" "mstr_discrete"
					( Origin gPackager )
				)
				( attribute "CDS_LOCATION" "C3L10"
					( Origin gPackager )
				)
				( attribute "CDS_SEC" "1"
					( Origin gPackager )
				)
				( attribute "LOCATION" "C3L10"
					( Origin gFrontEnd )
				)
				( attribute "MATERIAL" "X6S"
					( Origin gFrontEnd )
				)
				( attribute "PACK_TYPE" "0805"
					( Origin gFrontEnd )
				)
				( attribute "PART_NUMBER" "C95333-007"
					( Origin gFrontEnd )
				)
				( attribute "PHYS_PAGE" "236"
					( Origin gFrontEnd )
				)
				( attribute "ROOM" "P1V05_PCH_STBY_VR"
					( Origin gFrontEnd )
				)
				( attribute "ROT" "0"
					( Origin gFrontEnd )
				)
				( attribute "SEC" "1"
					( Origin gFrontEnd )
				)
				( attribute "SEC_TYPE" "0805"
					( Origin gFrontEnd )
				)
				( attribute "TOLERANCE" "10%"
					( Origin gFrontEnd )
				)
				( attribute "VALUE" "10UF"
					( Origin gFrontEnd )
				)
				( attribute "VER" "1"
					( Origin gFrontEnd )
				)
				( attribute "VOLTAGE" "16V"
					( Units "uVoltage" "V" 1.000000)
					( Origin gFrontEnd )
				)
				( attribute "XY" "(6100,2825)"
					( Origin gFrontEnd )
				)
				( attribute "CHIPS_PART_NAME" "CAP"
					( Origin gPackager )
				)
				( attribute "CDS_PART_NAME" "CAP_0805-10UF,16V,10%,X6S,C953A"
					( Origin gPackager )
				)
				( objectStatus "C3L10" )
				( pin "a"
					( attribute "PN" "1"
						( Origin gPackager )
					)
					( objectStatus "C3L10.1" )
				)
				( pin "b"
					( attribute "PN" "2"
						( Origin gPackager )
					)
					( objectStatus "C3L10.2" )
				)
			)
			( gate "@baseboard_fab2_lib.baseboard_fab2(sch_1):page236_i33"
				( attribute "CDS_LIB" "mstr_discrete"
					( Origin gPackager )
				)
				( attribute "CDS_LOCATION" "C7A9"
					( Origin gPackager )
				)
				( attribute "CDS_SEC" "1"
					( Origin gPackager )
				)
				( attribute "LOCATION" "C7A9"
					( Origin gFrontEnd )
				)
				( attribute "MATERIAL" "X6S"
					( Origin gFrontEnd )
				)
				( attribute "PACK_TYPE" "0402"
					( Origin gFrontEnd )
				)
				( attribute "PART_NUMBER" "D97712-011"
					( Origin gFrontEnd )
				)
				( attribute "PHYS_PAGE" "236"
					( Origin gFrontEnd )
				)
				( attribute "ROOM" "P1V05_PCH_STBY_VR"
					( Origin gFrontEnd )
				)
				( attribute "ROT" "0"
					( Origin gFrontEnd )
				)
				( attribute "SEC" "1"
					( Origin gFrontEnd )
				)
				( attribute "SEC_TYPE" "0402"
					( Origin gFrontEnd )
				)
				( attribute "TOLERANCE" "10%"
					( Origin gFrontEnd )
				)
				( attribute "VALUE" "1.0UF"
					( Origin gFrontEnd )
				)
				( attribute "VER" "1"
					( Origin gFrontEnd )
				)
				( attribute "VOLTAGE" "16V"
					( Units "uVoltage" "V" 1.000000)
					( Origin gFrontEnd )
				)
				( attribute "XY" "(6350,2825)"
					( Origin gFrontEnd )
				)
				( attribute "CHIPS_PART_NAME" "CAP"
					( Origin gPackager )
				)
				( attribute "CDS_PART_NAME" "CAP_0402-1.0UF,16V,10%,X6S,D97A"
					( Origin gPackager )
				)
				( objectStatus "C7A9" )
				( pin "a"
					( attribute "PN" "1"
						( Origin gPackager )
					)
					( objectStatus "C7A9.1" )
				)
				( pin "b"
					( attribute "PN" "2"
						( Origin gPackager )
					)
					( objectStatus "C7A9.2" )
				)
			)
			( gate "@baseboard_fab2_lib.baseboard_fab2(sch_1):page236_i34"
				( attribute "CDS_LIB" "mstr_discrete"
					( Origin gPackager )
				)
				( attribute "CDS_LOCATION" "C7A44"
					( Origin gPackager )
				)
				( attribute "CDS_SEC" "1"
					( Origin gPackager )
				)
				( attribute "LOCATION" "C7A44"
					( Origin gFrontEnd )
				)
				( attribute "MATERIAL" "X7R"
					( Origin gFrontEnd )
				)
				( attribute "PACK_TYPE" "0402"
					( Origin gFrontEnd )
				)
				( attribute "PART_NUMBER" "A36096-104"
					( Origin gFrontEnd )
				)
				( attribute "PHYS_PAGE" "236"
					( Origin gFrontEnd )
				)
				( attribute "ROOM" "P1V05_PCH_STBY_VR"
					( Origin gFrontEnd )
				)
				( attribute "ROT" "2"
					( Origin gFrontEnd )
				)
				( attribute "SEC" "1"
					( Origin gFrontEnd )
				)
				( attribute "SEC_TYPE" "0402"
					( Origin gFrontEnd )
				)
				( attribute "SPOF" "TRUE"
					( Origin gFrontEnd )
				)
				( attribute "TOLERANCE" "10%"
					( Origin gFrontEnd )
				)
				( attribute "VALUE" "0.220UF"
					( Origin gFrontEnd )
				)
				( attribute "VER" "1"
					( Origin gFrontEnd )
				)
				( attribute "VOLTAGE" "16V"
					( Units "uVoltage" "V" 1.000000)
					( Origin gFrontEnd )
				)
				( attribute "XY" "(6900,2075)"
					( Origin gFrontEnd )
				)
				( attribute "CHIPS_PART_NAME" "CAP"
					( Origin gPackager )
				)
				( attribute "CDS_PART_NAME" "CAP_0402-0.220UF,16V,10%,X7R,AA"
					( Origin gPackager )
				)
				( objectStatus "C7A44" )
				( pin "a"
					( attribute "PN" "1"
						( Origin gPackager )
					)
					( objectStatus "C7A44.1" )
				)
				( pin "b"
					( attribute "PN" "2"
						( Origin gPackager )
					)
					( objectStatus "C7A44.2" )
				)
			)
			( gate "@baseboard_fab2_lib.baseboard_fab2(sch_1):page236_i35"
				( attribute "CDS_LIB" "dev_discrete"
					( Origin gPackager )
				)
				( attribute "CDS_LOCATION" "C7A40"
					( Origin gPackager )
				)
				( attribute "CDS_SEC" "1"
					( Origin gPackager )
				)
				( attribute "LOCATION" "C7A40"
					( Origin gFrontEnd )
				)
				( attribute "MATERIAL" "X7R"
					( Origin gFrontEnd )
				)
				( attribute "PACK_TYPE" "0402V"
					( Origin gFrontEnd )
				)
				( attribute "PART_NUMBER" "A36096-030"
					( Origin gFrontEnd )
				)
				( attribute "PHYS_PAGE" "236"
					( Origin gFrontEnd )
				)
				( attribute "ROOM" "P1V05_PCH_STBY_VR"
					( Origin gFrontEnd )
				)
				( attribute "ROT" "0"
					( Origin gFrontEnd )
				)
				( attribute "SEC" "1"
					( Origin gFrontEnd )
				)
				( attribute "SEC_TYPE" "0402V"
					( Origin gFrontEnd )
				)
				( attribute "TOLERANCE" "10%"
					( Origin gFrontEnd )
				)
				( attribute "VALUE" "0.1UF"
					( Origin gFrontEnd )
				)
				( attribute "VER" "1"
					( Origin gFrontEnd )
				)
				( attribute "VOLTAGE" "16V"
					( Units "uVoltage" "V" 1.000000)
					( Origin gFrontEnd )
				)
				( attribute "XY" "(6575,2850)"
					( Origin gFrontEnd )
				)
				( attribute "CHIPS_PART_NAME" "CAP_A"
					( Origin gPackager )
				)
				( attribute "CDS_PART_NAME" "CAP_A_0402V-0.1UF,16V,10%,X7R,A"
					( Origin gPackager )
				)
				( objectStatus "C7A40" )
				( pin "a"
					( attribute "PN" "1"
						( Origin gPackager )
					)
					( objectStatus "C7A40.1" )
				)
				( pin "b"
					( attribute "PN" "2"
						( Origin gPackager )
					)
					( objectStatus "C7A40.2" )
				)
			)
			( gate "@baseboard_fab2_lib.baseboard_fab2(sch_1):page236_i36"
				( attribute "CDS_LIB" "mstr_discrete"
					( Origin gPackager )
				)
				( attribute "CDS_LOCATION" "C7A10"
					( Origin gPackager )
				)
				( attribute "CDS_SEC" "1"
					( Origin gPackager )
				)
				( attribute "LOCATION" "C7A10"
					( Origin gFrontEnd )
				)
				( attribute "MATERIAL" "X6S"
					( Origin gFrontEnd )
				)
				( attribute "PACK_TYPE" "0402"
					( Origin gFrontEnd )
				)
				( attribute "PART_NUMBER" "D97712-011"
					( Origin gFrontEnd )
				)
				( attribute "PHYS_PAGE" "236"
					( Origin gFrontEnd )
				)
				( attribute "ROOM" "P1V05_PCH_STBY_VR"
					( Origin gFrontEnd )
				)
				( attribute "ROT" "0"
					( Origin gFrontEnd )
				)
				( attribute "SEC" "1"
					( Origin gFrontEnd )
				)
				( attribute "SEC_TYPE" "0402"
					( Origin gFrontEnd )
				)
				( attribute "TOLERANCE" "10%"
					( Origin gFrontEnd )
				)
				( attribute "VALUE" "1.0UF"
					( Origin gFrontEnd )
				)
				( attribute "VER" "1"
					( Origin gFrontEnd )
				)
				( attribute "VOLTAGE" "16V"
					( Units "uVoltage" "V" 1.000000)
					( Origin gFrontEnd )
				)
				( attribute "XY" "(6850,2850)"
					( Origin gFrontEnd )
				)
				( attribute "CHIPS_PART_NAME" "CAP"
					( Origin gPackager )
				)
				( attribute "CDS_PART_NAME" "CAP_0402-1.0UF,16V,10%,X6S,D97A"
					( Origin gPackager )
				)
				( objectStatus "C7A10" )
				( pin "a"
					( attribute "PN" "1"
						( Origin gPackager )
					)
					( objectStatus "C7A10.1" )
				)
				( pin "b"
					( attribute "PN" "2"
						( Origin gPackager )
					)
					( objectStatus "C7A10.2" )
				)
			)
			( gate "@baseboard_fab2_lib.baseboard_fab2(sch_1):page236_i38"
				( attribute "CDS_LIB" "dev_discrete"
					( Origin gPackager )
				)
				( attribute "CDS_LOCATION" "C3L29"
					( Origin gPackager )
				)
				( attribute "CDS_SEC" "1"
					( Origin gPackager )
				)
				( attribute "LOCATION" "C3L29"
					( Origin gFrontEnd )
				)
				( attribute "MATERIAL" "X6S"
					( Origin gFrontEnd )
				)
				( attribute "PACK_TYPE" "0402V"
					( Origin gFrontEnd )
				)
				( attribute "PART_NUMBER" "D97712-004"
					( Origin gFrontEnd )
				)
				( attribute "PHYS_PAGE" "236"
					( Origin gFrontEnd )
				)
				( attribute "ROOM" "P1V05_PCH_STBY_VR"
					( Origin gFrontEnd )
				)
				( attribute "ROT" "2"
					( Origin gFrontEnd )
				)
				( attribute "SEC" "1"
					( Origin gFrontEnd )
				)
				( attribute "SEC_TYPE" "0402V"
					( Origin gFrontEnd )
				)
				( attribute "TOLERANCE" "10%"
					( Origin gFrontEnd )
				)
				( attribute "VALUE" "1.0UF"
					( Origin gFrontEnd )
				)
				( attribute "VER" "1"
					( Origin gFrontEnd )
				)
				( attribute "VOLTAGE" "6.3V"
					( Units "uVoltage" "V" 1.000000)
					( Origin gFrontEnd )
				)
				( attribute "XY" "(7550,2850)"
					( Origin gFrontEnd )
				)
				( attribute "CHIPS_PART_NAME" "CAP_A"
					( Origin gPackager )
				)
				( attribute "CDS_PART_NAME" "CAP_A_0402V-1.0UF,6.3V,10%,X6SA"
					( Origin gPackager )
				)
				( objectStatus "C3L29" )
				( pin "a"
					( attribute "PN" "1"
						( Origin gPackager )
					)
					( objectStatus "C3L29.1" )
				)
				( pin "b"
					( attribute "PN" "2"
						( Origin gPackager )
					)
					( objectStatus "C3L29.2" )
				)
			)
			( gate "@baseboard_fab2_lib.baseboard_fab2(sch_1):page236_i39"
				( attribute "CDS_LIB" "mstr_discrete"
					( Origin gPackager )
				)
				( attribute "CDS_LOCATION" "C7A41"
					( Origin gPackager )
				)
				( attribute "CDS_SEC" "1"
					( Origin gPackager )
				)
				( attribute "LOCATION" "C7A41"
					( Origin gFrontEnd )
				)
				( attribute "MATERIAL" "X7R"
					( Origin gFrontEnd )
				)
				( attribute "PACK_TYPE" "0402"
					( Origin gFrontEnd )
				)
				( attribute "PART_NUMBER" "A36096-155"
					( Origin gFrontEnd )
				)
				( attribute "PHYS_PAGE" "236"
					( Origin gFrontEnd )
				)
				( attribute "ROOM" "P1V05_PCH_STBY_VR"
					( Origin gFrontEnd )
				)
				( attribute "ROT" "0"
					( Origin gFrontEnd )
				)
				( attribute "SEC" "1"
					( Origin gFrontEnd )
				)
				( attribute "SEC_TYPE" "0402"
					( Origin gFrontEnd )
				)
				( attribute "TOLERANCE" "10%"
					( Origin gFrontEnd )
				)
				( attribute "VALUE" "0.22UF"
					( Origin gFrontEnd )
				)
				( attribute "VER" "1"
					( Origin gFrontEnd )
				)
				( attribute "VOLTAGE" "16V"
					( Units "uVoltage" "V" 1.000000)
					( Origin gFrontEnd )
				)
				( attribute "XY" "(7700,2850)"
					( Origin gFrontEnd )
				)
				( attribute "CHIPS_PART_NAME" "CAP"
					( Origin gPackager )
				)
				( attribute "CDS_PART_NAME" "CAP_0402-0.22UF,16V,10%,X7R,A3A"
					( Origin gPackager )
				)
				( objectStatus "C7A41" )
				( pin "a"
					( attribute "PN" "1"
						( Origin gPackager )
					)
					( objectStatus "C7A41.1" )
				)
				( pin "b"
					( attribute "PN" "2"
						( Origin gPackager )
					)
					( objectStatus "C7A41.2" )
				)
			)
			( gate "@baseboard_fab2_lib.baseboard_fab2(sch_1):page236_i41"
				( attribute "CDS_LIB" "mstr_discrete"
					( Origin gPackager )
				)
				( attribute "CDS_LOCATION" "R3L4"
					( Origin gPackager )
				)
				( attribute "CDS_SEC" "1"
					( Origin gPackager )
				)
				( attribute "LOCATION" "R3L4"
					( Origin gFrontEnd )
				)
				( attribute "MATERIAL" "CHIP"
					( Origin gFrontEnd )
				)
				( attribute "PACK_TYPE" "0402"
					( Origin gFrontEnd )
				)
				( attribute "PART_NUMBER" "G21796-090"
					( Origin gFrontEnd )
				)
				( attribute "PHYS_PAGE" "236"
					( Origin gFrontEnd )
				)
				( attribute "ROOM" "P1V05_PCH_STBY_VR"
					( Origin gFrontEnd )
				)
				( attribute "ROT" "0"
					( Origin gFrontEnd )
				)
				( attribute "SEC" "1"
					( Origin gFrontEnd )
				)
				( attribute "SEC_TYPE" "0402"
					( Origin gFrontEnd )
				)
				( attribute "TOLERANCE" "1%"
					( Origin gFrontEnd )
				)
				( attribute "VALUE" "1.0"
					( Origin gFrontEnd )
				)
				( attribute "VER" "1"
					( Origin gFrontEnd )
				)
				( attribute "WATTAGE" "1/16W"
					( Origin gFrontEnd )
				)
				( attribute "XY" "(7075,3275)"
					( Origin gFrontEnd )
				)
				( attribute "CHIPS_PART_NAME" "RES"
					( Origin gPackager )
				)
				( attribute "CDS_PART_NAME" "RES_0402-1.0,1%,1/16W,CHIP,G21A"
					( Origin gPackager )
				)
				( objectStatus "R3L4" )
				( pin "a"
					( attribute "PN" "1"
						( Origin gPackager )
					)
					( objectStatus "R3L4.1" )
				)
				( pin "b"
					( attribute "PN" "2"
						( Origin gPackager )
					)
					( objectStatus "R3L4.2" )
				)
			)
			( gate "@baseboard_fab2_lib.baseboard_fab2(sch_1):page236_i45"
				( attribute "CDS_LIB" "mstr_discrete"
					( Origin gPackager )
				)
				( attribute "CDS_LOCATION" "L7A4"
					( Origin gPackager )
				)
				( attribute "CDS_SEC" "1"
					( Origin gPackager )
				)
				( attribute "LOCATION" "L7A4"
					( Origin gFrontEnd )
				)
				( attribute "MATERIAL" "IND"
					( Origin gFrontEnd )
				)
				( attribute "PACK_TYPE" "SM"
					( Origin gFrontEnd )
				)
				( attribute "PART_NUMBER" "D92183-036"
					( Origin gFrontEnd )
				)
				( attribute "PHYS_PAGE" "236"
					( Origin gFrontEnd )
				)
				( attribute "ROOM" "P1V05_PCH_STBY_VR"
					( Origin gFrontEnd )
				)
				( attribute "ROT" "0"
					( Origin gFrontEnd )
				)
				( attribute "SEC" "1"
					( Origin gFrontEnd )
				)
				( attribute "SEC_TYPE" "SM"
					( Origin gFrontEnd )
				)
				( attribute "VALUE" "0.3UH"
					( Origin gFrontEnd )
				)
				( attribute "VER" "1"
					( Origin gFrontEnd )
				)
				( attribute "XY" "(11200,2250)"
					( Origin gFrontEnd )
				)
				( attribute "CHIPS_PART_NAME" "INDUCTOR"
					( Origin gPackager )
				)
				( attribute "CDS_PART_NAME" "INDUCTOR_SM-0.3UH,IND,D92183-0A"
					( Origin gPackager )
				)
				( objectStatus "L7A4" )
				( pin "ina"
					( attribute "PN" "1"
						( Origin gPackager )
					)
					( objectStatus "L7A4.1" )
				)
				( pin "inb"
					( attribute "PN" "2"
						( Origin gPackager )
					)
					( objectStatus "L7A4.2" )
				)
			)
			( gate "@baseboard_fab2_lib.baseboard_fab2(sch_1):page236_i46"
				( attribute "BOM_COST" "PROC_VRD_PVCCIO_CPU0"
					( Origin gFrontEnd )
				)
				( attribute "CDS_LIB" "mstr_discrete"
					( Origin gPackager )
				)
				( attribute "CDS_LOCATION" "C7A42"
					( Origin gPackager )
				)
				( attribute "CDS_SEC" "1"
					( Origin gPackager )
				)
				( attribute "LOCATION" "C7A42"
					( Origin gFrontEnd )
				)
				( attribute "MATERIAL" "X6S"
					( Origin gFrontEnd )
				)
				( attribute "PACK_TYPE" "0805LF"
					( Origin gFrontEnd )
				)
				( attribute "PART_NUMBER" "C95333-002"
					( Origin gFrontEnd )
				)
				( attribute "PHYS_PAGE" "236"
					( Origin gFrontEnd )
				)
				( attribute "ROOM" "P1V05_PCH_STBY_VR"
					( Origin gFrontEnd )
				)
				( attribute "ROT" "0"
					( Origin gFrontEnd )
				)
				( attribute "SEC" "1"
					( Origin gFrontEnd )
				)
				( attribute "SEC_TYPE" "0805LF"
					( Origin gFrontEnd )
				)
				( attribute "TOLERANCE" "20%"
					( Origin gFrontEnd )
				)
				( attribute "VALUE" "22UF"
					( Origin gFrontEnd )
				)
				( attribute "VER" "1"
					( Origin gFrontEnd )
				)
				( attribute "VOLTAGE" "4V"
					( Units "uVoltage" "V" 1.000000)
					( Origin gFrontEnd )
				)
				( attribute "XY" "(11500,2025)"
					( Origin gFrontEnd )
				)
				( attribute "CHIPS_PART_NAME" "CAP"
					( Origin gPackager )
				)
				( attribute "CDS_PART_NAME" "CAP_0805LF-22UF,4V,20%,X6S,C95A"
					( Origin gPackager )
				)
				( objectStatus "C7A42" )
				( pin "a"
					( attribute "PN" "1"
						( Origin gPackager )
					)
					( objectStatus "C7A42.1" )
				)
				( pin "b"
					( attribute "PN" "2"
						( Origin gPackager )
					)
					( objectStatus "C7A42.2" )
				)
			)
			( gate "@baseboard_fab2_lib.baseboard_fab2(sch_1):page236_i56"
				( attribute "BOM_COST" "P1V05_PCH_STBY"
					( Origin gFrontEnd )
				)
				( attribute "CDS_LIB" "mstr_discrete"
					( Origin gPackager )
				)
				( attribute "CDS_LOCATION" "R8B14"
					( Origin gPackager )
				)
				( attribute "CDS_SEC" "1"
					( Origin gPackager )
				)
				( attribute "LOCATION" "R8B14"
					( Origin gFrontEnd )
				)
				( attribute "MATERIAL" "CHIP"
					( Origin gFrontEnd )
				)
				( attribute "PACK_TYPE" "0402"
					( Origin gFrontEnd )
				)
				( attribute "PART_NUMBER" "G21497-005"
					( Origin gFrontEnd )
				)
				( attribute "PHYS_PAGE" "236"
					( Origin gFrontEnd )
				)
				( attribute "ROOM" "P1V05_PCH_STBY"
					( Origin gFrontEnd )
				)
				( attribute "ROT" "0"
					( Origin gFrontEnd )
				)
				( attribute "SEC" "1"
					( Origin gFrontEnd )
				)
				( attribute "SEC_TYPE" "0402"
					( Origin gFrontEnd )
				)
				( attribute "TOLERANCE" "5%"
					( Origin gFrontEnd )
				)
				( attribute "VALUE" "0.0"
					( Origin gFrontEnd )
				)
				( attribute "VER" "1"
					( Origin gFrontEnd )
				)
				( attribute "WATTAGE" "1/16W"
					( Origin gFrontEnd )
				)
				( attribute "XY" "(7350,1300)"
					( Origin gFrontEnd )
				)
				( attribute "CHIPS_PART_NAME" "RES"
					( Origin gPackager )
				)
				( attribute "CDS_PART_NAME" "RES_0402-0.0,5%,1/16W,CHIP,G21A"
					( Origin gPackager )
				)
				( objectStatus "R8B14" )
				( pin "a"
					( attribute "PN" "1"
						( Origin gPackager )
					)
					( objectStatus "R8B14.1" )
				)
				( pin "b"
					( attribute "PN" "2"
						( Origin gPackager )
					)
					( objectStatus "R8B14.2" )
				)
			)
			( gate "@baseboard_fab2_lib.baseboard_fab2(sch_1):page236_i57"
				( attribute "BOM_COST" "P1V05_PCH_STBY"
					( Origin gFrontEnd )
				)
				( attribute "CDS_LIB" "mstr_discrete"
					( Origin gPackager )
				)
				( attribute "CDS_LOCATION" "R8B15"
					( Origin gPackager )
				)
				( attribute "CDS_SEC" "1"
					( Origin gPackager )
				)
				( attribute "LOCATION" "R8B15"
					( Origin gFrontEnd )
				)
				( attribute "MATERIAL" "EMPTY"
					( Origin gFrontEnd )
				)
				( attribute "NO_XNET_CONNECTION" "1"
					( Origin gFrontEnd )
				)
				( attribute "PACK_TYPE" "0402"
					( Origin gFrontEnd )
				)
				( attribute "PART_NUMBER" "G21796-017"
					( Origin gFrontEnd )
				)
				( attribute "PHYS_PAGE" "236"
					( Origin gFrontEnd )
				)
				( attribute "ROOM" "P1V05_PCH_STBY"
					( Origin gFrontEnd )
				)
				( attribute "ROT" "0"
					( Origin gFrontEnd )
				)
				( attribute "SEC" "1"
					( Origin gFrontEnd )
				)
				( attribute "SEC_TYPE" "0402"
					( Origin gFrontEnd )
				)
				( attribute "TOLERANCE" "1%"
					( Origin gFrontEnd )
				)
				( attribute "VALUE" "100.0"
					( Origin gFrontEnd )
				)
				( attribute "VER" "2"
					( Origin gFrontEnd )
				)
				( attribute "WATTAGE" "1/16W"
					( Origin gFrontEnd )
				)
				( attribute "XY" "(7000,1050)"
					( Origin gFrontEnd )
				)
				( attribute "CHIPS_PART_NAME" "RES"
					( Origin gPackager )
				)
				( attribute "CDS_PART_NAME" "RES_0402-100.0,1%,1/16W,EMPTY,A"
					( Origin gPackager )
				)
				( objectStatus "R8B15" )
				( pin "a"
					( attribute "PN" "1"
						( Origin gPackager )
					)
					( objectStatus "R8B15.1" )
				)
				( pin "b"
					( attribute "PN" "2"
						( Origin gPackager )
					)
					( objectStatus "R8B15.2" )
				)
			)
			( gate "@baseboard_fab2_lib.baseboard_fab2(sch_1):page236_i59"
				( attribute "BOM_COST" "P1V05_PCH_STBY"
					( Origin gFrontEnd )
				)
				( attribute "CDS_LIB" "mstr_discrete"
					( Origin gPackager )
				)
				( attribute "CDS_LOCATION" "R8B12"
					( Origin gPackager )
				)
				( attribute "CDS_SEC" "1"
					( Origin gPackager )
				)
				( attribute "LOCATION" "R8B12"
					( Origin gFrontEnd )
				)
				( attribute "MATERIAL" "CHIP"
					( Origin gFrontEnd )
				)
				( attribute "PACK_TYPE" "0402"
					( Origin gFrontEnd )
				)
				( attribute "PART_NUMBER" "G21497-005"
					( Origin gFrontEnd )
				)
				( attribute "PHYS_PAGE" "236"
					( Origin gFrontEnd )
				)
				( attribute "ROOM" "P1V05_PCH_STBY"
					( Origin gFrontEnd )
				)
				( attribute "ROT" "0"
					( Origin gFrontEnd )
				)
				( attribute "SEC" "1"
					( Origin gFrontEnd )
				)
				( attribute "SEC_TYPE" "0402"
					( Origin gFrontEnd )
				)
				( attribute "TOLERANCE" "5%"
					( Origin gFrontEnd )
				)
				( attribute "VALUE" "0.0"
					( Origin gFrontEnd )
				)
				( attribute "VER" "1"
					( Origin gFrontEnd )
				)
				( attribute "WATTAGE" "1/16W"
					( Origin gFrontEnd )
				)
				( attribute "XY" "(7325,850)"
					( Origin gFrontEnd )
				)
				( attribute "CHIPS_PART_NAME" "RES"
					( Origin gPackager )
				)
				( attribute "CDS_PART_NAME" "RES_0402-0.0,5%,1/16W,CHIP,G21A"
					( Origin gPackager )
				)
				( objectStatus "R8B12" )
				( pin "a"
					( attribute "PN" "1"
						( Origin gPackager )
					)
					( objectStatus "R8B12.1" )
				)
				( pin "b"
					( attribute "PN" "2"
						( Origin gPackager )
					)
					( objectStatus "R8B12.2" )
				)
			)
			( gate "@baseboard_fab2_lib.baseboard_fab2(sch_1):page236_i63"
				( attribute "BOM_COST" "PVNN_PCH_STBY"
					( Origin gFrontEnd )
				)
				( attribute "CDS_LIB" "mstr_discrete"
					( Origin gPackager )
				)
				( attribute "CDS_LOCATION" "C7A13"
					( Origin gPackager )
				)
				( attribute "CDS_SEC" "1"
					( Origin gPackager )
				)
				( attribute "LOCATION" "C7A13"
					( Origin gFrontEnd )
				)
				( attribute "MATERIAL" "X5R"
					( Origin gFrontEnd )
				)
				( attribute "PACK_TYPE" "1210"
					( Origin gFrontEnd )
				)
				( attribute "PART_NUMBER" "644066-127"
					( Origin gFrontEnd )
				)
				( attribute "PHYS_PAGE" "236"
					( Origin gFrontEnd )
				)
				( attribute "ROOM" "PVNN_PCH_STBY"
					( Origin gFrontEnd )
				)
				( attribute "ROT" "2"
					( Origin gFrontEnd )
				)
				( attribute "SEC" "1"
					( Origin gPackager )
				)
				( attribute "TOLERANCE" "20%"
					( Origin gFrontEnd )
				)
				( attribute "VALUE" "100UF"
					( Origin gFrontEnd )
				)
				( attribute "VER" "1"
					( Origin gFrontEnd )
				)
				( attribute "VOLTAGE" "16V"
					( Units "uVoltage" "V" 1.000000)
					( Origin gFrontEnd )
				)
				( attribute "XY" "(12350,1225)"
					( Origin gFrontEnd )
				)
				( attribute "CHIPS_PART_NAME" "CAP"
					( Origin gPackager )
				)
				( attribute "CDS_PART_NAME" "CAP_1210-100UF,16V,20%,X5R,644A"
					( Origin gPackager )
				)
				( objectStatus "C7A13" )
				( pin "a"
					( attribute "PN" "1"
						( Origin gPackager )
					)
					( objectStatus "C7A13.1" )
				)
				( pin "b"
					( attribute "PN" "2"
						( Origin gPackager )
					)
					( objectStatus "C7A13.2" )
				)
			)
			( gate "@baseboard_fab2_lib.baseboard_fab2(sch_1):page236_i65"
				( attribute "BOM_COST" "PVNN_PCH_STBY"
					( Origin gFrontEnd )
				)
				( attribute "CDS_LIB" "mstr_discrete"
					( Origin gPackager )
				)
				( attribute "CDS_LOCATION" "C7A14"
					( Origin gPackager )
				)
				( attribute "CDS_SEC" "1"
					( Origin gPackager )
				)
				( attribute "LOCATION" "C7A14"
					( Origin gFrontEnd )
				)
				( attribute "MATERIAL" "X5R"
					( Origin gFrontEnd )
				)
				( attribute "PACK_TYPE" "1210"
					( Origin gFrontEnd )
				)
				( attribute "PART_NUMBER" "644066-127"
					( Origin gFrontEnd )
				)
				( attribute "PHYS_PAGE" "236"
					( Origin gFrontEnd )
				)
				( attribute "ROOM" "PVNN_PCH_STBY"
					( Origin gFrontEnd )
				)
				( attribute "ROT" "2"
					( Origin gFrontEnd )
				)
				( attribute "SEC" "1"
					( Origin gPackager )
				)
				( attribute "TOLERANCE" "20%"
					( Origin gFrontEnd )
				)
				( attribute "VALUE" "100UF"
					( Origin gFrontEnd )
				)
				( attribute "VER" "1"
					( Origin gFrontEnd )
				)
				( attribute "VOLTAGE" "16V"
					( Units "uVoltage" "V" 1.000000)
					( Origin gFrontEnd )
				)
				( attribute "XY" "(11975,1250)"
					( Origin gFrontEnd )
				)
				( attribute "CHIPS_PART_NAME" "CAP"
					( Origin gPackager )
				)
				( attribute "CDS_PART_NAME" "CAP_1210-100UF,16V,20%,X5R,644A"
					( Origin gPackager )
				)
				( objectStatus "C7A14" )
				( pin "a"
					( attribute "PN" "1"
						( Origin gPackager )
					)
					( objectStatus "C7A14.1" )
				)
				( pin "b"
					( attribute "PN" "2"
						( Origin gPackager )
					)
					( objectStatus "C7A14.2" )
				)
			)
			( gate "@baseboard_fab2_lib.baseboard_fab2(sch_1):page236_i71"
				( attribute "CDS_LIB" "mstr_discrete"
					( Origin gPackager )
				)
				( attribute "CDS_LOCATION" "C3L18"
					( Origin gPackager )
				)
				( attribute "CDS_SEC" "1"
					( Origin gPackager )
				)
				( attribute "LOCATION" "C3L18"
					( Origin gFrontEnd )
				)
				( attribute "MATERIAL" "ALUM"
					( Origin gFrontEnd )
				)
				( attribute "PACK_TYPE" "SM"
					( Origin gFrontEnd )
				)
				( attribute "PART_NUMBER" "699013-031"
					( Origin gFrontEnd )
				)
				( attribute "PHYS_PAGE" "236"
					( Origin gFrontEnd )
				)
				( attribute "ROOM" "PVNN_PCH_STBY"
					( Origin gFrontEnd )
				)
				( attribute "ROT" "0"
					( Origin gFrontEnd )
				)
				( attribute "SEC" "1"
					( Origin gFrontEnd )
				)
				( attribute "SEC_TYPE" "SM"
					( Origin gFrontEnd )
				)
				( attribute "TOLERANCE" "20%"
					( Origin gFrontEnd )
				)
				( attribute "VALUE" "470UF"
					( Origin gFrontEnd )
				)
				( attribute "VER" "1"
					( Origin gFrontEnd )
				)
				( attribute "VOLTAGE" "2V"
					( Units "uVoltage" "V" 1.000000)
					( Origin gFrontEnd )
				)
				( attribute "XY" "(11875,3750)"
					( Origin gFrontEnd )
				)
				( attribute "CHIPS_PART_NAME" "CAPP"
					( Origin gPackager )
				)
				( attribute "CDS_PART_NAME" "CAPP_SM-470UF,2V,20%,ALUM,6990A"
					( Origin gPackager )
				)
				( objectStatus "C3L18" )
				( pin "a"
					( attribute "PN" "1"
						( Origin gPackager )
					)
					( objectStatus "C3L18.1" )
				)
				( pin "b"
					( attribute "PN" "2"
						( Origin gPackager )
					)
					( objectStatus "C3L18.2" )
				)
			)
			( gate "@baseboard_fab2_lib.baseboard_fab2(sch_1):page236_i73"
				( attribute "CDS_LIB" "mstr_discrete"
					( Origin gPackager )
				)
				( attribute "CDS_LOCATION" "C3L20"
					( Origin gPackager )
				)
				( attribute "CDS_SEC" "1"
					( Origin gPackager )
				)
				( attribute "LOCATION" "C3L20"
					( Origin gFrontEnd )
				)
				( attribute "MATERIAL" "ALUM"
					( Origin gFrontEnd )
				)
				( attribute "PACK_TYPE" "SM"
					( Origin gFrontEnd )
				)
				( attribute "PART_NUMBER" "699013-031"
					( Origin gFrontEnd )
				)
				( attribute "PHYS_PAGE" "236"
					( Origin gFrontEnd )
				)
				( attribute "ROOM" "PVNN_PCH_STBY"
					( Origin gFrontEnd )
				)
				( attribute "ROT" "0"
					( Origin gFrontEnd )
				)
				( attribute "SEC" "1"
					( Origin gFrontEnd )
				)
				( attribute "SEC_TYPE" "SM"
					( Origin gFrontEnd )
				)
				( attribute "TOLERANCE" "20%"
					( Origin gFrontEnd )
				)
				( attribute "VALUE" "470UF"
					( Origin gFrontEnd )
				)
				( attribute "VER" "1"
					( Origin gFrontEnd )
				)
				( attribute "VOLTAGE" "2V"
					( Units "uVoltage" "V" 1.000000)
					( Origin gFrontEnd )
				)
				( attribute "XY" "(12175,3750)"
					( Origin gFrontEnd )
				)
				( attribute "CHIPS_PART_NAME" "CAPP"
					( Origin gPackager )
				)
				( attribute "CDS_PART_NAME" "CAPP_SM-470UF,2V,20%,ALUM,6990A"
					( Origin gPackager )
				)
				( objectStatus "C3L20" )
				( pin "a"
					( attribute "PN" "1"
						( Origin gPackager )
					)
					( objectStatus "C3L20.1" )
				)
				( pin "b"
					( attribute "PN" "2"
						( Origin gPackager )
					)
					( objectStatus "C3L20.2" )
				)
			)
			( gate "@baseboard_fab2_lib.baseboard_fab2(sch_1):page236_i74"
				( attribute "CDS_LIB" "mstr_discrete"
					( Origin gPackager )
				)
				( attribute "CDS_LOCATION" "C3L21"
					( Origin gPackager )
				)
				( attribute "CDS_SEC" "1"
					( Origin gPackager )
				)
				( attribute "LOCATION" "C3L21"
					( Origin gFrontEnd )
				)
				( attribute "MATERIAL" "ALUM"
					( Origin gFrontEnd )
				)
				( attribute "PACK_TYPE" "SM"
					( Origin gFrontEnd )
				)
				( attribute "PART_NUMBER" "699013-031"
					( Origin gFrontEnd )
				)
				( attribute "PHYS_PAGE" "236"
					( Origin gFrontEnd )
				)
				( attribute "ROOM" "PVNN_PCH_STBY"
					( Origin gFrontEnd )
				)
				( attribute "ROT" "0"
					( Origin gFrontEnd )
				)
				( attribute "SEC" "1"
					( Origin gFrontEnd )
				)
				( attribute "SEC_TYPE" "SM"
					( Origin gFrontEnd )
				)
				( attribute "TOLERANCE" "20%"
					( Origin gFrontEnd )
				)
				( attribute "VALUE" "470UF"
					( Origin gFrontEnd )
				)
				( attribute "VER" "1"
					( Origin gFrontEnd )
				)
				( attribute "VOLTAGE" "2V"
					( Units "uVoltage" "V" 1.000000)
					( Origin gFrontEnd )
				)
				( attribute "XY" "(12450,3750)"
					( Origin gFrontEnd )
				)
				( attribute "CHIPS_PART_NAME" "CAPP"
					( Origin gPackager )
				)
				( attribute "CDS_PART_NAME" "CAPP_SM-470UF,2V,20%,ALUM,6990A"
					( Origin gPackager )
				)
				( objectStatus "C3L21" )
				( pin "a"
					( attribute "PN" "1"
						( Origin gPackager )
					)
					( objectStatus "C3L21.1" )
				)
				( pin "b"
					( attribute "PN" "2"
						( Origin gPackager )
					)
					( objectStatus "C3L21.2" )
				)
			)
			( gate "@baseboard_fab2_lib.baseboard_fab2(sch_1):page236_i75"
				( attribute "CDS_LIB" "mstr_discrete"
					( Origin gPackager )
				)
				( attribute "CDS_LOCATION" "C7A27"
					( Origin gPackager )
				)
				( attribute "CDS_SEC" "1"
					( Origin gPackager )
				)
				( attribute "LOCATION" "C7A27"
					( Origin gFrontEnd )
				)
				( attribute "MATERIAL" "ALUM"
					( Origin gFrontEnd )
				)
				( attribute "PACK_TYPE" "SM"
					( Origin gFrontEnd )
				)
				( attribute "PART_NUMBER" "699013-031"
					( Origin gFrontEnd )
				)
				( attribute "PHYS_PAGE" "236"
					( Origin gFrontEnd )
				)
				( attribute "ROOM" "PVNN_PCH_STBY"
					( Origin gFrontEnd )
				)
				( attribute "ROT" "0"
					( Origin gFrontEnd )
				)
				( attribute "SEC" "1"
					( Origin gFrontEnd )
				)
				( attribute "SEC_TYPE" "SM"
					( Origin gFrontEnd )
				)
				( attribute "TOLERANCE" "20%"
					( Origin gFrontEnd )
				)
				( attribute "VALUE" "470UF"
					( Origin gFrontEnd )
				)
				( attribute "VER" "1"
					( Origin gFrontEnd )
				)
				( attribute "VOLTAGE" "2V"
					( Units "uVoltage" "V" 1.000000)
					( Origin gFrontEnd )
				)
				( attribute "XY" "(12700,3750)"
					( Origin gFrontEnd )
				)
				( attribute "CHIPS_PART_NAME" "CAPP"
					( Origin gPackager )
				)
				( attribute "CDS_PART_NAME" "CAPP_SM-470UF,2V,20%,ALUM,6990A"
					( Origin gPackager )
				)
				( objectStatus "C7A27" )
				( pin "a"
					( attribute "PN" "1"
						( Origin gPackager )
					)
					( objectStatus "C7A27.1" )
				)
				( pin "b"
					( attribute "PN" "2"
						( Origin gPackager )
					)
					( objectStatus "C7A27.2" )
				)
			)
			( gate "@baseboard_fab2_lib.baseboard_fab2(sch_1):page236_i76"
				( attribute "CDS_LIB" "mstr_discrete"
					( Origin gPackager )
				)
				( attribute "CDS_LOCATION" "C3L19"
					( Origin gPackager )
				)
				( attribute "CDS_SEC" "1"
					( Origin gPackager )
				)
				( attribute "LOCATION" "C3L19"
					( Origin gFrontEnd )
				)
				( attribute "MATERIAL" "ALUM"
					( Origin gFrontEnd )
				)
				( attribute "PACK_TYPE" "SM"
					( Origin gFrontEnd )
				)
				( attribute "PART_NUMBER" "699013-031"
					( Origin gFrontEnd )
				)
				( attribute "PHYS_PAGE" "236"
					( Origin gFrontEnd )
				)
				( attribute "ROOM" "P1V05_PCH_STBY"
					( Origin gFrontEnd )
				)
				( attribute "ROT" "0"
					( Origin gFrontEnd )
				)
				( attribute "SEC" "1"
					( Origin gFrontEnd )
				)
				( attribute "SEC_TYPE" "SM"
					( Origin gFrontEnd )
				)
				( attribute "TOLERANCE" "20%"
					( Origin gFrontEnd )
				)
				( attribute "VALUE" "470UF"
					( Origin gFrontEnd )
				)
				( attribute "VER" "1"
					( Origin gFrontEnd )
				)
				( attribute "VOLTAGE" "2V"
					( Units "uVoltage" "V" 1.000000)
					( Origin gFrontEnd )
				)
				( attribute "XY" "(11775,2025)"
					( Origin gFrontEnd )
				)
				( attribute "CHIPS_PART_NAME" "CAPP"
					( Origin gPackager )
				)
				( attribute "CDS_PART_NAME" "CAPP_SM-470UF,2V,20%,ALUM,6990A"
					( Origin gPackager )
				)
				( objectStatus "C3L19" )
				( pin "a"
					( attribute "PN" "1"
						( Origin gPackager )
					)
					( objectStatus "C3L19.1" )
				)
				( pin "b"
					( attribute "PN" "2"
						( Origin gPackager )
					)
					( objectStatus "C3L19.2" )
				)
			)
			( gate "@baseboard_fab2_lib.baseboard_fab2(sch_1):page236_i77"
				( attribute "CDS_LIB" "mstr_discrete"
					( Origin gPackager )
				)
				( attribute "CDS_LOCATION" "C2L46"
					( Origin gPackager )
				)
				( attribute "CDS_SEC" "1"
					( Origin gPackager )
				)
				( attribute "LOCATION" "C2L46"
					( Origin gFrontEnd )
				)
				( attribute "MATERIAL" "ALUM"
					( Origin gFrontEnd )
				)
				( attribute "PACK_TYPE" "SM"
					( Origin gFrontEnd )
				)
				( attribute "PART_NUMBER" "699013-031"
					( Origin gFrontEnd )
				)
				( attribute "PHYS_PAGE" "236"
					( Origin gFrontEnd )
				)
				( attribute "ROOM" "P1V05_PCH_STBY"
					( Origin gFrontEnd )
				)
				( attribute "ROT" "0"
					( Origin gFrontEnd )
				)
				( attribute "SEC" "1"
					( Origin gPackager )
				)
				( attribute "TOLERANCE" "20%"
					( Origin gFrontEnd )
				)
				( attribute "VALUE" "470UF"
					( Origin gFrontEnd )
				)
				( attribute "VER" "1"
					( Origin gFrontEnd )
				)
				( attribute "VOLTAGE" "2V"
					( Units "uVoltage" "V" 1.000000)
					( Origin gFrontEnd )
				)
				( attribute "XY" "(12025,2025)"
					( Origin gFrontEnd )
				)
				( attribute "CHIPS_PART_NAME" "CAPP"
					( Origin gPackager )
				)
				( attribute "CDS_PART_NAME" "CAPP_SM-470UF,2V,20%,ALUM,6990A"
					( Origin gPackager )
				)
				( objectStatus "C2L46" )
				( pin "a"
					( attribute "PN" "1"
						( Origin gPackager )
					)
					( objectStatus "C2L46.1" )
				)
				( pin "b"
					( attribute "PN" "2"
						( Origin gPackager )
					)
					( objectStatus "C2L46.2" )
				)
			)
			( gate "@baseboard_fab2_lib.baseboard_fab2(sch_1):page236_i78"
				( attribute "CDS_LIB" "mstr_discrete"
					( Origin gPackager )
				)
				( attribute "CDS_LOCATION" "C8A15"
					( Origin gPackager )
				)
				( attribute "CDS_SEC" "1"
					( Origin gPackager )
				)
				( attribute "LOCATION" "C8A15"
					( Origin gFrontEnd )
				)
				( attribute "MATERIAL" "ALUM"
					( Origin gFrontEnd )
				)
				( attribute "PACK_TYPE" "SM"
					( Origin gFrontEnd )
				)
				( attribute "PART_NUMBER" "699013-031"
					( Origin gFrontEnd )
				)
				( attribute "PHYS_PAGE" "236"
					( Origin gFrontEnd )
				)
				( attribute "ROOM" "P1V05_PCH_STBY"
					( Origin gFrontEnd )
				)
				( attribute "ROT" "0"
					( Origin gFrontEnd )
				)
				( attribute "SEC" "1"
					( Origin gPackager )
				)
				( attribute "TOLERANCE" "20%"
					( Origin gFrontEnd )
				)
				( attribute "VALUE" "470UF"
					( Origin gFrontEnd )
				)
				( attribute "VER" "1"
					( Origin gFrontEnd )
				)
				( attribute "VOLTAGE" "2V"
					( Units "uVoltage" "V" 1.000000)
					( Origin gFrontEnd )
				)
				( attribute "XY" "(12275,2025)"
					( Origin gFrontEnd )
				)
				( attribute "CHIPS_PART_NAME" "CAPP"
					( Origin gPackager )
				)
				( attribute "CDS_PART_NAME" "CAPP_SM-470UF,2V,20%,ALUM,6990A"
					( Origin gPackager )
				)
				( objectStatus "C8A15" )
				( pin "a"
					( attribute "PN" "1"
						( Origin gPackager )
					)
					( objectStatus "C8A15.1" )
				)
				( pin "b"
					( attribute "PN" "2"
						( Origin gPackager )
					)
					( objectStatus "C8A15.2" )
				)
			)
			( gate "@baseboard_fab2_lib.baseboard_fab2(sch_1):page236_i79"
				( attribute "CDS_LIB" "mstr_discrete"
					( Origin gPackager )
				)
				( attribute "CDS_LOCATION" "C2L25"
					( Origin gPackager )
				)
				( attribute "CDS_SEC" "1"
					( Origin gPackager )
				)
				( attribute "LOCATION" "C2L25"
					( Origin gFrontEnd )
				)
				( attribute "MATERIAL" "ALUM"
					( Origin gFrontEnd )
				)
				( attribute "PACK_TYPE" "SM"
					( Origin gFrontEnd )
				)
				( attribute "PART_NUMBER" "699013-031"
					( Origin gFrontEnd )
				)
				( attribute "PHYS_PAGE" "236"
					( Origin gFrontEnd )
				)
				( attribute "ROOM" "P1V05_PCH_STBY"
					( Origin gFrontEnd )
				)
				( attribute "ROT" "0"
					( Origin gFrontEnd )
				)
				( attribute "SEC" "1"
					( Origin gPackager )
				)
				( attribute "TOLERANCE" "20%"
					( Origin gFrontEnd )
				)
				( attribute "VALUE" "470UF"
					( Origin gFrontEnd )
				)
				( attribute "VER" "1"
					( Origin gFrontEnd )
				)
				( attribute "VOLTAGE" "2V"
					( Units "uVoltage" "V" 1.000000)
					( Origin gFrontEnd )
				)
				( attribute "XY" "(12550,2025)"
					( Origin gFrontEnd )
				)
				( attribute "CHIPS_PART_NAME" "CAPP"
					( Origin gPackager )
				)
				( attribute "CDS_PART_NAME" "CAPP_SM-470UF,2V,20%,ALUM,6990A"
					( Origin gPackager )
				)
				( objectStatus "C2L25" )
				( pin "a"
					( attribute "PN" "1"
						( Origin gPackager )
					)
					( objectStatus "C2L25.1" )
				)
				( pin "b"
					( attribute "PN" "2"
						( Origin gPackager )
					)
					( objectStatus "C2L25.2" )
				)
			)
			( gate "@baseboard_fab2_lib.baseboard_fab2(sch_1):page236_i90"
				( attribute "BOM_COST" "P1V05_PCH_STBY"
					( Origin gFrontEnd )
				)
				( attribute "CDS_LIB" "mstr_discrete"
					( Origin gPackager )
				)
				( attribute "CDS_LOCATION" "R7A13"
					( Origin gPackager )
				)
				( attribute "CDS_SEC" "1"
					( Origin gPackager )
				)
				( attribute "LOCATION" "R7A13"
					( Origin gFrontEnd )
				)
				( attribute "MATERIAL" "CHIP"
					( Origin gFrontEnd )
				)
				( attribute "PACK_TYPE" "0402"
					( Origin gFrontEnd )
				)
				( attribute "PART_NUMBER" "G21796-017"
					( Origin gFrontEnd )
				)
				( attribute "PHYS_PAGE" "236"
					( Origin gFrontEnd )
				)
				( attribute "ROOM" "P1V05_PCH_STBY"
					( Origin gFrontEnd )
				)
				( attribute "ROT" "0"
					( Origin gFrontEnd )
				)
				( attribute "SEC" "1"
					( Origin gPackager )
				)
				( attribute "SPOF" "TRUE"
					( Origin gFrontEnd )
				)
				( attribute "TOLERANCE" "1%"
					( Origin gFrontEnd )
				)
				( attribute "VALUE" "100.0"
					( Origin gFrontEnd )
				)
				( attribute "VER" "1"
					( Origin gFrontEnd )
				)
				( attribute "WATTAGE" "1/16W"
					( Origin gFrontEnd )
				)
				( attribute "XY" "(10475,1400)"
					( Origin gFrontEnd )
				)
				( attribute "CHIPS_PART_NAME" "RES"
					( Origin gPackager )
				)
				( attribute "CDS_PART_NAME" "RES_0402-100.0,1%,1/16W,CHIP,GA"
					( Origin gPackager )
				)
				( objectStatus "R7A13" )
				( pin "a"
					( attribute "PN" "1"
						( Origin gPackager )
					)
					( objectStatus "R7A13.1" )
				)
				( pin "b"
					( attribute "PN" "2"
						( Origin gPackager )
					)
					( objectStatus "R7A13.2" )
				)
			)
			( gate "@baseboard_fab2_lib.baseboard_fab2(sch_1):page236_i92"
				( attribute "BOM_COST" "P1V05_PCH_STBY"
					( Origin gFrontEnd )
				)
				( attribute "CDS_LIB" "mstr_discrete"
					( Origin gPackager )
				)
				( attribute "CDS_LOCATION" "R7A18"
					( Origin gPackager )
				)
				( attribute "CDS_SEC" "1"
					( Origin gPackager )
				)
				( attribute "LOCATION" "R7A18"
					( Origin gFrontEnd )
				)
				( attribute "MATERIAL" "CHIP"
					( Origin gFrontEnd )
				)
				( attribute "PACK_TYPE" "0402"
					( Origin gFrontEnd )
				)
				( attribute "PART_NUMBER" "G21497-005"
					( Origin gFrontEnd )
				)
				( attribute "PHYS_PAGE" "236"
					( Origin gFrontEnd )
				)
				( attribute "ROOM" "P1V05_PCH_STBY"
					( Origin gFrontEnd )
				)
				( attribute "ROT" "0"
					( Origin gFrontEnd )
				)
				( attribute "SEC" "1"
					( Origin gPackager )
				)
				( attribute "SPOF" "TRUE"
					( Origin gFrontEnd )
				)
				( attribute "TOLERANCE" "5%"
					( Origin gFrontEnd )
				)
				( attribute "VALUE" "0.0"
					( Origin gFrontEnd )
				)
				( attribute "VER" "1"
					( Origin gFrontEnd )
				)
				( attribute "WATTAGE" "1/16W"
					( Origin gFrontEnd )
				)
				( attribute "XY" "(9850,950)"
					( Origin gFrontEnd )
				)
				( attribute "CHIPS_PART_NAME" "RES"
					( Origin gPackager )
				)
				( attribute "CDS_PART_NAME" "RES_0402-0.0,5%,1/16W,CHIP,G21A"
					( Origin gPackager )
				)
				( objectStatus "R7A18" )
				( pin "a"
					( attribute "PN" "1"
						( Origin gPackager )
					)
					( objectStatus "R7A18.1" )
				)
				( pin "b"
					( attribute "PN" "2"
						( Origin gPackager )
					)
					( objectStatus "R7A18.2" )
				)
			)
			( gate "@baseboard_fab2_lib.baseboard_fab2(sch_1):page236_i93"
				( attribute "BOM_COST" "P1V05_PCH_STBY"
					( Origin gFrontEnd )
				)
				( attribute "CDS_LIB" "mstr_discrete"
					( Origin gPackager )
				)
				( attribute "CDS_LOCATION" "R7A19"
					( Origin gPackager )
				)
				( attribute "CDS_SEC" "1"
					( Origin gPackager )
				)
				( attribute "LOCATION" "R7A19"
					( Origin gFrontEnd )
				)
				( attribute "MATERIAL" "CHIP"
					( Origin gFrontEnd )
				)
				( attribute "NO_XNET_CONNECTION" "1"
					( Origin gFrontEnd )
				)
				( attribute "PACK_TYPE" "0402"
					( Origin gFrontEnd )
				)
				( attribute "PART_NUMBER" "G21796-066"
					( Origin gFrontEnd )
				)
				( attribute "PHYS_PAGE" "236"
					( Origin gFrontEnd )
				)
				( attribute "ROOM" "P1V05_PCH_STBY"
					( Origin gFrontEnd )
				)
				( attribute "ROT" "0"
					( Origin gFrontEnd )
				)
				( attribute "SEC" "1"
					( Origin gFrontEnd )
				)
				( attribute "SEC_TYPE" "0402"
					( Origin gFrontEnd )
				)
				( attribute "SPOF" "TRUE"
					( Origin gFrontEnd )
				)
				( attribute "TOLERANCE" "1%"
					( Origin gFrontEnd )
				)
				( attribute "VALUE" "10.0"
					( Origin gFrontEnd )
				)
				( attribute "VER" "1"
					( Origin gFrontEnd )
				)
				( attribute "WATTAGE" "1/16W"
					( Origin gFrontEnd )
				)
				( attribute "XY" "(8725,1175)"
					( Origin gFrontEnd )
				)
				( attribute "CHIPS_PART_NAME" "RES"
					( Origin gPackager )
				)
				( attribute "CDS_PART_NAME" "RES_0402-10.0,1%,1/16W,CHIP,G2A"
					( Origin gPackager )
				)
				( objectStatus "R7A19" )
				( pin "a"
					( attribute "PN" "1"
						( Origin gPackager )
					)
					( objectStatus "R7A19.1" )
				)
				( pin "b"
					( attribute "PN" "2"
						( Origin gPackager )
					)
					( objectStatus "R7A19.2" )
				)
			)
			( gate "@baseboard_fab2_lib.baseboard_fab2(sch_1):page236_i94"
				( attribute "BOM_COST" "P1V05_PCH_STBY"
					( Origin gFrontEnd )
				)
				( attribute "CDS_LIB" "mstr_discrete"
					( Origin gPackager )
				)
				( attribute "CDS_LOCATION" "R7A14"
					( Origin gPackager )
				)
				( attribute "CDS_SEC" "1"
					( Origin gPackager )
				)
				( attribute "LOCATION" "R7A14"
					( Origin gFrontEnd )
				)
				( attribute "MATERIAL" "CHIP"
					( Origin gFrontEnd )
				)
				( attribute "NO_XNET_CONNECTION" "1"
					( Origin gFrontEnd )
				)
				( attribute "PACK_TYPE" "0402"
					( Origin gFrontEnd )
				)
				( attribute "PART_NUMBER" "G21796-066"
					( Origin gFrontEnd )
				)
				( attribute "PHYS_PAGE" "236"
					( Origin gFrontEnd )
				)
				( attribute "ROOM" "P1V05_PCH_STBY"
					( Origin gFrontEnd )
				)
				( attribute "ROT" "0"
					( Origin gFrontEnd )
				)
				( attribute "SEC" "1"
					( Origin gFrontEnd )
				)
				( attribute "SEC_TYPE" "0402"
					( Origin gFrontEnd )
				)
				( attribute "SPOF" "TRUE"
					( Origin gFrontEnd )
				)
				( attribute "TOLERANCE" "1%"
					( Origin gFrontEnd )
				)
				( attribute "VALUE" "10.0"
					( Origin gFrontEnd )
				)
				( attribute "VER" "1"
					( Origin gFrontEnd )
				)
				( attribute "WATTAGE" "1/16W"
					( Origin gFrontEnd )
				)
				( attribute "XY" "(8750,900)"
					( Origin gFrontEnd )
				)
				( attribute "CHIPS_PART_NAME" "RES"
					( Origin gPackager )
				)
				( attribute "CDS_PART_NAME" "RES_0402-10.0,1%,1/16W,CHIP,G2A"
					( Origin gPackager )
				)
				( objectStatus "R7A14" )
				( pin "a"
					( attribute "PN" "1"
						( Origin gPackager )
					)
					( objectStatus "R7A14.1" )
				)
				( pin "b"
					( attribute "PN" "2"
						( Origin gPackager )
					)
					( objectStatus "R7A14.2" )
				)
			)
			( gate "@baseboard_fab2_lib.baseboard_fab2(sch_1):page236_i116"
				( attribute "CDS_LIB" "mstr_discrete"
					( Origin gPackager )
				)
				( attribute "CDS_LOCATION" "EU7A3"
					( Origin gPackager )
				)
				( attribute "CDS_SEC" "1"
					( Origin gPackager )
				)
				( attribute "LOCATION" "EU7A3"
					( Origin gFrontEnd )
				)
				( attribute "MATERIAL" "IC"
					( Origin gFrontEnd )
				)
				( attribute "NO_XNET_CONNECTION" "1"
					( Origin gFrontEnd )
				)
				( attribute "PACK_TYPE" "SM"
					( Origin gFrontEnd )
				)
				( attribute "PART_NUMBER" "H73684-001"
					( Origin gFrontEnd )
				)
				( attribute "PHYS_PAGE" "236"
					( Origin gFrontEnd )
				)
				( attribute "ROT" "0"
					( Origin gFrontEnd )
				)
				( attribute "SEC" "1"
					( Origin gFrontEnd )
				)
				( attribute "SEC_TYPE" "SM"
					( Origin gFrontEnd )
				)
				( attribute "VALUE" "IR35412"
					( Origin gFrontEnd )
				)
				( attribute "VER" "1"
					( Origin gFrontEnd )
				)
				( attribute "XY" "(9700,4250)"
					( Origin gFrontEnd )
				)
				( attribute "CHIPS_PART_NAME" "IR354XX"
					( Origin gPackager )
				)
				( attribute "CDS_PART_NAME" "IR354XX_SM-IR35412,IC,H73684-0A"
					( Origin gPackager )
				)
				( objectStatus "EU7A3" )
				( pin "boost"
					( attribute "PN" "33"
						( Origin gPackager )
					)
					( objectStatus "EU7A3.33" )
				)
				( pin "en"
					( attribute "PN" "35"
						( Origin gPackager )
					)
					( objectStatus "EU7A3.35" )
				)
				( pin "gl(0)"
					( attribute "PN" "6"
						( Origin gPackager )
					)
					( objectStatus "EU7A3.6" )
				)
				( pin "gl(1)"
					( attribute "PN" "41"
						( Origin gPackager )
					)
					( objectStatus "EU7A3.41" )
				)
				( pin "iout"
					( attribute "PN" "38"
						( Origin gPackager )
					)
					( objectStatus "EU7A3.38" )
				)
				( pin "lgnd"
					( attribute "PN" "2"
						( Origin gPackager )
					)
					( objectStatus "EU7A3.2" )
				)
				( pin "nc"
					( attribute "PN" "31"
						( Origin gPackager )
					)
					( objectStatus "EU7A3.31" )
				)
				( pin "ocset"
					( attribute "PN" "37"
						( Origin gPackager )
					)
					( objectStatus "EU7A3.37" )
				)
				( pin "pgnd(0)"
					( attribute "PN" "5"
						( Origin gPackager )
					)
					( objectStatus "EU7A3.5" )
				)
				( pin "pgnd(1)"
					( attribute "PN" "7"
						( Origin gPackager )
					)
					( objectStatus "EU7A3.7" )
				)
				( pin "pgnd(2)"
					( attribute "PN" "40"
						( Origin gPackager )
					)
					( objectStatus "EU7A3.40" )
				)
				( pin "phase"
					( attribute "PN" "32"
						( Origin gPackager )
					)
					( objectStatus "EU7A3.32" )
				)
				( pin "pwm"
					( attribute "PN" "34"
						( Origin gPackager )
					)
					( objectStatus "EU7A3.34" )
				)
				( pin "refin"
					( attribute "PN" "39"
						( Origin gPackager )
					)
					( objectStatus "EU7A3.39" )
				)
				( pin "sw"
					( attribute "PN" "10"
						( Origin gPackager )
					)
					( objectStatus "EU7A3.10" )
				)
				( pin "tout_flt"
					( attribute "PN" "36"
						( Origin gPackager )
					)
					( objectStatus "EU7A3.36" )
				)
				( pin "vcc"
					( attribute "PN" "3"
						( Origin gPackager )
					)
					( objectStatus "EU7A3.3" )
				)
				( pin "vdrv"
					( attribute "PN" "4"
						( Origin gPackager )
					)
					( objectStatus "EU7A3.4" )
				)
				( pin "vin(0)"
					( attribute "PN" "25"
						( Origin gPackager )
					)
					( objectStatus "EU7A3.25" )
				)
				( pin "vin(1)"
					( attribute "PN" "30"
						( Origin gPackager )
					)
					( objectStatus "EU7A3.30" )
				)
				( pin "vos"
					( attribute "PN" "1"
						( Origin gPackager )
					)
					( objectStatus "EU7A3.1" )
				)
			)
			( gate "@baseboard_fab2_lib.baseboard_fab2(sch_1):page236_i117"
				( attribute "CDS_LIB" "mstr_discrete"
					( Origin gPackager )
				)
				( attribute "CDS_LOCATION" "EU7A2"
					( Origin gPackager )
				)
				( attribute "LOCATION" "EU7A2"
					( Origin gFrontEnd )
				)
				( attribute "MATERIAL" "IC"
					( Origin gFrontEnd )
				)
				( attribute "NO_XNET_CONNECTION" "1"
					( Origin gFrontEnd )
				)
				( attribute "PACK_TYPE" "SM"
					( Origin gFrontEnd )
				)
				( attribute "PART_NUMBER" "H73684-001"
					( Origin gFrontEnd )
				)
				( attribute "PHYS_PAGE" "236"
					( Origin gFrontEnd )
				)
				( attribute "ROT" "0"
					( Origin gFrontEnd )
				)
				( attribute "SEC" "1"
					( Origin gFrontEnd )
				)
				( attribute "SEC_TYPE" "SM"
					( Origin gFrontEnd )
				)
				( attribute "VALUE" "IR35412"
					( Origin gFrontEnd )
				)
				( attribute "VER" "1"
					( Origin gFrontEnd )
				)
				( attribute "XY" "(9725,2500)"
					( Origin gFrontEnd )
				)
				( attribute "CHIPS_PART_NAME" "IR354XX"
					( Origin gPackager )
				)
				( attribute "CDS_PART_NAME" "IR354XX_SM-IR35412,IC,H73684-0A"
					( Origin gPackager )
				)
				( attribute "CDS_SEC" "1"
					( Origin gPackager )
				)
				( objectStatus "EU7A2" )
				( pin "boost"
					( attribute "PN" "33"
						( Origin gPackager )
					)
					( objectStatus "EU7A2.33" )
				)
				( pin "en"
					( attribute "PN" "35"
						( Origin gPackager )
					)
					( objectStatus "EU7A2.35" )
				)
				( pin "gl(0)"
					( attribute "PN" "6"
						( Origin gPackager )
					)
					( objectStatus "EU7A2.6" )
				)
				( pin "gl(1)"
					( attribute "PN" "41"
						( Origin gPackager )
					)
					( objectStatus "EU7A2.41" )
				)
				( pin "iout"
					( attribute "PN" "38"
						( Origin gPackager )
					)
					( objectStatus "EU7A2.38" )
				)
				( pin "lgnd"
					( attribute "PN" "2"
						( Origin gPackager )
					)
					( objectStatus "EU7A2.2" )
				)
				( pin "nc"
					( attribute "PN" "31"
						( Origin gPackager )
					)
					( objectStatus "EU7A2.31" )
				)
				( pin "ocset"
					( attribute "PN" "37"
						( Origin gPackager )
					)
					( objectStatus "EU7A2.37" )
				)
				( pin "pgnd(0)"
					( attribute "PN" "5"
						( Origin gPackager )
					)
					( objectStatus "EU7A2.5" )
				)
				( pin "pgnd(1)"
					( attribute "PN" "7"
						( Origin gPackager )
					)
					( objectStatus "EU7A2.7" )
				)
				( pin "pgnd(2)"
					( attribute "PN" "40"
						( Origin gPackager )
					)
					( objectStatus "EU7A2.40" )
				)
				( pin "phase"
					( attribute "PN" "32"
						( Origin gPackager )
					)
					( objectStatus "EU7A2.32" )
				)
				( pin "pwm"
					( attribute "PN" "34"
						( Origin gPackager )
					)
					( objectStatus "EU7A2.34" )
				)
				( pin "refin"
					( attribute "PN" "39"
						( Origin gPackager )
					)
					( objectStatus "EU7A2.39" )
				)
				( pin "sw"
					( attribute "PN" "10"
						( Origin gPackager )
					)
					( objectStatus "EU7A2.10" )
				)
				( pin "tout_flt"
					( attribute "PN" "36"
						( Origin gPackager )
					)
					( objectStatus "EU7A2.36" )
				)
				( pin "vcc"
					( attribute "PN" "3"
						( Origin gPackager )
					)
					( objectStatus "EU7A2.3" )
				)
				( pin "vdrv"
					( attribute "PN" "4"
						( Origin gPackager )
					)
					( objectStatus "EU7A2.4" )
				)
				( pin "vin(0)"
					( attribute "PN" "25"
						( Origin gPackager )
					)
					( objectStatus "EU7A2.25" )
				)
				( pin "vin(1)"
					( attribute "PN" "30"
						( Origin gPackager )
					)
					( objectStatus "EU7A2.30" )
				)
				( pin "vos"
					( attribute "PN" "1"
						( Origin gPackager )
					)
					( objectStatus "EU7A2.1" )
				)
			)
			( gate "@baseboard_fab2_lib.baseboard_fab2(sch_1):page236_i118"
				( attribute "CDS_LIB" "mstr_discrete"
					( Origin gPackager )
				)
				( attribute "CDS_LOCATION" "R3L15"
					( Origin gPackager )
				)
				( attribute "CDS_SEC" "1"
					( Origin gPackager )
				)
				( attribute "LOCATION" "R3L15"
					( Origin gFrontEnd )
				)
				( attribute "MATERIAL" "EMPTY"
					( Origin gFrontEnd )
				)
				( attribute "PACK_TYPE" "0402"
					( Origin gFrontEnd )
				)
				( attribute "PART_NUMBER" "G21796-187"
					( Origin gFrontEnd )
				)
				( attribute "PHYS_PAGE" "236"
					( Origin gFrontEnd )
				)
				( attribute "ROT" "0"
					( Origin gFrontEnd )
				)
				( attribute "SEC" "1"
					( Origin gPackager )
				)
				( attribute "TOLERANCE" "1%"
					( Origin gFrontEnd )
				)
				( attribute "VALUE" "68.1K"
					( Origin gFrontEnd )
				)
				( attribute "VER" "2"
					( Origin gFrontEnd )
				)
				( attribute "WATTAGE" "1/16W"
					( Origin gFrontEnd )
				)
				( attribute "XY" "(11975,4425)"
					( Origin gFrontEnd )
				)
				( attribute "CHIPS_PART_NAME" "RES"
					( Origin gPackager )
				)
				( attribute "CDS_PART_NAME" "RES_0402-68.1K,1%,1/16W,EMPTY,A"
					( Origin gPackager )
				)
				( objectStatus "R3L15" )
				( pin "a"
					( attribute "PN" "1"
						( Origin gPackager )
					)
					( objectStatus "R3L15.1" )
				)
				( pin "b"
					( attribute "PN" "2"
						( Origin gPackager )
					)
					( objectStatus "R3L15.2" )
				)
			)
			( gate "@baseboard_fab2_lib.baseboard_fab2(sch_1):page236_i120"
				( attribute "CDS_LIB" "mstr_discrete"
					( Origin gPackager )
				)
				( attribute "CDS_LOCATION" "R3L14"
					( Origin gPackager )
				)
				( attribute "CDS_SEC" "1"
					( Origin gPackager )
				)
				( attribute "LOCATION" "R3L14"
					( Origin gFrontEnd )
				)
				( attribute "MATERIAL" "EMPTY"
					( Origin gFrontEnd )
				)
				( attribute "PACK_TYPE" "0402"
					( Origin gFrontEnd )
				)
				( attribute "PART_NUMBER" "G21796-187"
					( Origin gFrontEnd )
				)
				( attribute "PHYS_PAGE" "236"
					( Origin gFrontEnd )
				)
				( attribute "ROT" "0"
					( Origin gFrontEnd )
				)
				( attribute "SEC" "1"
					( Origin gPackager )
				)
				( attribute "TOLERANCE" "1%"
					( Origin gFrontEnd )
				)
				( attribute "VALUE" "68.1K"
					( Origin gFrontEnd )
				)
				( attribute "VER" "2"
					( Origin gFrontEnd )
				)
				( attribute "WATTAGE" "1/16W"
					( Origin gFrontEnd )
				)
				( attribute "XY" "(12000,2675)"
					( Origin gFrontEnd )
				)
				( attribute "CHIPS_PART_NAME" "RES"
					( Origin gPackager )
				)
				( attribute "CDS_PART_NAME" "RES_0402-68.1K,1%,1/16W,EMPTY,A"
					( Origin gPackager )
				)
				( objectStatus "R3L14" )
				( pin "a"
					( attribute "PN" "1"
						( Origin gPackager )
					)
					( objectStatus "R3L14.1" )
				)
				( pin "b"
					( attribute "PN" "2"
						( Origin gPackager )
					)
					( objectStatus "R3L14.2" )
				)
			)
			( gate "@baseboard_fab2_lib.baseboard_fab2(sch_1):page237_i3"
				( attribute "BOM_COST" "P1V8_PCH_STBY_VR"
					( Origin gFrontEnd )
				)
				( attribute "CDS_LIB" "mstr_discrete"
					( Origin gPackager )
				)
				( attribute "CDS_LOCATION" "R8A10"
					( Origin gPackager )
				)
				( attribute "CDS_SEC" "1"
					( Origin gPackager )
				)
				( attribute "LOCATION" "R8A10"
					( Origin gFrontEnd )
				)
				( attribute "MATERIAL" "CHIP"
					( Origin gFrontEnd )
				)
				( attribute "PACK_TYPE" "0402"
					( Origin gFrontEnd )
				)
				( attribute "PART_NUMBER" "G21796-140"
					( Origin gFrontEnd )
				)
				( attribute "PHYS_PAGE" "237"
					( Origin gFrontEnd )
				)
				( attribute "ROOM" "P1V8_PCH_STBY_VR"
					( Origin gFrontEnd )
				)
				( attribute "ROT" "0"
					( Origin gFrontEnd )
				)
				( attribute "SEC" "1"
					( Origin gPackager )
				)
				( attribute "TOLERANCE" "1%"
					( Origin gFrontEnd )
				)
				( attribute "VALUE" "5.11K"
					( Origin gFrontEnd )
				)
				( attribute "VER" "2"
					( Origin gFrontEnd )
				)
				( attribute "WATTAGE" "1/16W"
					( Origin gFrontEnd )
				)
				( attribute "XY" "(1350,3875)"
					( Origin gFrontEnd )
				)
				( attribute "CHIPS_PART_NAME" "RES"
					( Origin gPackager )
				)
				( attribute "CDS_PART_NAME" "RES_0402-5.11K,1%,1/16W,CHIP,GA"
					( Origin gPackager )
				)
				( objectStatus "R8A10" )
				( pin "a"
					( attribute "PN" "1"
						( Origin gPackager )
					)
					( objectStatus "R8A10.1" )
				)
				( pin "b"
					( attribute "PN" "2"
						( Origin gPackager )
					)
					( objectStatus "R8A10.2" )
				)
			)
			( gate "@baseboard_fab2_lib.baseboard_fab2(sch_1):page237_i5"
				( attribute "BOM_COST" "P1V8_PCH_STBY_VR"
					( Origin gFrontEnd )
				)
				( attribute "CDS_LIB" "mstr_discrete"
					( Origin gPackager )
				)
				( attribute "CDS_LOCATION" "C8A11"
					( Origin gPackager )
				)
				( attribute "CDS_SEC" "1"
					( Origin gPackager )
				)
				( attribute "LOCATION" "C8A11"
					( Origin gFrontEnd )
				)
				( attribute "MATERIAL" "X7R"
					( Origin gFrontEnd )
				)
				( attribute "PACK_TYPE" "0402LF"
					( Origin gFrontEnd )
				)
				( attribute "PART_NUMBER" "A36096-046"
					( Origin gFrontEnd )
				)
				( attribute "PHYS_PAGE" "237"
					( Origin gFrontEnd )
				)
				( attribute "ROOM" "P1V8_PCH_STBY_VR"
					( Origin gFrontEnd )
				)
				( attribute "ROT" "0"
					( Origin gFrontEnd )
				)
				( attribute "SEC" "1"
					( Origin gPackager )
				)
				( attribute "TOLERANCE" "10%"
					( Origin gFrontEnd )
				)
				( attribute "VALUE" "1000PF"
					( Origin gFrontEnd )
				)
				( attribute "VER" "1"
					( Origin gFrontEnd )
				)
				( attribute "VOLTAGE" "50V"
					( Units "uVoltage" "V" 1.000000)
					( Origin gFrontEnd )
				)
				( attribute "XY" "(1350,3475)"
					( Origin gFrontEnd )
				)
				( attribute "CHIPS_PART_NAME" "CAP"
					( Origin gPackager )
				)
				( attribute "CDS_PART_NAME" "CAP_0402LF-1000PF,50V,10%,X7R,A"
					( Origin gPackager )
				)
				( objectStatus "C8A11" )
				( pin "a"
					( attribute "PN" "1"
						( Origin gPackager )
					)
					( objectStatus "C8A11.1" )
				)
				( pin "b"
					( attribute "PN" "2"
						( Origin gPackager )
					)
					( objectStatus "C8A11.2" )
				)
			)
			( gate "@baseboard_fab2_lib.baseboard_fab2(sch_1):page237_i12"
				( attribute "BOM_COST" "P1V8_PCH_STBY_VR"
					( Origin gFrontEnd )
				)
				( attribute "CDS_LIB" "mstr_discrete"
					( Origin gPackager )
				)
				( attribute "CDS_LOCATION" "C2L45"
					( Origin gPackager )
				)
				( attribute "CDS_SEC" "1"
					( Origin gPackager )
				)
				( attribute "LOCATION" "C2L45"
					( Origin gFrontEnd )
				)
				( attribute "MATERIAL" "X6S"
					( Origin gFrontEnd )
				)
				( attribute "PACK_TYPE" "0805"
					( Origin gFrontEnd )
				)
				( attribute "PART_NUMBER" "C95333-008"
					( Origin gFrontEnd )
				)
				( attribute "PHYS_PAGE" "237"
					( Origin gFrontEnd )
				)
				( attribute "ROOM" "P1V8_PCH_STBY_VR"
					( Origin gFrontEnd )
				)
				( attribute "ROT" "0"
					( Origin gFrontEnd )
				)
				( attribute "SEC" "1"
					( Origin gPackager )
				)
				( attribute "TOLERANCE" "20%"
					( Origin gFrontEnd )
				)
				( attribute "VALUE" "22UF"
					( Origin gFrontEnd )
				)
				( attribute "VER" "1"
					( Origin gFrontEnd )
				)
				( attribute "VOLTAGE" "6.3V"
					( Units "uVoltage" "V" 1.000000)
					( Origin gFrontEnd )
				)
				( attribute "XY" "(3375,2150)"
					( Origin gFrontEnd )
				)
				( attribute "CHIPS_PART_NAME" "CAP"
					( Origin gPackager )
				)
				( attribute "CDS_PART_NAME" "CAP_0805-22UF,6.3V,20%,X6S,C95A"
					( Origin gPackager )
				)
				( objectStatus "C2L45" )
				( pin "a"
					( attribute "PN" "1"
						( Origin gPackager )
					)
					( objectStatus "C2L45.1" )
				)
				( pin "b"
					( attribute "PN" "2"
						( Origin gPackager )
					)
					( objectStatus "C2L45.2" )
				)
			)
			( gate "@baseboard_fab2_lib.baseboard_fab2(sch_1):page237_i13"
				( attribute "BOM_COST" "P1V8_PCH_STBY_VR"
					( Origin gFrontEnd )
				)
				( attribute "CDS_LIB" "mstr_discrete"
					( Origin gPackager )
				)
				( attribute "CDS_LOCATION" "C8A14"
					( Origin gPackager )
				)
				( attribute "CDS_SEC" "1"
					( Origin gPackager )
				)
				( attribute "LOCATION" "C8A14"
					( Origin gFrontEnd )
				)
				( attribute "MATERIAL" "X6S"
					( Origin gFrontEnd )
				)
				( attribute "PACK_TYPE" "0805"
					( Origin gFrontEnd )
				)
				( attribute "PART_NUMBER" "C95333-008"
					( Origin gFrontEnd )
				)
				( attribute "PHYS_PAGE" "237"
					( Origin gFrontEnd )
				)
				( attribute "ROOM" "P1V8_PCH_STBY_VR"
					( Origin gFrontEnd )
				)
				( attribute "ROT" "0"
					( Origin gFrontEnd )
				)
				( attribute "SEC" "1"
					( Origin gFrontEnd )
				)
				( attribute "SEC_TYPE" "0805"
					( Origin gFrontEnd )
				)
				( attribute "TOLERANCE" "20%"
					( Origin gFrontEnd )
				)
				( attribute "VALUE" "22UF"
					( Origin gFrontEnd )
				)
				( attribute "VER" "1"
					( Origin gFrontEnd )
				)
				( attribute "VOLTAGE" "6.3V"
					( Units "uVoltage" "V" 1.000000)
					( Origin gFrontEnd )
				)
				( attribute "XY" "(3100,2200)"
					( Origin gFrontEnd )
				)
				( attribute "CHIPS_PART_NAME" "CAP"
					( Origin gPackager )
				)
				( attribute "CDS_PART_NAME" "CAP_0805-22UF,6.3V,20%,X6S,C95A"
					( Origin gPackager )
				)
				( objectStatus "C8A14" )
				( pin "a"
					( attribute "PN" "1"
						( Origin gPackager )
					)
					( objectStatus "C8A14.1" )
				)
				( pin "b"
					( attribute "PN" "2"
						( Origin gPackager )
					)
					( objectStatus "C8A14.2" )
				)
			)
			( gate "@baseboard_fab2_lib.baseboard_fab2(sch_1):page237_i15"
				( attribute "BOM_COST" "P1V8_PCH_STBY_VR"
					( Origin gFrontEnd )
				)
				( attribute "CDS_LIB" "mstr_discrete"
					( Origin gPackager )
				)
				( attribute "CDS_LOCATION" "R8A12"
					( Origin gPackager )
				)
				( attribute "CDS_SEC" "1"
					( Origin gPackager )
				)
				( attribute "LOCATION" "R8A12"
					( Origin gFrontEnd )
				)
				( attribute "MATERIAL" "CHIP"
					( Origin gFrontEnd )
				)
				( attribute "PACK_TYPE" "0603"
					( Origin gFrontEnd )
				)
				( attribute "PART_NUMBER" "G22026-030"
					( Origin gFrontEnd )
				)
				( attribute "PHYS_PAGE" "237"
					( Origin gFrontEnd )
				)
				( attribute "ROOM" "P1V8_PCH_STBY_VR"
					( Origin gFrontEnd )
				)
				( attribute "ROT" "0"
					( Origin gFrontEnd )
				)
				( attribute "SEC" "1"
					( Origin gFrontEnd )
				)
				( attribute "SEC_TYPE" "0603"
					( Origin gFrontEnd )
				)
				( attribute "TOLERANCE" "1%"
					( Origin gFrontEnd )
				)
				( attribute "VALUE" "475.0"
					( Origin gFrontEnd )
				)
				( attribute "VER" "2"
					( Origin gFrontEnd )
				)
				( attribute "WATTAGE" "1/10W"
					( Origin gFrontEnd )
				)
				( attribute "XY" "(2800,2125)"
					( Origin gFrontEnd )
				)
				( attribute "CHIPS_PART_NAME" "RES"
					( Origin gPackager )
				)
				( attribute "CDS_PART_NAME" "RES_0603-475.0,1%,1/10W,CHIP,GA"
					( Origin gPackager )
				)
				( objectStatus "R8A12" )
				( pin "a"
					( attribute "PN" "1"
						( Origin gPackager )
					)
					( objectStatus "R8A12.1" )
				)
				( pin "b"
					( attribute "PN" "2"
						( Origin gPackager )
					)
					( objectStatus "R8A12.2" )
				)
			)
			( gate "@baseboard_fab2_lib.baseboard_fab2(sch_1):page237_i29"
				( attribute "BOM_COST" "P1V8_PCH_STBY_VR"
					( Origin gFrontEnd )
				)
				( attribute "CDS_LIB" "mstr_discrete"
					( Origin gPackager )
				)
				( attribute "CDS_LOCATION" "C8A6"
					( Origin gPackager )
				)
				( attribute "CDS_SEC" "1"
					( Origin gPackager )
				)
				( attribute "LOCATION" "C8A6"
					( Origin gFrontEnd )
				)
				( attribute "MATERIAL" "X6S"
					( Origin gFrontEnd )
				)
				( attribute "PACK_TYPE" "0603"
					( Origin gFrontEnd )
				)
				( attribute "PART_NUMBER" "E15431-002"
					( Origin gFrontEnd )
				)
				( attribute "PHYS_PAGE" "237"
					( Origin gFrontEnd )
				)
				( attribute "ROOM" "P1V8_PCH_STBY_VR"
					( Origin gFrontEnd )
				)
				( attribute "ROT" "0"
					( Origin gFrontEnd )
				)
				( attribute "SEC" "1"
					( Origin gFrontEnd )
				)
				( attribute "SEC_TYPE" "0603"
					( Origin gFrontEnd )
				)
				( attribute "TOLERANCE" "20%"
					( Origin gFrontEnd )
				)
				( attribute "VALUE" "10UF"
					( Origin gFrontEnd )
				)
				( attribute "VER" "1"
					( Origin gFrontEnd )
				)
				( attribute "VOLTAGE" "6.3V"
					( Units "uVoltage" "V" 1.000000)
					( Origin gFrontEnd )
				)
				( attribute "XY" "(-1975,3150)"
					( Origin gFrontEnd )
				)
				( attribute "CHIPS_PART_NAME" "CAP"
					( Origin gPackager )
				)
				( attribute "CDS_PART_NAME" "CAP_0603-10UF,6.3V,20%,X6S,E15A"
					( Origin gPackager )
				)
				( objectStatus "C8A6" )
				( pin "a"
					( attribute "PN" "1"
						( Origin gPackager )
					)
					( objectStatus "C8A6.1" )
				)
				( pin "b"
					( attribute "PN" "2"
						( Origin gPackager )
					)
					( objectStatus "C8A6.2" )
				)
			)
			( gate "@baseboard_fab2_lib.baseboard_fab2(sch_1):page237_i31"
				( attribute "BOM_COST" "P1V8_PCH_STBY_VR"
					( Origin gFrontEnd )
				)
				( attribute "CDS_LIB" "mstr_discrete"
					( Origin gPackager )
				)
				( attribute "CDS_LOCATION" "C8A4"
					( Origin gPackager )
				)
				( attribute "CDS_SEC" "1"
					( Origin gPackager )
				)
				( attribute "LOCATION" "C8A4"
					( Origin gFrontEnd )
				)
				( attribute "MATERIAL" "X7R"
					( Origin gFrontEnd )
				)
				( attribute "PACK_TYPE" "0603LF"
					( Origin gFrontEnd )
				)
				( attribute "PART_NUMBER" "602433-020"
					( Origin gFrontEnd )
				)
				( attribute "PHYS_PAGE" "237"
					( Origin gFrontEnd )
				)
				( attribute "ROOM" "P1V8_PCH_STBY_VR"
					( Origin gFrontEnd )
				)
				( attribute "ROT" "0"
					( Origin gFrontEnd )
				)
				( attribute "SEC" "1"
					( Origin gFrontEnd )
				)
				( attribute "SEC_TYPE" "0603LF"
					( Origin gFrontEnd )
				)
				( attribute "TOLERANCE" "10%"
					( Origin gFrontEnd )
				)
				( attribute "VALUE" "0.1UF"
					( Origin gFrontEnd )
				)
				( attribute "VER" "1"
					( Origin gFrontEnd )
				)
				( attribute "VOLTAGE" "25V"
					( Units "uVoltage" "V" 1.000000)
					( Origin gFrontEnd )
				)
				( attribute "XY" "(-1550,3175)"
					( Origin gFrontEnd )
				)
				( attribute "CHIPS_PART_NAME" "CAP"
					( Origin gPackager )
				)
				( attribute "CDS_PART_NAME" "CAP_0603LF-0.1UF,25V,10%,X7R,6A"
					( Origin gPackager )
				)
				( objectStatus "C8A4" )
				( pin "a"
					( attribute "PN" "1"
						( Origin gPackager )
					)
					( objectStatus "C8A4.1" )
				)
				( pin "b"
					( attribute "PN" "2"
						( Origin gPackager )
					)
					( objectStatus "C8A4.2" )
				)
			)
			( gate "@baseboard_fab2_lib.baseboard_fab2(sch_1):page237_i55"
				( attribute "BOM_COST" "P1V8_PCH_STBY_VR"
					( Origin gFrontEnd )
				)
				( attribute "CDS_LIB" "mstr_discrete"
					( Origin gPackager )
				)
				( attribute "CDS_LOCATION" "C8A10"
					( Origin gPackager )
				)
				( attribute "CDS_SEC" "1"
					( Origin gPackager )
				)
				( attribute "LOCATION" "C8A10"
					( Origin gFrontEnd )
				)
				( attribute "MATERIAL" "EMPTY"
					( Origin gFrontEnd )
				)
				( attribute "PACK_TYPE" "0402LF"
					( Origin gFrontEnd )
				)
				( attribute "PART_NUMBER" "A36096-046"
					( Origin gFrontEnd )
				)
				( attribute "PHYS_PAGE" "237"
					( Origin gFrontEnd )
				)
				( attribute "ROOM" "P1V8_PCH_STBY_VR"
					( Origin gFrontEnd )
				)
				( attribute "ROT" "2"
					( Origin gFrontEnd )
				)
				( attribute "SEC" "1"
					( Origin gPackager )
				)
				( attribute "TOLERANCE" "10%"
					( Origin gFrontEnd )
				)
				( attribute "VALUE" "1000PF"
					( Origin gFrontEnd )
				)
				( attribute "VER" "1"
					( Origin gFrontEnd )
				)
				( attribute "VOLTAGE" "50V"
					( Units "uVoltage" "V" 1.000000)
					( Origin gFrontEnd )
				)
				( attribute "XY" "(-1500,2200)"
					( Origin gFrontEnd )
				)
				( attribute "CHIPS_PART_NAME" "CAP"
					( Origin gPackager )
				)
				( attribute "CDS_PART_NAME" "CAP_0402LF-1000PF,50V,10%,EMPTA"
					( Origin gPackager )
				)
				( objectStatus "C8A10" )
				( pin "a"
					( attribute "PN" "1"
						( Origin gPackager )
					)
					( objectStatus "C8A10.1" )
				)
				( pin "b"
					( attribute "PN" "2"
						( Origin gPackager )
					)
					( objectStatus "C8A10.2" )
				)
			)
			( gate "@baseboard_fab2_lib.baseboard_fab2(sch_1):page237_i77"
				( attribute "CDS_LIB" "mstr_discrete"
					( Origin gPackager )
				)
				( attribute "CDS_LOCATION" "C8A12"
					( Origin gPackager )
				)
				( attribute "CDS_SEC" "1"
					( Origin gPackager )
				)
				( attribute "LOCATION" "C8A12"
					( Origin gFrontEnd )
				)
				( attribute "MATERIAL" "X6S"
					( Origin gFrontEnd )
				)
				( attribute "PACK_TYPE" "0805"
					( Origin gFrontEnd )
				)
				( attribute "PART_NUMBER" "C95333-006"
					( Origin gFrontEnd )
				)
				( attribute "PHYS_PAGE" "237"
					( Origin gFrontEnd )
				)
				( attribute "ROOM" "P1V8_PCH_STBY_VR"
					( Origin gFrontEnd )
				)
				( attribute "ROT" "0"
					( Origin gFrontEnd )
				)
				( attribute "SEC" "1"
					( Origin gFrontEnd )
				)
				( attribute "SEC_TYPE" "0805"
					( Origin gFrontEnd )
				)
				( attribute "TOLERANCE" "20%"
					( Origin gFrontEnd )
				)
				( attribute "VALUE" "47UF"
					( Origin gFrontEnd )
				)
				( attribute "VER" "1"
					( Origin gFrontEnd )
				)
				( attribute "VOLTAGE" "4V"
					( Units "uVoltage" "V" 1.000000)
					( Origin gFrontEnd )
				)
				( attribute "XY" "(3650,2200)"
					( Origin gFrontEnd )
				)
				( attribute "CHIPS_PART_NAME" "CAP"
					( Origin gPackager )
				)
				( attribute "CDS_PART_NAME" "CAP_0805-47UF,4V,20%,X6S,C9533A"
					( Origin gPackager )
				)
				( objectStatus "C8A12" )
				( pin "a"
					( attribute "PN" "1"
						( Origin gPackager )
					)
					( objectStatus "C8A12.1" )
				)
				( pin "b"
					( attribute "PN" "2"
						( Origin gPackager )
					)
					( objectStatus "C8A12.2" )
				)
			)
			( gate "@baseboard_fab2_lib.baseboard_fab2(sch_1):page237_i79"
				( attribute "CDS_LIB" "mstr_discrete"
					( Origin gPackager )
				)
				( attribute "CDS_LOCATION" "C2L32"
					( Origin gPackager )
				)
				( attribute "CDS_SEC" "1"
					( Origin gPackager )
				)
				( attribute "LOCATION" "C2L32"
					( Origin gFrontEnd )
				)
				( attribute "MATERIAL" "X6S"
					( Origin gFrontEnd )
				)
				( attribute "PACK_TYPE" "0805"
					( Origin gFrontEnd )
				)
				( attribute "PART_NUMBER" "C95333-006"
					( Origin gFrontEnd )
				)
				( attribute "PHYS_PAGE" "237"
					( Origin gFrontEnd )
				)
				( attribute "ROOM" "P1V8_PCH_STBY_VR"
					( Origin gFrontEnd )
				)
				( attribute "ROT" "0"
					( Origin gFrontEnd )
				)
				( attribute "SEC" "1"
					( Origin gFrontEnd )
				)
				( attribute "SEC_TYPE" "0805"
					( Origin gFrontEnd )
				)
				( attribute "TOLERANCE" "20%"
					( Origin gFrontEnd )
				)
				( attribute "VALUE" "47UF"
					( Origin gFrontEnd )
				)
				( attribute "VER" "1"
					( Origin gFrontEnd )
				)
				( attribute "VOLTAGE" "4V"
					( Units "uVoltage" "V" 1.000000)
					( Origin gFrontEnd )
				)
				( attribute "XY" "(3900,1850)"
					( Origin gFrontEnd )
				)
				( attribute "CHIPS_PART_NAME" "CAP"
					( Origin gPackager )
				)
				( attribute "CDS_PART_NAME" "CAP_0805-47UF,4V,20%,X6S,C9533A"
					( Origin gPackager )
				)
				( objectStatus "C2L32" )
				( pin "a"
					( attribute "PN" "1"
						( Origin gPackager )
					)
					( objectStatus "C2L32.1" )
				)
				( pin "b"
					( attribute "PN" "2"
						( Origin gPackager )
					)
					( objectStatus "C2L32.2" )
				)
			)
			( gate "@baseboard_fab2_lib.baseboard_fab2(sch_1):page237_i80"
				( attribute "CDS_LIB" "mstr_discrete"
					( Origin gPackager )
				)
				( attribute "CDS_LOCATION" "R2L19"
					( Origin gPackager )
				)
				( attribute "CDS_SEC" "1"
					( Origin gPackager )
				)
				( attribute "LOCATION" "R2L19"
					( Origin gFrontEnd )
				)
				( attribute "MATERIAL" "CHIP"
					( Origin gFrontEnd )
				)
				( attribute "PACK_TYPE" "0402"
					( Origin gFrontEnd )
				)
				( attribute "PART_NUMBER" "G21796-048"
					( Origin gFrontEnd )
				)
				( attribute "PHYS_PAGE" "237"
					( Origin gFrontEnd )
				)
				( attribute "ROOM" "P1V8_PCH_STBY_VR"
					( Origin gFrontEnd )
				)
				( attribute "ROT" "0"
					( Origin gFrontEnd )
				)
				( attribute "SEC" "1"
					( Origin gFrontEnd )
				)
				( attribute "SEC_TYPE" "0402"
					( Origin gFrontEnd )
				)
				( attribute "TOLERANCE" "1%"
					( Origin gFrontEnd )
				)
				( attribute "VALUE" "49.9K"
					( Origin gFrontEnd )
				)
				( attribute "VER" "2"
					( Origin gFrontEnd )
				)
				( attribute "WATTAGE" "1/16W"
					( Origin gFrontEnd )
				)
				( attribute "XY" "(2325,1700)"
					( Origin gFrontEnd )
				)
				( attribute "CHIPS_PART_NAME" "RES"
					( Origin gPackager )
				)
				( attribute "CDS_PART_NAME" "RES_0402-49.9K,1%,1/16W,CHIP,GA"
					( Origin gPackager )
				)
				( objectStatus "R2L19" )
				( pin "a"
					( attribute "PN" "1"
						( Origin gPackager )
					)
					( objectStatus "R2L19.1" )
				)
				( pin "b"
					( attribute "PN" "2"
						( Origin gPackager )
					)
					( objectStatus "R2L19.2" )
				)
			)
			( gate "@baseboard_fab2_lib.baseboard_fab2(sch_1):page237_i81"
				( attribute "CDS_LIB" "mstr_discrete"
					( Origin gPackager )
				)
				( attribute "CDS_LOCATION" "R2L20"
					( Origin gPackager )
				)
				( attribute "CDS_SEC" "1"
					( Origin gPackager )
				)
				( attribute "LOCATION" "R2L20"
					( Origin gFrontEnd )
				)
				( attribute "MATERIAL" "CHIP"
					( Origin gFrontEnd )
				)
				( attribute "PACK_TYPE" "0402"
					( Origin gFrontEnd )
				)
				( attribute "PART_NUMBER" "G21796-327"
					( Origin gFrontEnd )
				)
				( attribute "PHYS_PAGE" "237"
					( Origin gFrontEnd )
				)
				( attribute "ROOM" "P1V8_PCH_STBY_VR"
					( Origin gFrontEnd )
				)
				( attribute "ROT" "0"
					( Origin gFrontEnd )
				)
				( attribute "SEC" "1"
					( Origin gFrontEnd )
				)
				( attribute "SEC_TYPE" "0402"
					( Origin gFrontEnd )
				)
				( attribute "TOLERANCE" "1.0%"
					( Origin gFrontEnd )
				)
				( attribute "VALUE" "63.4K"
					( Origin gFrontEnd )
				)
				( attribute "VER" "2"
					( Origin gFrontEnd )
				)
				( attribute "WATTAGE" "1/16W"
					( Origin gFrontEnd )
				)
				( attribute "XY" "(2325,2275)"
					( Origin gFrontEnd )
				)
				( attribute "CHIPS_PART_NAME" "RES"
					( Origin gPackager )
				)
				( attribute "CDS_PART_NAME" "RES_0402-63.4K,1.0%,1/16W,CHIPA"
					( Origin gPackager )
				)
				( objectStatus "R2L20" )
				( pin "a"
					( attribute "PN" "1"
						( Origin gPackager )
					)
					( objectStatus "R2L20.1" )
				)
				( pin "b"
					( attribute "PN" "2"
						( Origin gPackager )
					)
					( objectStatus "R2L20.2" )
				)
			)
			( gate "@baseboard_fab2_lib.baseboard_fab2(sch_1):page237_i86"
				( attribute "CDS_LIB" "mstr_vreg"
					( Origin gPackager )
				)
				( attribute "CDS_LOCATION" "EU8A2"
					( Origin gPackager )
				)
				( attribute "CDS_SEC" "1"
					( Origin gPackager )
				)
				( attribute "LOCATION" "EU8A2"
					( Origin gFrontEnd )
				)
				( attribute "MATERIAL" "IC"
					( Origin gFrontEnd )
				)
				( attribute "PACK_TYPE" "DFN"
					( Origin gFrontEnd )
				)
				( attribute "PART_NUMBER" "H65765-001"
					( Origin gFrontEnd )
				)
				( attribute "PHYS_PAGE" "237"
					( Origin gFrontEnd )
				)
				( attribute "ROOM" "P1V8_PCH_STBY_VR"
					( Origin gFrontEnd )
				)
				( attribute "ROT" "0"
					( Origin gFrontEnd )
				)
				( attribute "SEC" "1"
					( Origin gFrontEnd )
				)
				( attribute "SEC_TYPE" "DFN"
					( Origin gFrontEnd )
				)
				( attribute "VER" "1"
					( Origin gFrontEnd )
				)
				( attribute "XY" "(-50,2725)"
					( Origin gFrontEnd )
				)
				( attribute "CHIPS_PART_NAME" "RT9059"
					( Origin gPackager )
				)
				( attribute "CDS_PART_NAME" "RT9059_DFN-IC,H65765-001"
					( Origin gPackager )
				)
				( objectStatus "EU8A2" )
				( pin "adj_nc"
					( attribute "PN" "4"
						( Origin gPackager )
					)
					( objectStatus "EU8A2.4" )
				)
				( pin "en"
					( attribute "PN" "6"
						( Origin gPackager )
					)
					( objectStatus "EU8A2.6" )
				)
				( pin "gnd"
					( attribute "PN" "11"
						( Origin gPackager )
					)
					( objectStatus "EU8A2.11" )
				)
				( pin "pgood"
					( attribute "PN" "5"
						( Origin gPackager )
					)
					( objectStatus "EU8A2.5" )
				)
				( pin "vdd"
					( attribute "PN" "10"
						( Origin gPackager )
					)
					( objectStatus "EU8A2.10" )
				)
				( pin "vin(0)"
					( attribute "PN" "7"
						( Origin gPackager )
					)
					( objectStatus "EU8A2.7" )
				)
				( pin "vin(1)"
					( attribute "PN" "8"
						( Origin gPackager )
					)
					( objectStatus "EU8A2.8" )
				)
				( pin "vin(2)"
					( attribute "PN" "9"
						( Origin gPackager )
					)
					( objectStatus "EU8A2.9" )
				)
				( pin "vout(0)"
					( attribute "PN" "1"
						( Origin gPackager )
					)
					( objectStatus "EU8A2.1" )
				)
				( pin "vout(1)"
					( attribute "PN" "2"
						( Origin gPackager )
					)
					( objectStatus "EU8A2.2" )
				)
				( pin "vout(2)"
					( attribute "PN" "3"
						( Origin gPackager )
					)
					( objectStatus "EU8A2.3" )
				)
			)
			( gate "@baseboard_fab2_lib.baseboard_fab2(sch_1):page237_i90"
				( attribute "CDS_LIB" "mstr_discrete"
					( Origin gPackager )
				)
				( attribute "CDS_LOCATION" "R8A11"
					( Origin gPackager )
				)
				( attribute "CDS_SEC" "1"
					( Origin gPackager )
				)
				( attribute "LOCATION" "R8A11"
					( Origin gFrontEnd )
				)
				( attribute "MATERIAL" "CHIP"
					( Origin gFrontEnd )
				)
				( attribute "PACK_TYPE" "0402"
					( Origin gFrontEnd )
				)
				( attribute "PART_NUMBER" "G21796-250"
					( Origin gFrontEnd )
				)
				( attribute "PHYS_PAGE" "237"
					( Origin gFrontEnd )
				)
				( attribute "ROOM" "P1V8_PCH_STBY_VR"
					( Origin gFrontEnd )
				)
				( attribute "ROT" "0"
					( Origin gFrontEnd )
				)
				( attribute "SEC" "1"
					( Origin gFrontEnd )
				)
				( attribute "SEC_TYPE" "0402"
					( Origin gFrontEnd )
				)
				( attribute "TOLERANCE" "1.0%"
					( Origin gFrontEnd )
				)
				( attribute "VALUE" "22.1"
					( Origin gFrontEnd )
				)
				( attribute "VER" "1"
					( Origin gFrontEnd )
				)
				( attribute "WATTAGE" "1/16W"
					( Origin gFrontEnd )
				)
				( attribute "XY" "(2175,3650)"
					( Origin gFrontEnd )
				)
				( attribute "CHIPS_PART_NAME" "RES"
					( Origin gPackager )
				)
				( attribute "CDS_PART_NAME" "RES_0402-22.1,1.0%,1/16W,CHIP,A"
					( Origin gPackager )
				)
				( objectStatus "R8A11" )
				( pin "a"
					( attribute "PN" "1"
						( Origin gPackager )
					)
					( objectStatus "R8A11.1" )
				)
				( pin "b"
					( attribute "PN" "2"
						( Origin gPackager )
					)
					( objectStatus "R8A11.2" )
				)
			)
			( gate "@baseboard_fab2_lib.baseboard_fab2(sch_1):page238_i5"
				( attribute "BOM_COST" "P1V26_BMC_STBY_VR"
					( Origin gFrontEnd )
				)
				( attribute "CDS_LIB" "mstr_discrete"
					( Origin gPackager )
				)
				( attribute "CDS_LOCATION" "C9F9"
					( Origin gPackager )
				)
				( attribute "CDS_SEC" "1"
					( Origin gPackager )
				)
				( attribute "LOCATION" "C9F9"
					( Origin gFrontEnd )
				)
				( attribute "MATERIAL" "EMPTY"
					( Origin gFrontEnd )
				)
				( attribute "PACK_TYPE" "0402LF"
					( Origin gFrontEnd )
				)
				( attribute "PART_NUMBER" "A36096-046"
					( Origin gFrontEnd )
				)
				( attribute "PHYS_PAGE" "238"
					( Origin gFrontEnd )
				)
				( attribute "ROOM" "P1V26_BMC_STBY_VR"
					( Origin gFrontEnd )
				)
				( attribute "ROT" "2"
					( Origin gFrontEnd )
				)
				( attribute "SEC" "1"
					( Origin gPackager )
				)
				( attribute "TOLERANCE" "10%"
					( Origin gFrontEnd )
				)
				( attribute "VALUE" "1000PF"
					( Origin gFrontEnd )
				)
				( attribute "VER" "1"
					( Origin gFrontEnd )
				)
				( attribute "VOLTAGE" "50V"
					( Units "uVoltage" "V" 1.000000)
					( Origin gFrontEnd )
				)
				( attribute "XY" "(-2000,2175)"
					( Origin gFrontEnd )
				)
				( attribute "CHIPS_PART_NAME" "CAP"
					( Origin gPackager )
				)
				( attribute "CDS_PART_NAME" "CAP_0402LF-1000PF,50V,10%,EMPTA"
					( Origin gPackager )
				)
				( objectStatus "C9F9" )
				( pin "a"
					( attribute "PN" "1"
						( Origin gPackager )
					)
					( objectStatus "C9F9.1" )
				)
				( pin "b"
					( attribute "PN" "2"
						( Origin gPackager )
					)
					( objectStatus "C9F9.2" )
				)
			)
			( gate "@baseboard_fab2_lib.baseboard_fab2(sch_1):page238_i7"
				( attribute "BOM_COST" "P1V26_BMC_STBY_VR"
					( Origin gFrontEnd )
				)
				( attribute "CDS_LIB" "mstr_discrete"
					( Origin gPackager )
				)
				( attribute "CDS_LOCATION" "C9F3"
					( Origin gPackager )
				)
				( attribute "CDS_SEC" "1"
					( Origin gPackager )
				)
				( attribute "LOCATION" "C9F3"
					( Origin gFrontEnd )
				)
				( attribute "MATERIAL" "X6S"
					( Origin gFrontEnd )
				)
				( attribute "PACK_TYPE" "0603"
					( Origin gFrontEnd )
				)
				( attribute "PART_NUMBER" "E15431-002"
					( Origin gFrontEnd )
				)
				( attribute "PHYS_PAGE" "238"
					( Origin gFrontEnd )
				)
				( attribute "ROOM" "P1V26_BMC_STBY_VR"
					( Origin gFrontEnd )
				)
				( attribute "ROT" "0"
					( Origin gFrontEnd )
				)
				( attribute "SEC" "1"
					( Origin gFrontEnd )
				)
				( attribute "SEC_TYPE" "0603"
					( Origin gFrontEnd )
				)
				( attribute "TOLERANCE" "20%"
					( Origin gFrontEnd )
				)
				( attribute "VALUE" "10UF"
					( Origin gFrontEnd )
				)
				( attribute "VER" "1"
					( Origin gFrontEnd )
				)
				( attribute "VOLTAGE" "6.3V"
					( Units "uVoltage" "V" 1.000000)
					( Origin gFrontEnd )
				)
				( attribute "XY" "(-1875,3025)"
					( Origin gFrontEnd )
				)
				( attribute "CHIPS_PART_NAME" "CAP"
					( Origin gPackager )
				)
				( attribute "CDS_PART_NAME" "CAP_0603-10UF,6.3V,20%,X6S,E15A"
					( Origin gPackager )
				)
				( objectStatus "C9F3" )
				( pin "a"
					( attribute "PN" "1"
						( Origin gPackager )
					)
					( objectStatus "C9F3.1" )
				)
				( pin "b"
					( attribute "PN" "2"
						( Origin gPackager )
					)
					( objectStatus "C9F3.2" )
				)
			)
			( gate "@baseboard_fab2_lib.baseboard_fab2(sch_1):page238_i14"
				( attribute "BOM_COST" "P1V26_BMC_STBY_VR"
					( Origin gFrontEnd )
				)
				( attribute "CDS_LIB" "mstr_discrete"
					( Origin gPackager )
				)
				( attribute "CDS_LOCATION" "R9F8"
					( Origin gPackager )
				)
				( attribute "CDS_SEC" "1"
					( Origin gPackager )
				)
				( attribute "LOCATION" "R9F8"
					( Origin gFrontEnd )
				)
				( attribute "MATERIAL" "CHIP"
					( Origin gFrontEnd )
				)
				( attribute "P1V5_STBY_IBMC" "<< NULL >>"
					( Origin gFrontEnd )
				)
				( attribute "P1V5_STBY_IBMC_VR" "<< NULL >>"
					( Origin gFrontEnd )
				)
				( attribute "PACK_TYPE" "0402"
					( Origin gFrontEnd )
				)
				( attribute "PART_NUMBER" "G21796-016"
					( Origin gFrontEnd )
				)
				( attribute "PHYS_PAGE" "238"
					( Origin gFrontEnd )
				)
				( attribute "ROOM" "P1V26_BMC_STBY_VR"
					( Origin gFrontEnd )
				)
				( attribute "ROT" "1"
					( Origin gFrontEnd )
				)
				( attribute "SEC" "1"
					( Origin gFrontEnd )
				)
				( attribute "SEC_TYPE" "0402"
					( Origin gFrontEnd )
				)
				( attribute "TOLERANCE" "1%"
					( Origin gFrontEnd )
				)
				( attribute "VALUE" "10.0K"
					( Origin gFrontEnd )
				)
				( attribute "VER" "1"
					( Origin gFrontEnd )
				)
				( attribute "WATTAGE" "1/16W"
					( Origin gFrontEnd )
				)
				( attribute "XY" "(1025,2100)"
					( Origin gFrontEnd )
				)
				( attribute "CHIPS_PART_NAME" "RES"
					( Origin gPackager )
				)
				( attribute "CDS_PART_NAME" "RES_0402-10.0K,1%,1/16W,CHIP,GA"
					( Origin gPackager )
				)
				( objectStatus "R9F8" )
				( pin "a"
					( attribute "PN" "1"
						( Origin gPackager )
					)
					( objectStatus "R9F8.1" )
				)
				( pin "b"
					( attribute "PN" "2"
						( Origin gPackager )
					)
					( objectStatus "R9F8.2" )
				)
			)
			( gate "@baseboard_fab2_lib.baseboard_fab2(sch_1):page238_i19"
				( attribute "BOM_COST" "P1V26_BMC_STBY_VR"
					( Origin gFrontEnd )
				)
				( attribute "CDS_LIB" "mstr_discrete"
					( Origin gPackager )
				)
				( attribute "CDS_LOCATION" "C9F8"
					( Origin gPackager )
				)
				( attribute "CDS_SEC" "1"
					( Origin gPackager )
				)
				( attribute "LOCATION" "C9F8"
					( Origin gFrontEnd )
				)
				( attribute "MATERIAL" "X7R"
					( Origin gFrontEnd )
				)
				( attribute "PACK_TYPE" "0402LF"
					( Origin gFrontEnd )
				)
				( attribute "PART_NUMBER" "A36096-046"
					( Origin gFrontEnd )
				)
				( attribute "PHYS_PAGE" "238"
					( Origin gFrontEnd )
				)
				( attribute "ROOM" "P1V26_BMC_STBY_VR"
					( Origin gFrontEnd )
				)
				( attribute "ROT" "0"
					( Origin gFrontEnd )
				)
				( attribute "SEC" "1"
					( Origin gPackager )
				)
				( attribute "TOLERANCE" "10%"
					( Origin gFrontEnd )
				)
				( attribute "VALUE" "1000PF"
					( Origin gFrontEnd )
				)
				( attribute "VER" "1"
					( Origin gFrontEnd )
				)
				( attribute "VOLTAGE" "50V"
					( Units "uVoltage" "V" 1.000000)
					( Origin gFrontEnd )
				)
				( attribute "XY" "(1250,3050)"
					( Origin gFrontEnd )
				)
				( attribute "CHIPS_PART_NAME" "CAP"
					( Origin gPackager )
				)
				( attribute "CDS_PART_NAME" "CAP_0402LF-1000PF,50V,10%,X7R,A"
					( Origin gPackager )
				)
				( objectStatus "C9F8" )
				( pin "a"
					( attribute "PN" "1"
						( Origin gPackager )
					)
					( objectStatus "C9F8.1" )
				)
				( pin "b"
					( attribute "PN" "2"
						( Origin gPackager )
					)
					( objectStatus "C9F8.2" )
				)
			)
			( gate "@baseboard_fab2_lib.baseboard_fab2(sch_1):page238_i21"
				( attribute "BOM_COST" "P1V26_BMC_STBY_VR"
					( Origin gFrontEnd )
				)
				( attribute "CDS_LIB" "mstr_discrete"
					( Origin gPackager )
				)
				( attribute "CDS_LOCATION" "R9F13"
					( Origin gPackager )
				)
				( attribute "CDS_SEC" "1"
					( Origin gPackager )
				)
				( attribute "LOCATION" "R9F13"
					( Origin gFrontEnd )
				)
				( attribute "MATERIAL" "CHIP"
					( Origin gFrontEnd )
				)
				( attribute "P1V5_STBY_IBMC" "<< NULL >>"
					( Origin gFrontEnd )
				)
				( attribute "P1V5_STBY_IBMC_VR" "<< NULL >>"
					( Origin gFrontEnd )
				)
				( attribute "PACK_TYPE" "0402"
					( Origin gFrontEnd )
				)
				( attribute "PART_NUMBER" "G21796-016"
					( Origin gFrontEnd )
				)
				( attribute "PHYS_PAGE" "238"
					( Origin gFrontEnd )
				)
				( attribute "ROOM" "P1V26_BMC_STBY_VR"
					( Origin gFrontEnd )
				)
				( attribute "ROT" "0"
					( Origin gFrontEnd )
				)
				( attribute "SEC" "1"
					( Origin gFrontEnd )
				)
				( attribute "SEC_TYPE" "0402"
					( Origin gFrontEnd )
				)
				( attribute "TOLERANCE" "1%"
					( Origin gFrontEnd )
				)
				( attribute "VALUE" "10.0K"
					( Origin gFrontEnd )
				)
				( attribute "VER" "2"
					( Origin gFrontEnd )
				)
				( attribute "WATTAGE" "1/16W"
					( Origin gFrontEnd )
				)
				( attribute "XY" "(900,3500)"
					( Origin gFrontEnd )
				)
				( attribute "CHIPS_PART_NAME" "RES"
					( Origin gPackager )
				)
				( attribute "CDS_PART_NAME" "RES_0402-10.0K,1%,1/16W,CHIP,GA"
					( Origin gPackager )
				)
				( objectStatus "R9F13" )
				( pin "a"
					( attribute "PN" "1"
						( Origin gPackager )
					)
					( objectStatus "R9F13.1" )
				)
				( pin "b"
					( attribute "PN" "2"
						( Origin gPackager )
					)
					( objectStatus "R9F13.2" )
				)
			)
			( gate "@baseboard_fab2_lib.baseboard_fab2(sch_1):page238_i23"
				( attribute "BOM_COST" "P1V26_BMC_STBY_VR"
					( Origin gFrontEnd )
				)
				( attribute "CDS_LIB" "mstr_discrete"
					( Origin gPackager )
				)
				( attribute "CDS_LOCATION" "C9E10"
					( Origin gPackager )
				)
				( attribute "CDS_SEC" "1"
					( Origin gPackager )
				)
				( attribute "LOCATION" "C9E10"
					( Origin gFrontEnd )
				)
				( attribute "MATERIAL" "X6S"
					( Origin gFrontEnd )
				)
				( attribute "PACK_TYPE" "0603"
					( Origin gFrontEnd )
				)
				( attribute "PART_NUMBER" "E15431-002"
					( Origin gFrontEnd )
				)
				( attribute "PHYS_PAGE" "238"
					( Origin gFrontEnd )
				)
				( attribute "ROOM" "P1V26_BMC_STBY_VR"
					( Origin gFrontEnd )
				)
				( attribute "ROT" "0"
					( Origin gFrontEnd )
				)
				( attribute "SEC" "1"
					( Origin gFrontEnd )
				)
				( attribute "SEC_TYPE" "0603"
					( Origin gFrontEnd )
				)
				( attribute "TOLERANCE" "20%"
					( Origin gFrontEnd )
				)
				( attribute "VALUE" "10UF"
					( Origin gFrontEnd )
				)
				( attribute "VER" "1"
					( Origin gFrontEnd )
				)
				( attribute "VOLTAGE" "6.3V"
					( Units "uVoltage" "V" 1.000000)
					( Origin gFrontEnd )
				)
				( attribute "XY" "(1950,2525)"
					( Origin gFrontEnd )
				)
				( attribute "CHIPS_PART_NAME" "CAP"
					( Origin gPackager )
				)
				( attribute "CDS_PART_NAME" "CAP_0603-10UF,6.3V,20%,X6S,E15A"
					( Origin gPackager )
				)
				( objectStatus "C9E10" )
				( pin "a"
					( attribute "PN" "1"
						( Origin gPackager )
					)
					( objectStatus "C9E10.1" )
				)
				( pin "b"
					( attribute "PN" "2"
						( Origin gPackager )
					)
					( objectStatus "C9E10.2" )
				)
			)
			( gate "@baseboard_fab2_lib.baseboard_fab2(sch_1):page238_i30"
				( attribute "BOM_COST" "P1V26_BMC_STBY_VR"
					( Origin gFrontEnd )
				)
				( attribute "CDS_LIB" "mstr_discrete"
					( Origin gPackager )
				)
				( attribute "CDS_LOCATION" "C9F4"
					( Origin gPackager )
				)
				( attribute "CDS_SEC" "1"
					( Origin gPackager )
				)
				( attribute "LOCATION" "C9F4"
					( Origin gFrontEnd )
				)
				( attribute "MATERIAL" "X6S"
					( Origin gFrontEnd )
				)
				( attribute "PACK_TYPE" "0805LF"
					( Origin gFrontEnd )
				)
				( attribute "PART_NUMBER" "C95333-002"
					( Origin gFrontEnd )
				)
				( attribute "PHYS_PAGE" "238"
					( Origin gFrontEnd )
				)
				( attribute "ROOM" "P1V26_BMC_STBY_VR"
					( Origin gFrontEnd )
				)
				( attribute "ROT" "0"
					( Origin gFrontEnd )
				)
				( attribute "SEC" "1"
					( Origin gFrontEnd )
				)
				( attribute "SEC_TYPE" "0805LF"
					( Origin gFrontEnd )
				)
				( attribute "TOLERANCE" "20%"
					( Origin gFrontEnd )
				)
				( attribute "VALUE" "22UF"
					( Origin gFrontEnd )
				)
				( attribute "VER" "1"
					( Origin gFrontEnd )
				)
				( attribute "VOLTAGE" "4V"
					( Units "uVoltage" "V" 1.000000)
					( Origin gFrontEnd )
				)
				( attribute "XY" "(2325,2525)"
					( Origin gFrontEnd )
				)
				( attribute "CHIPS_PART_NAME" "CAP"
					( Origin gPackager )
				)
				( attribute "CDS_PART_NAME" "CAP_0805LF-22UF,4V,20%,X6S,C95A"
					( Origin gPackager )
				)
				( objectStatus "C9F4" )
				( pin "a"
					( attribute "PN" "1"
						( Origin gPackager )
					)
					( objectStatus "C9F4.1" )
				)
				( pin "b"
					( attribute "PN" "2"
						( Origin gPackager )
					)
					( objectStatus "C9F4.2" )
				)
			)
			( gate "@baseboard_fab2_lib.baseboard_fab2(sch_1):page238_i39"
				( attribute "CDS_LIB" "mstr_discrete"
					( Origin gPackager )
				)
				( attribute "CDS_LOCATION" "C9E11"
					( Origin gPackager )
				)
				( attribute "CDS_SEC" "1"
					( Origin gPackager )
				)
				( attribute "LOCATION" "C9E11"
					( Origin gFrontEnd )
				)
				( attribute "MATERIAL" "X6S"
					( Origin gFrontEnd )
				)
				( attribute "PACK_TYPE" "0402"
					( Origin gFrontEnd )
				)
				( attribute "PART_NUMBER" "D97712-011"
					( Origin gFrontEnd )
				)
				( attribute "PHYS_PAGE" "238"
					( Origin gFrontEnd )
				)
				( attribute "ROT" "0"
					( Origin gFrontEnd )
				)
				( attribute "SEC" "1"
					( Origin gFrontEnd )
				)
				( attribute "SEC_TYPE" "0402"
					( Origin gFrontEnd )
				)
				( attribute "TOLERANCE" "10%"
					( Origin gFrontEnd )
				)
				( attribute "VALUE" "1.0UF"
					( Origin gFrontEnd )
				)
				( attribute "VER" "1"
					( Origin gFrontEnd )
				)
				( attribute "VOLTAGE" "16V"
					( Units "uVoltage" "V" 1.000000)
					( Origin gFrontEnd )
				)
				( attribute "XY" "(-1275,2150)"
					( Origin gFrontEnd )
				)
				( attribute "CHIPS_PART_NAME" "CAP"
					( Origin gPackager )
				)
				( attribute "CDS_PART_NAME" "CAP_0402-1.0UF,16V,10%,X6S,D97A"
					( Origin gPackager )
				)
				( objectStatus "C9E11" )
				( pin "a"
					( attribute "PN" "1"
						( Origin gPackager )
					)
					( objectStatus "C9E11.1" )
				)
				( pin "b"
					( attribute "PN" "2"
						( Origin gPackager )
					)
					( objectStatus "C9E11.2" )
				)
			)
			( gate "@baseboard_fab2_lib.baseboard_fab2(sch_1):page238_i40"
				( attribute "CDS_LIB" "mstr_vreg"
					( Origin gPackager )
				)
				( attribute "CDS_LOCATION" "EU9F1"
					( Origin gPackager )
				)
				( attribute "CDS_SEC" "1"
					( Origin gPackager )
				)
				( attribute "LOCATION" "EU9F1"
					( Origin gFrontEnd )
				)
				( attribute "MATERIAL" "IC"
					( Origin gFrontEnd )
				)
				( attribute "PACK_TYPE" "DFN"
					( Origin gFrontEnd )
				)
				( attribute "PART_NUMBER" "H65765-001"
					( Origin gFrontEnd )
				)
				( attribute "PHYS_PAGE" "238"
					( Origin gFrontEnd )
				)
				( attribute "ROOM" "P1V26_BMC_STBY_VR"
					( Origin gFrontEnd )
				)
				( attribute "ROT" "0"
					( Origin gFrontEnd )
				)
				( attribute "SEC" "1"
					( Origin gFrontEnd )
				)
				( attribute "SEC_TYPE" "DFN"
					( Origin gFrontEnd )
				)
				( attribute "VER" "1"
					( Origin gFrontEnd )
				)
				( attribute "XY" "(-175,2700)"
					( Origin gFrontEnd )
				)
				( attribute "CHIPS_PART_NAME" "RT9059"
					( Origin gPackager )
				)
				( attribute "CDS_PART_NAME" "RT9059_DFN-IC,H65765-001"
					( Origin gPackager )
				)
				( objectStatus "EU9F1" )
				( pin "adj_nc"
					( attribute "PN" "4"
						( Origin gPackager )
					)
					( objectStatus "EU9F1.4" )
				)
				( pin "en"
					( attribute "PN" "6"
						( Origin gPackager )
					)
					( objectStatus "EU9F1.6" )
				)
				( pin "gnd"
					( attribute "PN" "11"
						( Origin gPackager )
					)
					( objectStatus "EU9F1.11" )
				)
				( pin "pgood"
					( attribute "PN" "5"
						( Origin gPackager )
					)
					( objectStatus "EU9F1.5" )
				)
				( pin "vdd"
					( attribute "PN" "10"
						( Origin gPackager )
					)
					( objectStatus "EU9F1.10" )
				)
				( pin "vin(0)"
					( attribute "PN" "7"
						( Origin gPackager )
					)
					( objectStatus "EU9F1.7" )
				)
				( pin "vin(1)"
					( attribute "PN" "8"
						( Origin gPackager )
					)
					( objectStatus "EU9F1.8" )
				)
				( pin "vin(2)"
					( attribute "PN" "9"
						( Origin gPackager )
					)
					( objectStatus "EU9F1.9" )
				)
				( pin "vout(0)"
					( attribute "PN" "1"
						( Origin gPackager )
					)
					( objectStatus "EU9F1.1" )
				)
				( pin "vout(1)"
					( attribute "PN" "2"
						( Origin gPackager )
					)
					( objectStatus "EU9F1.2" )
				)
				( pin "vout(2)"
					( attribute "PN" "3"
						( Origin gPackager )
					)
					( objectStatus "EU9F1.3" )
				)
			)
			( gate "@baseboard_fab2_lib.baseboard_fab2(sch_1):page238_i41"
				( attribute "CDS_LIB" "mstr_discrete"
					( Origin gPackager )
				)
				( attribute "CDS_LOCATION" "R9F11"
					( Origin gPackager )
				)
				( attribute "CDS_SEC" "1"
					( Origin gPackager )
				)
				( attribute "LOCATION" "R9F11"
					( Origin gFrontEnd )
				)
				( attribute "MATERIAL" "CHIP"
					( Origin gFrontEnd )
				)
				( attribute "PACK_TYPE" "0402"
					( Origin gFrontEnd )
				)
				( attribute "PART_NUMBER" "G21796-250"
					( Origin gFrontEnd )
				)
				( attribute "PHYS_PAGE" "238"
					( Origin gFrontEnd )
				)
				( attribute "ROOM" "P1V26_BMC_STBY_VR"
					( Origin gFrontEnd )
				)
				( attribute "ROT" "0"
					( Origin gFrontEnd )
				)
				( attribute "SEC" "1"
					( Origin gFrontEnd )
				)
				( attribute "SEC_TYPE" "0402"
					( Origin gFrontEnd )
				)
				( attribute "TOLERANCE" "1.0%"
					( Origin gFrontEnd )
				)
				( attribute "VALUE" "22.1"
					( Origin gFrontEnd )
				)
				( attribute "VER" "1"
					( Origin gFrontEnd )
				)
				( attribute "WATTAGE" "1/16W"
					( Origin gFrontEnd )
				)
				( attribute "XY" "(1850,3200)"
					( Origin gFrontEnd )
				)
				( attribute "CHIPS_PART_NAME" "RES"
					( Origin gPackager )
				)
				( attribute "CDS_PART_NAME" "RES_0402-22.1,1.0%,1/16W,CHIP,A"
					( Origin gPackager )
				)
				( objectStatus "R9F11" )
				( pin "a"
					( attribute "PN" "1"
						( Origin gPackager )
					)
					( objectStatus "R9F11.1" )
				)
				( pin "b"
					( attribute "PN" "2"
						( Origin gPackager )
					)
					( objectStatus "R9F11.2" )
				)
			)
			( gate "@baseboard_fab2_lib.baseboard_fab2(sch_1):page239_i4"
				( attribute "BOM_COST" "P1V538_BMC_STBY_VR"
					( Origin gFrontEnd )
				)
				( attribute "CDS_LIB" "mstr_discrete"
					( Origin gPackager )
				)
				( attribute "CDS_LOCATION" "C9F10"
					( Origin gPackager )
				)
				( attribute "CDS_SEC" "1"
					( Origin gPackager )
				)
				( attribute "LOCATION" "C9F10"
					( Origin gFrontEnd )
				)
				( attribute "MATERIAL" "X7R"
					( Origin gFrontEnd )
				)
				( attribute "PACK_TYPE" "0402LF"
					( Origin gFrontEnd )
				)
				( attribute "PART_NUMBER" "A36096-046"
					( Origin gFrontEnd )
				)
				( attribute "PHYS_PAGE" "239"
					( Origin gFrontEnd )
				)
				( attribute "ROOM" "P1V538_BMC_STBY_VR"
					( Origin gFrontEnd )
				)
				( attribute "ROT" "0"
					( Origin gFrontEnd )
				)
				( attribute "SEC" "1"
					( Origin gPackager )
				)
				( attribute "TOLERANCE" "10%"
					( Origin gFrontEnd )
				)
				( attribute "VALUE" "1000PF"
					( Origin gFrontEnd )
				)
				( attribute "VER" "1"
					( Origin gFrontEnd )
				)
				( attribute "VOLTAGE" "50V"
					( Units "uVoltage" "V" 1.000000)
					( Origin gFrontEnd )
				)
				( attribute "XY" "(10375,4150)"
					( Origin gFrontEnd )
				)
				( attribute "CHIPS_PART_NAME" "CAP"
					( Origin gPackager )
				)
				( attribute "CDS_PART_NAME" "CAP_0402LF-1000PF,50V,10%,X7R,A"
					( Origin gPackager )
				)
				( objectStatus "C9F10" )
				( pin "a"
					( attribute "PN" "1"
						( Origin gPackager )
					)
					( objectStatus "C9F10.1" )
				)
				( pin "b"
					( attribute "PN" "2"
						( Origin gPackager )
					)
					( objectStatus "C9F10.2" )
				)
			)
			( gate "@baseboard_fab2_lib.baseboard_fab2(sch_1):page239_i6"
				( attribute "BOM_COST" "P1V538_BMC_STBY_VR"
					( Origin gFrontEnd )
				)
				( attribute "CDS_LIB" "mstr_discrete"
					( Origin gPackager )
				)
				( attribute "CDS_LOCATION" "R9F12"
					( Origin gPackager )
				)
				( attribute "CDS_SEC" "1"
					( Origin gPackager )
				)
				( attribute "LOCATION" "R9F12"
					( Origin gFrontEnd )
				)
				( attribute "MATERIAL" "CHIP"
					( Origin gFrontEnd )
				)
				( attribute "P1V5_STBY_IBMC" "<< NULL >>"
					( Origin gFrontEnd )
				)
				( attribute "P1V5_STBY_IBMC_VR" "<< NULL >>"
					( Origin gFrontEnd )
				)
				( attribute "PACK_TYPE" "0402"
					( Origin gFrontEnd )
				)
				( attribute "PART_NUMBER" "G21796-016"
					( Origin gFrontEnd )
				)
				( attribute "PHYS_PAGE" "239"
					( Origin gFrontEnd )
				)
				( attribute "ROOM" "P1V538_BMC_STBY_VR"
					( Origin gFrontEnd )
				)
				( attribute "ROT" "0"
					( Origin gFrontEnd )
				)
				( attribute "SEC" "1"
					( Origin gFrontEnd )
				)
				( attribute "SEC_TYPE" "0402"
					( Origin gFrontEnd )
				)
				( attribute "TOLERANCE" "1%"
					( Origin gFrontEnd )
				)
				( attribute "VALUE" "10.0K"
					( Origin gFrontEnd )
				)
				( attribute "VER" "2"
					( Origin gFrontEnd )
				)
				( attribute "WATTAGE" "1/16W"
					( Origin gFrontEnd )
				)
				( attribute "XY" "(9625,4525)"
					( Origin gFrontEnd )
				)
				( attribute "CHIPS_PART_NAME" "RES"
					( Origin gPackager )
				)
				( attribute "CDS_PART_NAME" "RES_0402-10.0K,1%,1/16W,CHIP,GA"
					( Origin gPackager )
				)
				( objectStatus "R9F12" )
				( pin "a"
					( attribute "PN" "1"
						( Origin gPackager )
					)
					( objectStatus "R9F12.1" )
				)
				( pin "b"
					( attribute "PN" "2"
						( Origin gPackager )
					)
					( objectStatus "R9F12.2" )
				)
			)
			( gate "@baseboard_fab2_lib.baseboard_fab2(sch_1):page239_i7"
				( attribute "BOM_COST" "P1V538_BMC_STBY_VR"
					( Origin gFrontEnd )
				)
				( attribute "CDS_LIB" "mstr_discrete"
					( Origin gPackager )
				)
				( attribute "CDS_LOCATION" "C9F13"
					( Origin gPackager )
				)
				( attribute "CDS_SEC" "1"
					( Origin gPackager )
				)
				( attribute "LOCATION" "C9F13"
					( Origin gFrontEnd )
				)
				( attribute "MATERIAL" "X6S"
					( Origin gFrontEnd )
				)
				( attribute "PACK_TYPE" "0805LF"
					( Origin gFrontEnd )
				)
				( attribute "PART_NUMBER" "C95333-002"
					( Origin gFrontEnd )
				)
				( attribute "PHYS_PAGE" "239"
					( Origin gFrontEnd )
				)
				( attribute "ROOM" "P1V538_BMC_STBY_VR"
					( Origin gFrontEnd )
				)
				( attribute "ROT" "0"
					( Origin gFrontEnd )
				)
				( attribute "SEC" "1"
					( Origin gFrontEnd )
				)
				( attribute "SEC_TYPE" "0805LF"
					( Origin gFrontEnd )
				)
				( attribute "TOLERANCE" "20%"
					( Origin gFrontEnd )
				)
				( attribute "VALUE" "22UF"
					( Origin gFrontEnd )
				)
				( attribute "VER" "1"
					( Origin gFrontEnd )
				)
				( attribute "VOLTAGE" "4V"
					( Units "uVoltage" "V" 1.000000)
					( Origin gFrontEnd )
				)
				( attribute "XY" "(11300,3550)"
					( Origin gFrontEnd )
				)
				( attribute "CHIPS_PART_NAME" "CAP"
					( Origin gPackager )
				)
				( attribute "CDS_PART_NAME" "CAP_0805LF-22UF,4V,20%,X6S,C95A"
					( Origin gPackager )
				)
				( objectStatus "C9F13" )
				( pin "a"
					( attribute "PN" "1"
						( Origin gPackager )
					)
					( objectStatus "C9F13.1" )
				)
				( pin "b"
					( attribute "PN" "2"
						( Origin gPackager )
					)
					( objectStatus "C9F13.2" )
				)
			)
			( gate "@baseboard_fab2_lib.baseboard_fab2(sch_1):page239_i12"
				( attribute "BOM_COST" "P1V538_BMC_STBY_VR"
					( Origin gFrontEnd )
				)
				( attribute "CDS_LIB" "mstr_discrete"
					( Origin gPackager )
				)
				( attribute "CDS_LOCATION" "C1T15"
					( Origin gPackager )
				)
				( attribute "CDS_SEC" "1"
					( Origin gPackager )
				)
				( attribute "LOCATION" "C1T15"
					( Origin gFrontEnd )
				)
				( attribute "MATERIAL" "X6S"
					( Origin gFrontEnd )
				)
				( attribute "PACK_TYPE" "0603"
					( Origin gFrontEnd )
				)
				( attribute "PART_NUMBER" "E15431-002"
					( Origin gFrontEnd )
				)
				( attribute "PHYS_PAGE" "239"
					( Origin gFrontEnd )
				)
				( attribute "ROOM" "P1V538_BMC_STBY_VR"
					( Origin gFrontEnd )
				)
				( attribute "ROT" "0"
					( Origin gFrontEnd )
				)
				( attribute "SEC" "1"
					( Origin gFrontEnd )
				)
				( attribute "SEC_TYPE" "0603"
					( Origin gFrontEnd )
				)
				( attribute "TOLERANCE" "20%"
					( Origin gFrontEnd )
				)
				( attribute "VALUE" "10UF"
					( Origin gFrontEnd )
				)
				( attribute "VER" "1"
					( Origin gFrontEnd )
				)
				( attribute "VOLTAGE" "6.3V"
					( Units "uVoltage" "V" 1.000000)
					( Origin gFrontEnd )
				)
				( attribute "XY" "(10875,3625)"
					( Origin gFrontEnd )
				)
				( attribute "CHIPS_PART_NAME" "CAP"
					( Origin gPackager )
				)
				( attribute "CDS_PART_NAME" "CAP_0603-10UF,6.3V,20%,X6S,E15A"
					( Origin gPackager )
				)
				( objectStatus "C1T15" )
				( pin "a"
					( attribute "PN" "1"
						( Origin gPackager )
					)
					( objectStatus "C1T15.1" )
				)
				( pin "b"
					( attribute "PN" "2"
						( Origin gPackager )
					)
					( objectStatus "C1T15.2" )
				)
			)
			( gate "@baseboard_fab2_lib.baseboard_fab2(sch_1):page238_i45"
				( attribute "CDS_LIB" "w_hdl"
					( Origin gPackager )
				)
				( attribute "CDS_LMAN_SYM_OUTLINE" "-50,75,50,-75"
					( Origin gPackager )
				)
				( attribute "LOCATION" "R9F6"
					( Origin gFrontEnd )
				)
				( attribute "PACK_TYPE" "SMD-RG"
					( Origin gFrontEnd )
				)
				( attribute "PART_NUMBER" "64.44215.6DL"
					( Origin gFrontEnd )
				)
				( attribute "PHYS_PAGE" "238"
					( Origin gFrontEnd )
				)
				( attribute "ROT" "0"
					( Origin gFrontEnd )
				)
				( attribute "VALUE" "4K42R2F-GP"
					( Origin gFrontEnd )
				)
				( attribute "VER" "1"
					( Origin gFrontEnd )
				)
				( attribute "XY" "(1025,2475)"
					( Origin gFrontEnd )
				)
				( attribute "CHIPS_PART_NAME" "4K42R2F-GP"
					( Origin gPackager )
				)
				( attribute "CDS_PART_NAME" "4K42R2F-GP_SMD-RG-4K42R2F-GP,6A"
					( Origin gPackager )
				)
				( attribute "CDS_LOCATION" "R9F6"
					( Origin gPackager )
				)
				( attribute "CDS_SEC" "1"
					( Origin gPackager )
				)
				( attribute "SEC" "1"
					( Origin gPackager )
				)
				( objectStatus "R9F6" )
				( pin "\1\"
					( attribute "PN" "1"
						( Origin gPackager )
					)
					( objectStatus "R9F6.1" )
				)
				( pin "\2\"
					( attribute "PN" "2"
						( Origin gPackager )
					)
					( objectStatus "R9F6.2" )
				)
			)
			( gate "@baseboard_fab2_lib.baseboard_fab2(sch_1):page239_i15"
				( attribute "BOM_COST" "P1V538_BMC_STBY_VR"
					( Origin gFrontEnd )
				)
				( attribute "CDS_LIB" "mstr_discrete"
					( Origin gPackager )
				)
				( attribute "CDS_LOCATION" "R9F32"
					( Origin gPackager )
				)
				( attribute "CDS_SEC" "1"
					( Origin gPackager )
				)
				( attribute "LOCATION" "R9F32"
					( Origin gFrontEnd )
				)
				( attribute "MATERIAL" "CHIP"
					( Origin gFrontEnd )
				)
				( attribute "P1V5_STBY_IBMC" "<< NULL >>"
					( Origin gFrontEnd )
				)
				( attribute "P1V5_STBY_IBMC_VR" "<< NULL >>"
					( Origin gFrontEnd )
				)
				( attribute "PACK_TYPE" "0402"
					( Origin gFrontEnd )
				)
				( attribute "PART_NUMBER" "G21796-221"
					( Origin gFrontEnd )
				)
				( attribute "PHYS_PAGE" "239"
					( Origin gFrontEnd )
				)
				( attribute "ROOM" "P1V538_BMC_STBY_VR"
					( Origin gFrontEnd )
				)
				( attribute "ROT" "1"
					( Origin gFrontEnd )
				)
				( attribute "SEC" "1"
					( Origin gFrontEnd )
				)
				( attribute "SEC_TYPE" "0402"
					( Origin gFrontEnd )
				)
				( attribute "TOLERANCE" "1.0%"
					( Origin gFrontEnd )
				)
				( attribute "VALUE" "13K"
					( Origin gFrontEnd )
				)
				( attribute "VER" "1"
					( Origin gFrontEnd )
				)
				( attribute "WATTAGE" "1/16W"
					( Origin gFrontEnd )
				)
				( attribute "XY" "(10350,3125)"
					( Origin gFrontEnd )
				)
				( attribute "CHIPS_PART_NAME" "RES"
					( Origin gPackager )
				)
				( attribute "CDS_PART_NAME" "RES_0402-13K,1.0%,1/16W,CHIP,GA"
					( Origin gPackager )
				)
				( objectStatus "R9F32" )
				( pin "a"
					( attribute "PN" "1"
						( Origin gPackager )
					)
					( objectStatus "R9F32.1" )
				)
				( pin "b"
					( attribute "PN" "2"
						( Origin gPackager )
					)
					( objectStatus "R9F32.2" )
				)
			)
			( gate "@baseboard_fab2_lib.baseboard_fab2(sch_1):page239_i22"
				( attribute "BOM_COST" "P1V538_BMC_STBY_VR"
					( Origin gFrontEnd )
				)
				( attribute "CDS_LIB" "mstr_discrete"
					( Origin gPackager )
				)
				( attribute "CDS_LOCATION" "C1T7"
					( Origin gPackager )
				)
				( attribute "CDS_SEC" "1"
					( Origin gPackager )
				)
				( attribute "LOCATION" "C1T7"
					( Origin gFrontEnd )
				)
				( attribute "MATERIAL" "X6S"
					( Origin gFrontEnd )
				)
				( attribute "PACK_TYPE" "0603"
					( Origin gFrontEnd )
				)
				( attribute "PART_NUMBER" "E15431-002"
					( Origin gFrontEnd )
				)
				( attribute "PHYS_PAGE" "239"
					( Origin gFrontEnd )
				)
				( attribute "ROOM" "P1V538_BMC_STBY_VR"
					( Origin gFrontEnd )
				)
				( attribute "ROT" "0"
					( Origin gFrontEnd )
				)
				( attribute "SEC" "1"
					( Origin gFrontEnd )
				)
				( attribute "SEC_TYPE" "0603"
					( Origin gFrontEnd )
				)
				( attribute "TOLERANCE" "20%"
					( Origin gFrontEnd )
				)
				( attribute "VALUE" "10UF"
					( Origin gFrontEnd )
				)
				( attribute "VER" "1"
					( Origin gFrontEnd )
				)
				( attribute "VOLTAGE" "6.3V"
					( Units "uVoltage" "V" 1.000000)
					( Origin gFrontEnd )
				)
				( attribute "XY" "(6525,4150)"
					( Origin gFrontEnd )
				)
				( attribute "CHIPS_PART_NAME" "CAP"
					( Origin gPackager )
				)
				( attribute "CDS_PART_NAME" "CAP_0603-10UF,6.3V,20%,X6S,E15A"
					( Origin gPackager )
				)
				( objectStatus "C1T7" )
				( pin "a"
					( attribute "PN" "1"
						( Origin gPackager )
					)
					( objectStatus "C1T7.1" )
				)
				( pin "b"
					( attribute "PN" "2"
						( Origin gPackager )
					)
					( objectStatus "C1T7.2" )
				)
			)
			( gate "@baseboard_fab2_lib.baseboard_fab2(sch_1):page239_i30"
				( attribute "BOM_COST" "P1V538_BMC_STBY_VR"
					( Origin gFrontEnd )
				)
				( attribute "CDS_LIB" "mstr_discrete"
					( Origin gPackager )
				)
				( attribute "CDS_LOCATION" "C9F6"
					( Origin gPackager )
				)
				( attribute "CDS_SEC" "1"
					( Origin gPackager )
				)
				( attribute "LOCATION" "C9F6"
					( Origin gFrontEnd )
				)
				( attribute "MATERIAL" "EMPTY"
					( Origin gFrontEnd )
				)
				( attribute "PACK_TYPE" "0402LF"
					( Origin gFrontEnd )
				)
				( attribute "PART_NUMBER" "A36096-046"
					( Origin gFrontEnd )
				)
				( attribute "PHYS_PAGE" "239"
					( Origin gFrontEnd )
				)
				( attribute "ROOM" "P1V538_BMC_STBY_VR"
					( Origin gFrontEnd )
				)
				( attribute "ROT" "2"
					( Origin gFrontEnd )
				)
				( attribute "SEC" "1"
					( Origin gPackager )
				)
				( attribute "TOLERANCE" "10%"
					( Origin gFrontEnd )
				)
				( attribute "VALUE" "1000PF"
					( Origin gFrontEnd )
				)
				( attribute "VER" "1"
					( Origin gFrontEnd )
				)
				( attribute "VOLTAGE" "50V"
					( Units "uVoltage" "V" 1.000000)
					( Origin gFrontEnd )
				)
				( attribute "XY" "(7050,3300)"
					( Origin gFrontEnd )
				)
				( attribute "CHIPS_PART_NAME" "CAP"
					( Origin gPackager )
				)
				( attribute "CDS_PART_NAME" "CAP_0402LF-1000PF,50V,10%,EMPTA"
					( Origin gPackager )
				)
				( objectStatus "C9F6" )
				( pin "a"
					( attribute "PN" "1"
						( Origin gPackager )
					)
					( objectStatus "C9F6.1" )
				)
				( pin "b"
					( attribute "PN" "2"
						( Origin gPackager )
					)
					( objectStatus "C9F6.2" )
				)
			)
			( gate "@baseboard_fab2_lib.baseboard_fab2(sch_1):page239_i70"
				( attribute "CDS_LIB" "mstr_vreg"
					( Origin gPackager )
				)
				( attribute "CDS_LOCATION" "EU9F2"
					( Origin gPackager )
				)
				( attribute "CDS_SEC" "1"
					( Origin gPackager )
				)
				( attribute "LOCATION" "EU9F2"
					( Origin gFrontEnd )
				)
				( attribute "MATERIAL" "IC"
					( Origin gFrontEnd )
				)
				( attribute "PACK_TYPE" "DFN"
					( Origin gFrontEnd )
				)
				( attribute "PART_NUMBER" "H65765-001"
					( Origin gFrontEnd )
				)
				( attribute "PHYS_PAGE" "239"
					( Origin gFrontEnd )
				)
				( attribute "ROT" "0"
					( Origin gFrontEnd )
				)
				( attribute "SEC" "1"
					( Origin gFrontEnd )
				)
				( attribute "SEC_TYPE" "DFN"
					( Origin gFrontEnd )
				)
				( attribute "VER" "1"
					( Origin gFrontEnd )
				)
				( attribute "XY" "(8850,3775)"
					( Origin gFrontEnd )
				)
				( attribute "CHIPS_PART_NAME" "RT9059"
					( Origin gPackager )
				)
				( attribute "CDS_PART_NAME" "RT9059_DFN-IC,H65765-001"
					( Origin gPackager )
				)
				( objectStatus "EU9F2" )
				( pin "adj_nc"
					( attribute "PN" "4"
						( Origin gPackager )
					)
					( objectStatus "EU9F2.4" )
				)
				( pin "en"
					( attribute "PN" "6"
						( Origin gPackager )
					)
					( objectStatus "EU9F2.6" )
				)
				( pin "gnd"
					( attribute "PN" "11"
						( Origin gPackager )
					)
					( objectStatus "EU9F2.11" )
				)
				( pin "pgood"
					( attribute "PN" "5"
						( Origin gPackager )
					)
					( objectStatus "EU9F2.5" )
				)
				( pin "vdd"
					( attribute "PN" "10"
						( Origin gPackager )
					)
					( objectStatus "EU9F2.10" )
				)
				( pin "vin(0)"
					( attribute "PN" "7"
						( Origin gPackager )
					)
					( objectStatus "EU9F2.7" )
				)
				( pin "vin(1)"
					( attribute "PN" "8"
						( Origin gPackager )
					)
					( objectStatus "EU9F2.8" )
				)
				( pin "vin(2)"
					( attribute "PN" "9"
						( Origin gPackager )
					)
					( objectStatus "EU9F2.9" )
				)
				( pin "vout(0)"
					( attribute "PN" "1"
						( Origin gPackager )
					)
					( objectStatus "EU9F2.1" )
				)
				( pin "vout(1)"
					( attribute "PN" "2"
						( Origin gPackager )
					)
					( objectStatus "EU9F2.2" )
				)
				( pin "vout(2)"
					( attribute "PN" "3"
						( Origin gPackager )
					)
					( objectStatus "EU9F2.3" )
				)
			)
			( gate "@baseboard_fab2_lib.baseboard_fab2(sch_1):page239_i71"
				( attribute "CDS_LIB" "dev_discrete"
					( Origin gPackager )
				)
				( attribute "CDS_LOCATION" "C9F5"
					( Origin gPackager )
				)
				( attribute "CDS_SEC" "1"
					( Origin gPackager )
				)
				( attribute "LOCATION" "C9F5"
					( Origin gFrontEnd )
				)
				( attribute "MATERIAL" "X7R"
					( Origin gFrontEnd )
				)
				( attribute "PACK_TYPE" "0402V"
					( Origin gFrontEnd )
				)
				( attribute "PART_NUMBER" "A36096-030"
					( Origin gFrontEnd )
				)
				( attribute "PHYS_PAGE" "239"
					( Origin gFrontEnd )
				)
				( attribute "ROT" "0"
					( Origin gFrontEnd )
				)
				( attribute "SEC" "1"
					( Origin gFrontEnd )
				)
				( attribute "SEC_TYPE" "0402V"
					( Origin gFrontEnd )
				)
				( attribute "TOLERANCE" "10%"
					( Origin gFrontEnd )
				)
				( attribute "VALUE" "0.1UF"
					( Origin gFrontEnd )
				)
				( attribute "VER" "1"
					( Origin gFrontEnd )
				)
				( attribute "VOLTAGE" "16V"
					( Units "uVoltage" "V" 1.000000)
					( Origin gFrontEnd )
				)
				( attribute "XY" "(7475,4125)"
					( Origin gFrontEnd )
				)
				( attribute "CHIPS_PART_NAME" "CAP_A"
					( Origin gPackager )
				)
				( attribute "CDS_PART_NAME" "CAP_A_0402V-0.1UF,16V,10%,X7R,A"
					( Origin gPackager )
				)
				( objectStatus "C9F5" )
				( pin "a"
					( attribute "PN" "1"
						( Origin gPackager )
					)
					( objectStatus "C9F5.1" )
				)
				( pin "b"
					( attribute "PN" "2"
						( Origin gPackager )
					)
					( objectStatus "C9F5.2" )
				)
			)
			( gate "@baseboard_fab2_lib.baseboard_fab2(sch_1):page239_i72"
				( attribute "CDS_LIB" "mstr_discrete"
					( Origin gPackager )
				)
				( attribute "CDS_LOCATION" "R1T9"
					( Origin gPackager )
				)
				( attribute "CDS_SEC" "1"
					( Origin gPackager )
				)
				( attribute "LOCATION" "R1T9"
					( Origin gFrontEnd )
				)
				( attribute "MATERIAL" "CHIP"
					( Origin gFrontEnd )
				)
				( attribute "PACK_TYPE" "0402"
					( Origin gFrontEnd )
				)
				( attribute "PART_NUMBER" "G21796-250"
					( Origin gFrontEnd )
				)
				( attribute "PHYS_PAGE" "239"
					( Origin gFrontEnd )
				)
				( attribute "ROOM" "P1V538_BMC_STBY_VR"
					( Origin gFrontEnd )
				)
				( attribute "ROT" "0"
					( Origin gFrontEnd )
				)
				( attribute "SEC" "1"
					( Origin gFrontEnd )
				)
				( attribute "SEC_TYPE" "0402"
					( Origin gFrontEnd )
				)
				( attribute "TOLERANCE" "1.0%"
					( Origin gFrontEnd )
				)
				( attribute "VALUE" "22.1"
					( Origin gFrontEnd )
				)
				( attribute "VER" "1"
					( Origin gFrontEnd )
				)
				( attribute "WATTAGE" "1/16W"
					( Origin gFrontEnd )
				)
				( attribute "XY" "(10700,4275)"
					( Origin gFrontEnd )
				)
				( attribute "CHIPS_PART_NAME" "RES"
					( Origin gPackager )
				)
				( attribute "CDS_PART_NAME" "RES_0402-22.1,1.0%,1/16W,CHIP,A"
					( Origin gPackager )
				)
				( objectStatus "R1T9" )
				( pin "a"
					( attribute "PN" "1"
						( Origin gPackager )
					)
					( objectStatus "R1T9.1" )
				)
				( pin "b"
					( attribute "PN" "2"
						( Origin gPackager )
					)
					( objectStatus "R1T9.2" )
				)
			)
			( gate "@baseboard_fab2_lib.baseboard_fab2(sch_1):page240_i106"
				( attribute "BOM_COST" "P3V3_STBY_VR"
					( Origin gFrontEnd )
				)
				( attribute "CDS_LIB" "mstr_discrete"
					( Origin gPackager )
				)
				( attribute "CDS_LOCATION" "R8F9"
					( Origin gPackager )
				)
				( attribute "CDS_SEC" "1"
					( Origin gPackager )
				)
				( attribute "LOCATION" "R8F9"
					( Origin gFrontEnd )
				)
				( attribute "MATERIAL" "CHIP"
					( Origin gFrontEnd )
				)
				( attribute "PACK_TYPE" "0402"
					( Origin gFrontEnd )
				)
				( attribute "PART_NUMBER" "G21796-148"
					( Origin gFrontEnd )
				)
				( attribute "PHYS_PAGE" "240"
					( Origin gFrontEnd )
				)
				( attribute "ROOM" "P3V3_STBY_VR"
					( Origin gFrontEnd )
				)
				( attribute "ROT" "2"
					( Origin gFrontEnd )
				)
				( attribute "SEC" "1"
					( Origin gFrontEnd )
				)
				( attribute "SEC_TYPE" "0402"
					( Origin gFrontEnd )
				)
				( attribute "TOLERANCE" "1%"
					( Origin gFrontEnd )
				)
				( attribute "VALUE" "64.9K"
					( Origin gFrontEnd )
				)
				( attribute "VER" "2"
					( Origin gFrontEnd )
				)
				( attribute "WATTAGE" "1/16W"
					( Origin gFrontEnd )
				)
				( attribute "XY" "(6425,1850)"
					( Origin gFrontEnd )
				)
				( attribute "CHIPS_PART_NAME" "RES"
					( Origin gPackager )
				)
				( attribute "CDS_PART_NAME" "RES_0402-64.9K,1%,1/16W,CHIP,GA"
					( Origin gPackager )
				)
				( objectStatus "R8F9" )
				( pin "a"
					( attribute "PN" "1"
						( Origin gPackager )
					)
					( objectStatus "R8F9.1" )
				)
				( pin "b"
					( attribute "PN" "2"
						( Origin gPackager )
					)
					( objectStatus "R8F9.2" )
				)
			)
			( gate "@baseboard_fab2_lib.baseboard_fab2(sch_1):page240_i109"
				( attribute "BOM_COST" "P3V3_STBY_VR"
					( Origin gFrontEnd )
				)
				( attribute "CDS_LIB" "mstr_discrete"
					( Origin gPackager )
				)
				( attribute "CDS_LOCATION" "C2R11"
					( Origin gPackager )
				)
				( attribute "CDS_SEC" "1"
					( Origin gPackager )
				)
				( attribute "LOCATION" "C2R11"
					( Origin gFrontEnd )
				)
				( attribute "MATERIAL" "X6S"
					( Origin gFrontEnd )
				)
				( attribute "PACK_TYPE" "0603"
					( Origin gFrontEnd )
				)
				( attribute "PART_NUMBER" "E15431-003"
					( Origin gFrontEnd )
				)
				( attribute "PHYS_PAGE" "240"
					( Origin gFrontEnd )
				)
				( attribute "REUSE_ID" "20"
					( Origin gFrontEnd )
				)
				( attribute "ROOM" "P3V3_STBY_VR"
					( Origin gFrontEnd )
				)
				( attribute "ROT" "2"
					( Origin gFrontEnd )
				)
				( attribute "SEC" "1"
					( Origin gFrontEnd )
				)
				( attribute "SEC_TYPE" "0603"
					( Origin gFrontEnd )
				)
				( attribute "TOLERANCE" "10%"
					( Origin gFrontEnd )
				)
				( attribute "VALUE" "4.7UF"
					( Origin gFrontEnd )
				)
				( attribute "VER" "1"
					( Origin gFrontEnd )
				)
				( attribute "VOLTAGE" "6.3V"
					( Units "uVoltage" "V" 1.000000)
					( Origin gFrontEnd )
				)
				( attribute "XY" "(5600,3300)"
					( Origin gFrontEnd )
				)
				( attribute "CHIPS_PART_NAME" "CAP"
					( Origin gPackager )
				)
				( attribute "CDS_PART_NAME" "CAP_0603-4.7UF,6.3V,10%,X6S,E1A"
					( Origin gPackager )
				)
				( objectStatus "C2R11" )
				( pin "a"
					( attribute "PN" "1"
						( Origin gPackager )
					)
					( objectStatus "C2R11.1" )
				)
				( pin "b"
					( attribute "PN" "2"
						( Origin gPackager )
					)
					( objectStatus "C2R11.2" )
				)
			)
			( gate "@baseboard_fab2_lib.baseboard_fab2(sch_1):page240_i111"
				( attribute "BOM" "SYSB_CPLD"
					( Origin gFrontEnd )
				)
				( attribute "BOM_COST" "P3V3_STBY_VR"
					( Origin gFrontEnd )
				)
				( attribute "CDS_LIB" "mstr_discrete"
					( Origin gPackager )
				)
				( attribute "CDS_LOCATION" "R8F1"
					( Origin gPackager )
				)
				( attribute "CDS_SEC" "1"
					( Origin gPackager )
				)
				( attribute "LOCATION" "R8F1"
					( Origin gFrontEnd )
				)
				( attribute "MATERIAL" "EMPTY"
					( Origin gFrontEnd )
				)
				( attribute "PACK_TYPE" "0402"
					( Origin gFrontEnd )
				)
				( attribute "PART_NUMBER" "G21796-016"
					( Origin gFrontEnd )
				)
				( attribute "PHYS_PAGE" "240"
					( Origin gFrontEnd )
				)
				( attribute "ROOM" "P3V3_STBY_VR"
					( Origin gFrontEnd )
				)
				( attribute "ROT" "0"
					( Origin gFrontEnd )
				)
				( attribute "SEC" "1"
					( Origin gPackager )
				)
				( attribute "TOLERANCE" "1%"
					( Origin gFrontEnd )
				)
				( attribute "VALUE" "10.0K"
					( Origin gFrontEnd )
				)
				( attribute "VER" "2"
					( Origin gFrontEnd )
				)
				( attribute "WATTAGE" "1/16W"
					( Origin gFrontEnd )
				)
				( attribute "XY" "(5625,2400)"
					( Origin gFrontEnd )
				)
				( attribute "CHIPS_PART_NAME" "RES"
					( Origin gPackager )
				)
				( attribute "CDS_PART_NAME" "RES_0402-10.0K,1%,1/16W,EMPTY,A"
					( Origin gPackager )
				)
				( objectStatus "R8F1" )
				( pin "a"
					( attribute "PN" "1"
						( Origin gPackager )
					)
					( objectStatus "R8F1.1" )
				)
				( pin "b"
					( attribute "PN" "2"
						( Origin gPackager )
					)
					( objectStatus "R8F1.2" )
				)
			)
			( gate "@baseboard_fab2_lib.baseboard_fab2(sch_1):page240_i113"
				( attribute "BOM_COST" "P3V3_STBY_VR"
					( Origin gFrontEnd )
				)
				( attribute "CDS_LIB" "mstr_discrete"
					( Origin gPackager )
				)
				( attribute "CDS_LOCATION" "C8E17"
					( Origin gPackager )
				)
				( attribute "CDS_SEC" "1"
					( Origin gPackager )
				)
				( attribute "FIN" "VR_1P2"
					( Origin gFrontEnd )
				)
				( attribute "LOCATION" "C8E17"
					( Origin gFrontEnd )
				)
				( attribute "MATERIAL" "EMPTY"
					( Origin gFrontEnd )
				)
				( attribute "PACK_TYPE" "0402LF"
					( Origin gFrontEnd )
				)
				( attribute "PART_NUMBER" "A36096-046"
					( Origin gFrontEnd )
				)
				( attribute "PHYS_PAGE" "240"
					( Origin gFrontEnd )
				)
				( attribute "REUSE_ID" "1"
					( Origin gFrontEnd )
				)
				( attribute "ROOM" "P3V3_STBY_VR"
					( Origin gFrontEnd )
				)
				( attribute "ROT" "2"
					( Origin gFrontEnd )
				)
				( attribute "SEC" "1"
					( Origin gPackager )
				)
				( attribute "TOLERANCE" "10%"
					( Origin gFrontEnd )
				)
				( attribute "VALUE" "1000PF"
					( Origin gFrontEnd )
				)
				( attribute "VER" "1"
					( Origin gFrontEnd )
				)
				( attribute "VOLTAGE" "50V"
					( Units "uVoltage" "V" 1.000000)
					( Origin gFrontEnd )
				)
				( attribute "XY" "(6175,2475)"
					( Origin gFrontEnd )
				)
				( attribute "CHIPS_PART_NAME" "CAP"
					( Origin gPackager )
				)
				( attribute "CDS_PART_NAME" "CAP_0402LF-1000PF,50V,10%,EMPTA"
					( Origin gPackager )
				)
				( objectStatus "C8E17" )
				( pin "a"
					( attribute "PN" "1"
						( Origin gPackager )
					)
					( objectStatus "C8E17.1" )
				)
				( pin "b"
					( attribute "PN" "2"
						( Origin gPackager )
					)
					( objectStatus "C8E17.2" )
				)
			)
			( gate "@baseboard_fab2_lib.baseboard_fab2(sch_1):page240_i116"
				( attribute "BOM_COST" "P3V3_STBY_VR"
					( Origin gFrontEnd )
				)
				( attribute "CDS_LIB" "mstr_discrete"
					( Origin gPackager )
				)
				( attribute "CDS_LOCATION" "C8F2"
					( Origin gPackager )
				)
				( attribute "CDS_SEC" "1"
					( Origin gPackager )
				)
				( attribute "LOCATION" "C8F2"
					( Origin gFrontEnd )
				)
				( attribute "MATERIAL" "X7R"
					( Origin gFrontEnd )
				)
				( attribute "PACK_TYPE" "0402LF"
					( Origin gFrontEnd )
				)
				( attribute "PART_NUMBER" "A36096-046"
					( Origin gFrontEnd )
				)
				( attribute "PHYS_PAGE" "240"
					( Origin gFrontEnd )
				)
				( attribute "REUSE_ID" "17"
					( Origin gFrontEnd )
				)
				( attribute "ROOM" "P3V3_STBY_VR"
					( Origin gFrontEnd )
				)
				( attribute "ROT" "0"
					( Origin gFrontEnd )
				)
				( attribute "SEC" "1"
					( Origin gPackager )
				)
				( attribute "TOLERANCE" "10%"
					( Origin gFrontEnd )
				)
				( attribute "VALUE" "1000PF"
					( Origin gFrontEnd )
				)
				( attribute "VER" "1"
					( Origin gFrontEnd )
				)
				( attribute "VOLTAGE" "50V"
					( Units "uVoltage" "V" 1.000000)
					( Origin gFrontEnd )
				)
				( attribute "XY" "(6350,3350)"
					( Origin gFrontEnd )
				)
				( attribute "CHIPS_PART_NAME" "CAP"
					( Origin gPackager )
				)
				( attribute "CDS_PART_NAME" "CAP_0402LF-1000PF,50V,10%,X7R,A"
					( Origin gPackager )
				)
				( objectStatus "C8F2" )
				( pin "a"
					( attribute "PN" "1"
						( Origin gPackager )
					)
					( objectStatus "C8F2.1" )
				)
				( pin "b"
					( attribute "PN" "2"
						( Origin gPackager )
					)
					( objectStatus "C8F2.2" )
				)
			)
			( gate "@baseboard_fab2_lib.baseboard_fab2(sch_1):page240_i117"
				( attribute "BOM_COST" "P3V3_STBY_VR"
					( Origin gFrontEnd )
				)
				( attribute "CDS_LIB" "mstr_discrete"
					( Origin gPackager )
				)
				( attribute "CDS_LOCATION" "R8F5"
					( Origin gPackager )
				)
				( attribute "CDS_SEC" "1"
					( Origin gPackager )
				)
				( attribute "LOCATION" "R8F5"
					( Origin gFrontEnd )
				)
				( attribute "MATERIAL" "CHIP"
					( Origin gFrontEnd )
				)
				( attribute "PACK_TYPE" "0402"
					( Origin gFrontEnd )
				)
				( attribute "PART_NUMBER" "G21796-026"
					( Origin gFrontEnd )
				)
				( attribute "PHYS_PAGE" "240"
					( Origin gFrontEnd )
				)
				( attribute "REUSE_ID" "21"
					( Origin gFrontEnd )
				)
				( attribute "ROOM" "PVPP_KLM_VR"
					( Origin gFrontEnd )
				)
				( attribute "ROT" "2"
					( Origin gFrontEnd )
				)
				( attribute "SEC" "1"
					( Origin gFrontEnd )
				)
				( attribute "SEC_TYPE" "0402"
					( Origin gFrontEnd )
				)
				( attribute "TOLERANCE" "1%"
					( Origin gFrontEnd )
				)
				( attribute "VALUE" "1.00K"
					( Origin gFrontEnd )
				)
				( attribute "VER" "2"
					( Origin gFrontEnd )
				)
				( attribute "WATTAGE" "1/16W"
					( Origin gFrontEnd )
				)
				( attribute "XY" "(6275,3900)"
					( Origin gFrontEnd )
				)
				( attribute "CHIPS_PART_NAME" "RES"
					( Origin gPackager )
				)
				( attribute "CDS_PART_NAME" "RES_0402-1.00K,1%,1/16W,CHIP,GA"
					( Origin gPackager )
				)
				( objectStatus "R8F5" )
				( pin "a"
					( attribute "PN" "1"
						( Origin gPackager )
					)
					( objectStatus "R8F5.1" )
				)
				( pin "b"
					( attribute "PN" "2"
						( Origin gPackager )
					)
					( objectStatus "R8F5.2" )
				)
			)
			( gate "@baseboard_fab2_lib.baseboard_fab2(sch_1):page240_i125"
				( attribute "CDS_LIB" "mstr_vreg"
					( Origin gPackager )
				)
				( attribute "CDS_LOCATION" "EU8F1"
					( Origin gPackager )
				)
				( attribute "CDS_SEC" "1"
					( Origin gPackager )
				)
				( attribute "LOCATION" "EU8F1"
					( Origin gFrontEnd )
				)
				( attribute "MATERIAL" "IC"
					( Origin gFrontEnd )
				)
				( attribute "PACK_TYPE" "QFN"
					( Origin gFrontEnd )
				)
				( attribute "PART_NUMBER" "H66262-001"
					( Origin gFrontEnd )
				)
				( attribute "PHYS_PAGE" "240"
					( Origin gFrontEnd )
				)
				( attribute "ROOM" "P3V3_STBY_VR"
					( Origin gFrontEnd )
				)
				( attribute "ROT" "0"
					( Origin gFrontEnd )
				)
				( attribute "SEC" "1"
					( Origin gFrontEnd )
				)
				( attribute "SEC_TYPE" "QFN"
					( Origin gFrontEnd )
				)
				( attribute "VER" "1"
					( Origin gFrontEnd )
				)
				( attribute "XY" "(7550,2625)"
					( Origin gFrontEnd )
				)
				( attribute "CHIPS_PART_NAME" "RT8240"
					( Origin gPackager )
				)
				( attribute "CDS_PART_NAME" "RT8240_QFN-IC,H66262-001"
					( Origin gPackager )
				)
				( objectStatus "EU8F1" )
				( pin "boot"
					( attribute "PN" "4"
						( Origin gPackager )
					)
					( objectStatus "EU8F1.4" )
				)
				( pin "cs"
					( attribute "PN" "10"
						( Origin gPackager )
					)
					( objectStatus "EU8F1.10" )
				)
				( pin "en"
					( attribute "PN" "8"
						( Origin gPackager )
					)
					( objectStatus "EU8F1.8" )
				)
				( pin "g0"
					( attribute "PN" "11"
						( Origin gPackager )
					)
					( objectStatus "EU8F1.11" )
				)
				( pin "gnd(0)"
					( attribute "PN" "12"
						( Origin gPackager )
					)
					( objectStatus "EU8F1.12" )
				)
				( pin "gnd(1)"
					( attribute "PN" "13"
						( Origin gPackager )
					)
					( objectStatus "EU8F1.13" )
				)
				( pin "lgate"
					( attribute "PN" "1"
						( Origin gPackager )
					)
					( objectStatus "EU8F1.1" )
				)
				( pin "pgood"
					( attribute "PN" "9"
						( Origin gPackager )
					)
					( objectStatus "EU8F1.9" )
				)
				( pin "phase"
					( attribute "PN" "2"
						( Origin gPackager )
					)
					( objectStatus "EU8F1.2" )
				)
				( pin "rgnd"
					( attribute "PN" "7"
						( Origin gPackager )
					)
					( objectStatus "EU8F1.7" )
				)
				( pin "ugate"
					( attribute "PN" "3"
						( Origin gPackager )
					)
					( objectStatus "EU8F1.3" )
				)
				( pin "vcc"
					( attribute "PN" "5"
						( Origin gPackager )
					)
					( objectStatus "EU8F1.5" )
				)
				( pin "vout"
					( attribute "PN" "6"
						( Origin gPackager )
					)
					( objectStatus "EU8F1.6" )
				)
			)
			( gate "@baseboard_fab2_lib.baseboard_fab2(sch_1):page240_i127"
				( attribute "BOM_COST" "P3V3_STBY_VR"
					( Origin gFrontEnd )
				)
				( attribute "CDS_LIB" "mstr_discrete"
					( Origin gPackager )
				)
				( attribute "CDS_LOCATION" "R8E35"
					( Origin gPackager )
				)
				( attribute "CDS_SEC" "1"
					( Origin gPackager )
				)
				( attribute "LOCATION" "R8E35"
					( Origin gFrontEnd )
				)
				( attribute "MATERIAL" "CHIP"
					( Origin gFrontEnd )
				)
				( attribute "PACK_TYPE" "0402"
					( Origin gFrontEnd )
				)
				( attribute "PART_NUMBER" "G21497-005"
					( Origin gFrontEnd )
				)
				( attribute "PHYS_PAGE" "240"
					( Origin gFrontEnd )
				)
				( attribute "REUSE_ID" "13"
					( Origin gFrontEnd )
				)
				( attribute "ROOM" "P3V3_STBY_VR"
					( Origin gFrontEnd )
				)
				( attribute "ROT" "0"
					( Origin gFrontEnd )
				)
				( attribute "SEC" "1"
					( Origin gPackager )
				)
				( attribute "SPOF" "TRUE"
					( Origin gFrontEnd )
				)
				( attribute "TOLERANCE" "5%"
					( Origin gFrontEnd )
				)
				( attribute "VALUE" "0.0"
					( Origin gFrontEnd )
				)
				( attribute "VER" "1"
					( Origin gFrontEnd )
				)
				( attribute "WATTAGE" "1/16W"
					( Origin gFrontEnd )
				)
				( attribute "XY" "(7600,3425)"
					( Origin gFrontEnd )
				)
				( attribute "CHIPS_PART_NAME" "RES"
					( Origin gPackager )
				)
				( attribute "CDS_PART_NAME" "RES_0402-0.0,5%,1/16W,CHIP,G21A"
					( Origin gPackager )
				)
				( objectStatus "R8E35" )
				( pin "a"
					( attribute "PN" "1"
						( Origin gPackager )
					)
					( objectStatus "R8E35.1" )
				)
				( pin "b"
					( attribute "PN" "2"
						( Origin gPackager )
					)
					( objectStatus "R8E35.2" )
				)
			)
			( gate "@baseboard_fab2_lib.baseboard_fab2(sch_1):page240_i129"
				( attribute "BOM_COST" "P3V3_STBY_VR"
					( Origin gFrontEnd )
				)
				( attribute "CDS_LIB" "mstr_discrete"
					( Origin gPackager )
				)
				( attribute "CDS_LOCATION" "C8E12"
					( Origin gPackager )
				)
				( attribute "CDS_SEC" "1"
					( Origin gPackager )
				)
				( attribute "LOCATION" "C8E12"
					( Origin gFrontEnd )
				)
				( attribute "MATERIAL" "X7R"
					( Origin gFrontEnd )
				)
				( attribute "PACK_TYPE" "0603LF"
					( Origin gFrontEnd )
				)
				( attribute "PART_NUMBER" "602433-020"
					( Origin gFrontEnd )
				)
				( attribute "PHYS_PAGE" "240"
					( Origin gFrontEnd )
				)
				( attribute "REUSE_ID" "27"
					( Origin gFrontEnd )
				)
				( attribute "ROOM" "P3V3_STBY_VR"
					( Origin gFrontEnd )
				)
				( attribute "ROT" "2"
					( Origin gFrontEnd )
				)
				( attribute "SEC" "1"
					( Origin gPackager )
				)
				( attribute "SPOF" "TRUE"
					( Origin gFrontEnd )
				)
				( attribute "TOLERANCE" "10%"
					( Origin gFrontEnd )
				)
				( attribute "VALUE" "0.1UF"
					( Origin gFrontEnd )
				)
				( attribute "VER" "2"
					( Origin gFrontEnd )
				)
				( attribute "VOLTAGE" "25V"
					( Units "uVoltage" "V" 1.000000)
					( Origin gFrontEnd )
				)
				( attribute "XY" "(8300,3425)"
					( Origin gFrontEnd )
				)
				( attribute "CHIPS_PART_NAME" "CAP"
					( Origin gPackager )
				)
				( attribute "CDS_PART_NAME" "CAP_0603LF-0.1UF,25V,10%,X7R,6A"
					( Origin gPackager )
				)
				( objectStatus "C8E12" )
				( pin "a"
					( attribute "PN" "1"
						( Origin gPackager )
					)
					( objectStatus "C8E12.1" )
				)
				( pin "b"
					( attribute "PN" "2"
						( Origin gPackager )
					)
					( objectStatus "C8E12.2" )
				)
			)
			( gate "@baseboard_fab2_lib.baseboard_fab2(sch_1):page240_i132"
				( attribute "CDS_LIB" "mstr_discrete"
					( Origin gPackager )
				)
				( attribute "CDS_LOCATION" "FB9E1"
					( Origin gPackager )
				)
				( attribute "CDS_SEC" "1"
					( Origin gPackager )
				)
				( attribute "LOCATION" "FB9E1"
					( Origin gFrontEnd )
				)
				( attribute "MATERIAL" "FB"
					( Origin gFrontEnd )
				)
				( attribute "PACK_TYPE" "SM"
					( Origin gFrontEnd )
				)
				( attribute "PART_NUMBER" "656554-051"
					( Origin gFrontEnd )
				)
				( attribute "PHYS_PAGE" "240"
					( Origin gFrontEnd )
				)
				( attribute "ROOM" "P3V3_STBY_VR"
					( Origin gFrontEnd )
				)
				( attribute "ROT" "0"
					( Origin gFrontEnd )
				)
				( attribute "SEC" "1"
					( Origin gFrontEnd )
				)
				( attribute "SEC_TYPE" "SM"
					( Origin gFrontEnd )
				)
				( attribute "TOLERANCE" "1%"
					( Origin gFrontEnd )
				)
				( attribute "VALUE" "22"
					( Origin gFrontEnd )
				)
				( attribute "VER" "1"
					( Origin gFrontEnd )
				)
				( attribute "XY" "(6900,4500)"
					( Origin gFrontEnd )
				)
				( attribute "CHIPS_PART_NAME" "FERRITE"
					( Origin gPackager )
				)
				( attribute "CDS_PART_NAME" "FERRITE_SM-22,FB,656554-051"
					( Origin gPackager )
				)
				( objectStatus "FB9E1" )
				( pin "a"
					( attribute "PN" "1"
						( Origin gPackager )
					)
					( objectStatus "FB9E1.1" )
				)
				( pin "b"
					( attribute "PN" "2"
						( Origin gPackager )
					)
					( objectStatus "FB9E1.2" )
				)
			)
			( gate "@baseboard_fab2_lib.baseboard_fab2(sch_1):page240_i134"
				( attribute "BOM_COST" "P3V3_STBY_VR"
					( Origin gFrontEnd )
				)
				( attribute "CDS_LIB" "mstr_discrete"
					( Origin gPackager )
				)
				( attribute "CDS_LOCATION" "C9F1"
					( Origin gPackager )
				)
				( attribute "CDS_SEC" "1"
					( Origin gPackager )
				)
				( attribute "LOCATION" "C9F1"
					( Origin gFrontEnd )
				)
				( attribute "MATERIAL" "X6S"
					( Origin gFrontEnd )
				)
				( attribute "PACK_TYPE" "1210"
					( Origin gFrontEnd )
				)
				( attribute "PART_NUMBER" "D38464-007"
					( Origin gFrontEnd )
				)
				( attribute "PHYS_PAGE" "240"
					( Origin gFrontEnd )
				)
				( attribute "ROOM" "P3V3_STBY_VR"
					( Origin gFrontEnd )
				)
				( attribute "ROT" "0"
					( Origin gFrontEnd )
				)
				( attribute "SEC" "1"
					( Origin gPackager )
				)
				( attribute "TOLERANCE" "20%"
					( Origin gFrontEnd )
				)
				( attribute "VALUE" "47UF"
					( Origin gFrontEnd )
				)
				( attribute "VER" "1"
					( Origin gFrontEnd )
				)
				( attribute "VOLTAGE" "16V"
					( Units "uVoltage" "V" 1.000000)
					( Origin gFrontEnd )
				)
				( attribute "XY" "(7125,4325)"
					( Origin gFrontEnd )
				)
				( attribute "CHIPS_PART_NAME" "CAP"
					( Origin gPackager )
				)
				( attribute "CDS_PART_NAME" "CAP_1210-47UF,16V,20%,X6S,D384A"
					( Origin gPackager )
				)
				( objectStatus "C9F1" )
				( pin "a"
					( attribute "PN" "1"
						( Origin gPackager )
					)
					( objectStatus "C9F1.1" )
				)
				( pin "b"
					( attribute "PN" "2"
						( Origin gPackager )
					)
					( objectStatus "C9F1.2" )
				)
			)
			( gate "@baseboard_fab2_lib.baseboard_fab2(sch_1):page240_i135"
				( attribute "BOM_COST" "P3V3_STBY_VR"
					( Origin gFrontEnd )
				)
				( attribute "CDS_LIB" "mstr_discrete"
					( Origin gPackager )
				)
				( attribute "CDS_LOCATION" "C8E11"
					( Origin gPackager )
				)
				( attribute "CDS_SEC" "1"
					( Origin gPackager )
				)
				( attribute "LOCATION" "C8E11"
					( Origin gFrontEnd )
				)
				( attribute "MATERIAL" "X6S"
					( Origin gFrontEnd )
				)
				( attribute "PACK_TYPE" "1210"
					( Origin gFrontEnd )
				)
				( attribute "PART_NUMBER" "D38464-007"
					( Origin gFrontEnd )
				)
				( attribute "PHYS_PAGE" "240"
					( Origin gFrontEnd )
				)
				( attribute "ROOM" "P3V3_STBY_VR"
					( Origin gFrontEnd )
				)
				( attribute "ROT" "0"
					( Origin gFrontEnd )
				)
				( attribute "SEC" "1"
					( Origin gPackager )
				)
				( attribute "TOLERANCE" "20%"
					( Origin gFrontEnd )
				)
				( attribute "VALUE" "47UF"
					( Origin gFrontEnd )
				)
				( attribute "VER" "1"
					( Origin gFrontEnd )
				)
				( attribute "VOLTAGE" "16V"
					( Units "uVoltage" "V" 1.000000)
					( Origin gFrontEnd )
				)
				( attribute "XY" "(7475,4325)"
					( Origin gFrontEnd )
				)
				( attribute "CHIPS_PART_NAME" "CAP"
					( Origin gPackager )
				)
				( attribute "CDS_PART_NAME" "CAP_1210-47UF,16V,20%,X6S,D384A"
					( Origin gPackager )
				)
				( objectStatus "C8E11" )
				( pin "a"
					( attribute "PN" "1"
						( Origin gPackager )
					)
					( objectStatus "C8E11.1" )
				)
				( pin "b"
					( attribute "PN" "2"
						( Origin gPackager )
					)
					( objectStatus "C8E11.2" )
				)
			)
			( gate "@baseboard_fab2_lib.baseboard_fab2(sch_1):page240_i137"
				( attribute "BOM_COST" "P3V3_STBY_VR"
					( Origin gFrontEnd )
				)
				( attribute "CDS_LIB" "mstr_discrete"
					( Origin gPackager )
				)
				( attribute "CDS_LOCATION" "C8E10"
					( Origin gPackager )
				)
				( attribute "CDS_SEC" "1"
					( Origin gPackager )
				)
				( attribute "LOCATION" "C8E10"
					( Origin gFrontEnd )
				)
				( attribute "MATERIAL" "X6S"
					( Origin gFrontEnd )
				)
				( attribute "PACK_TYPE" "1206LF"
					( Origin gFrontEnd )
				)
				( attribute "PART_NUMBER" "D38464-005"
					( Origin gFrontEnd )
				)
				( attribute "PHYS_PAGE" "240"
					( Origin gFrontEnd )
				)
				( attribute "ROOM" "P3V3_STBY_VR"
					( Origin gFrontEnd )
				)
				( attribute "ROT" "0"
					( Origin gFrontEnd )
				)
				( attribute "SEC" "1"
					( Origin gPackager )
				)
				( attribute "TOLERANCE" "10%"
					( Origin gFrontEnd )
				)
				( attribute "VALUE" "22UF"
					( Origin gFrontEnd )
				)
				( attribute "VER" "1"
					( Origin gFrontEnd )
				)
				( attribute "VOLTAGE" "16V"
					( Units "uVoltage" "V" 1.000000)
					( Origin gFrontEnd )
				)
				( attribute "XY" "(7825,4325)"
					( Origin gFrontEnd )
				)
				( attribute "CHIPS_PART_NAME" "CAP"
					( Origin gPackager )
				)
				( attribute "CDS_PART_NAME" "CAP_1206LF-22UF,16V,10%,X6S,D3A"
					( Origin gPackager )
				)
				( objectStatus "C8E10" )
				( pin "a"
					( attribute "PN" "1"
						( Origin gPackager )
					)
					( objectStatus "C8E10.1" )
				)
				( pin "b"
					( attribute "PN" "2"
						( Origin gPackager )
					)
					( objectStatus "C8E10.2" )
				)
			)
			( gate "@baseboard_fab2_lib.baseboard_fab2(sch_1):page240_i139"
				( attribute "BOM_COST" "P3V3_STBY_VR"
					( Origin gFrontEnd )
				)
				( attribute "CDS_LIB" "mstr_discrete"
					( Origin gPackager )
				)
				( attribute "CDS_LOCATION" "C8E14"
					( Origin gPackager )
				)
				( attribute "CDS_SEC" "1"
					( Origin gPackager )
				)
				( attribute "FIN" "VR_1P2"
					( Origin gFrontEnd )
				)
				( attribute "LOCATION" "C8E14"
					( Origin gFrontEnd )
				)
				( attribute "MATERIAL" "X6S"
					( Origin gFrontEnd )
				)
				( attribute "PACK_TYPE" "0402"
					( Origin gFrontEnd )
				)
				( attribute "PART_NUMBER" "D97712-011"
					( Origin gFrontEnd )
				)
				( attribute "PHYS_PAGE" "240"
					( Origin gFrontEnd )
				)
				( attribute "REUSE_ID" "1"
					( Origin gFrontEnd )
				)
				( attribute "ROOM" "P3V3_STBY_VR"
					( Origin gFrontEnd )
				)
				( attribute "ROT" "0"
					( Origin gFrontEnd )
				)
				( attribute "SEC" "1"
					( Origin gPackager )
				)
				( attribute "TOLERANCE" "10%"
					( Origin gFrontEnd )
				)
				( attribute "VALUE" "1.0UF"
					( Origin gFrontEnd )
				)
				( attribute "VER" "1"
					( Origin gFrontEnd )
				)
				( attribute "VOLTAGE" "16V"
					( Units "uVoltage" "V" 1.000000)
					( Origin gFrontEnd )
				)
				( attribute "XY" "(8150,4350)"
					( Origin gFrontEnd )
				)
				( attribute "CHIPS_PART_NAME" "CAP"
					( Origin gPackager )
				)
				( attribute "CDS_PART_NAME" "CAP_0402-1.0UF,16V,10%,X6S,D97A"
					( Origin gPackager )
				)
				( objectStatus "C8E14" )
				( pin "a"
					( attribute "PN" "1"
						( Origin gPackager )
					)
					( objectStatus "C8E14.1" )
				)
				( pin "b"
					( attribute "PN" "2"
						( Origin gPackager )
					)
					( objectStatus "C8E14.2" )
				)
			)
			( gate "@baseboard_fab2_lib.baseboard_fab2(sch_1):page240_i140"
				( attribute "BOM_COST" "P3V3_STBY_VR"
					( Origin gFrontEnd )
				)
				( attribute "CDS_LIB" "mstr_discrete"
					( Origin gPackager )
				)
				( attribute "CDS_LOCATION" "R8E38"
					( Origin gPackager )
				)
				( attribute "CDS_SEC" "1"
					( Origin gPackager )
				)
				( attribute "LOCATION" "R8E38"
					( Origin gFrontEnd )
				)
				( attribute "MATERIAL" "CHIP"
					( Origin gFrontEnd )
				)
				( attribute "PACK_TYPE" "0402"
					( Origin gFrontEnd )
				)
				( attribute "PART_NUMBER" "G21497-005"
					( Origin gFrontEnd )
				)
				( attribute "PHYS_PAGE" "240"
					( Origin gFrontEnd )
				)
				( attribute "ROOM" "P3V3_STBY_VR"
					( Origin gFrontEnd )
				)
				( attribute "ROT" "0"
					( Origin gFrontEnd )
				)
				( attribute "SEC" "1"
					( Origin gPackager )
				)
				( attribute "TOLERANCE" "5%"
					( Origin gFrontEnd )
				)
				( attribute "VALUE" "0.0"
					( Origin gFrontEnd )
				)
				( attribute "VER" "1"
					( Origin gFrontEnd )
				)
				( attribute "WATTAGE" "1/16W"
					( Origin gFrontEnd )
				)
				( attribute "XY" "(9225,925)"
					( Origin gFrontEnd )
				)
				( attribute "CHIPS_PART_NAME" "RES"
					( Origin gPackager )
				)
				( attribute "CDS_PART_NAME" "RES_0402-0.0,5%,1/16W,CHIP,G21A"
					( Origin gPackager )
				)
				( objectStatus "R8E38" )
				( pin "a"
					( attribute "PN" "1"
						( Origin gPackager )
					)
					( objectStatus "R8E38.1" )
				)
				( pin "b"
					( attribute "PN" "2"
						( Origin gPackager )
					)
					( objectStatus "R8E38.2" )
				)
			)
			( gate "@baseboard_fab2_lib.baseboard_fab2(sch_1):page240_i142"
				( attribute "BOM_COST" "P3V3_STBY_VR"
					( Origin gFrontEnd )
				)
				( attribute "CDS_LIB" "mstr_discrete"
					( Origin gPackager )
				)
				( attribute "CDS_LOCATION" "R8E34"
					( Origin gPackager )
				)
				( attribute "CDS_SEC" "1"
					( Origin gPackager )
				)
				( attribute "LOCATION" "R8E34"
					( Origin gFrontEnd )
				)
				( attribute "MATERIAL" "CHIP"
					( Origin gFrontEnd )
				)
				( attribute "PACK_TYPE" "0402"
					( Origin gFrontEnd )
				)
				( attribute "PART_NUMBER" "G21796-016"
					( Origin gFrontEnd )
				)
				( attribute "PHYS_PAGE" "240"
					( Origin gFrontEnd )
				)
				( attribute "REUSE_ID" "7"
					( Origin gFrontEnd )
				)
				( attribute "ROOM" "P3V3_STBY_VR"
					( Origin gFrontEnd )
				)
				( attribute "ROT" "0"
					( Origin gFrontEnd )
				)
				( attribute "SEC" "1"
					( Origin gPackager )
				)
				( attribute "SPOF" "TRUE"
					( Origin gFrontEnd )
				)
				( attribute "TOLERANCE" "1%"
					( Origin gFrontEnd )
				)
				( attribute "VALUE" "10.0K"
					( Origin gFrontEnd )
				)
				( attribute "VER" "2"
					( Origin gFrontEnd )
				)
				( attribute "WATTAGE" "1/16W"
					( Origin gFrontEnd )
				)
				( attribute "XY" "(9475,1100)"
					( Origin gFrontEnd )
				)
				( attribute "CHIPS_PART_NAME" "RES"
					( Origin gPackager )
				)
				( attribute "CDS_PART_NAME" "RES_0402-10.0K,1%,1/16W,CHIP,GA"
					( Origin gPackager )
				)
				( objectStatus "R8E34" )
				( pin "a"
					( attribute "PN" "1"
						( Origin gPackager )
					)
					( objectStatus "R8E34.1" )
				)
				( pin "b"
					( attribute "PN" "2"
						( Origin gPackager )
					)
					( objectStatus "R8E34.2" )
				)
			)
			( gate "@baseboard_fab2_lib.baseboard_fab2(sch_1):page240_i143"
				( attribute "BOM_COST" "P3V3_STBY_VR"
					( Origin gFrontEnd )
				)
				( attribute "CDS_LIB" "mstr_discrete"
					( Origin gPackager )
				)
				( attribute "CDS_LOCATION" "R8E31"
					( Origin gPackager )
				)
				( attribute "CDS_SEC" "1"
					( Origin gPackager )
				)
				( attribute "LOCATION" "R8E31"
					( Origin gFrontEnd )
				)
				( attribute "MATERIAL" "CHIP"
					( Origin gFrontEnd )
				)
				( attribute "PACK_TYPE" "0402"
					( Origin gFrontEnd )
				)
				( attribute "PART_NUMBER" "G21796-114"
					( Origin gFrontEnd )
				)
				( attribute "PHYS_PAGE" "240"
					( Origin gFrontEnd )
				)
				( attribute "REUSE_ID" "9"
					( Origin gFrontEnd )
				)
				( attribute "ROOM" "P3V3_STBY_VR"
					( Origin gFrontEnd )
				)
				( attribute "ROT" "0"
					( Origin gFrontEnd )
				)
				( attribute "SEC" "1"
					( Origin gPackager )
				)
				( attribute "SPOF" "TRUE"
					( Origin gFrontEnd )
				)
				( attribute "TOLERANCE" "1%"
					( Origin gFrontEnd )
				)
				( attribute "VALUE" "23.2K"
					( Origin gFrontEnd )
				)
				( attribute "VER" "2"
					( Origin gFrontEnd )
				)
				( attribute "WATTAGE" "1/16W"
					( Origin gFrontEnd )
				)
				( attribute "XY" "(9475,1425)"
					( Origin gFrontEnd )
				)
				( attribute "CHIPS_PART_NAME" "RES"
					( Origin gPackager )
				)
				( attribute "CDS_PART_NAME" "RES_0402-23.2K,1%,1/16W,CHIP,GA"
					( Origin gPackager )
				)
				( objectStatus "R8E31" )
				( pin "a"
					( attribute "PN" "1"
						( Origin gPackager )
					)
					( objectStatus "R8E31.1" )
				)
				( pin "b"
					( attribute "PN" "2"
						( Origin gPackager )
					)
					( objectStatus "R8E31.2" )
				)
			)
			( gate "@baseboard_fab2_lib.baseboard_fab2(sch_1):page240_i144"
				( attribute "CDS_LIB" "mstr_discrete"
					( Origin gPackager )
				)
				( attribute "CDS_LOCATION" "R8E25"
					( Origin gPackager )
				)
				( attribute "CDS_SEC" "1"
					( Origin gPackager )
				)
				( attribute "LOCATION" "R8E25"
					( Origin gFrontEnd )
				)
				( attribute "MATERIAL" "CHIP"
					( Origin gFrontEnd )
				)
				( attribute "PACK_TYPE" "0402"
					( Origin gFrontEnd )
				)
				( attribute "PART_NUMBER" "G21497-005"
					( Origin gFrontEnd )
				)
				( attribute "PHYS_PAGE" "240"
					( Origin gFrontEnd )
				)
				( attribute "ROOM" "PVPP_KLM_VR"
					( Origin gFrontEnd )
				)
				( attribute "ROT" "5"
					( Origin gFrontEnd )
				)
				( attribute "SEC" "1"
					( Origin gFrontEnd )
				)
				( attribute "SEC_TYPE" "0402"
					( Origin gFrontEnd )
				)
				( attribute "SPOF" "TRUE"
					( Origin gFrontEnd )
				)
				( attribute "TOLERANCE" "5%"
					( Origin gFrontEnd )
				)
				( attribute "VALUE" "0.0"
					( Origin gFrontEnd )
				)
				( attribute "VER" "1"
					( Origin gFrontEnd )
				)
				( attribute "WATTAGE" "1/16W"
					( Origin gFrontEnd )
				)
				( attribute "XY" "(9475,1825)"
					( Origin gFrontEnd )
				)
				( attribute "CHIPS_PART_NAME" "RES"
					( Origin gPackager )
				)
				( attribute "CDS_PART_NAME" "RES_0402-0.0,5%,1/16W,CHIP,G21A"
					( Origin gPackager )
				)
				( objectStatus "R8E25" )
				( pin "a"
					( attribute "PN" "1"
						( Origin gPackager )
					)
					( objectStatus "R8E25.1" )
				)
				( pin "b"
					( attribute "PN" "2"
						( Origin gPackager )
					)
					( objectStatus "R8E25.2" )
				)
			)
			( gate "@baseboard_fab2_lib.baseboard_fab2(sch_1):page240_i146"
				( attribute "CDS_LIB" "mstr_discrete"
					( Origin gPackager )
				)
				( attribute "CDS_LOCATION" "R8F11"
					( Origin gPackager )
				)
				( attribute "CDS_SEC" "1"
					( Origin gPackager )
				)
				( attribute "LOCATION" "R8F11"
					( Origin gFrontEnd )
				)
				( attribute "MATERIAL" "CHIP"
					( Origin gFrontEnd )
				)
				( attribute "PACK_TYPE" "0402"
					( Origin gFrontEnd )
				)
				( attribute "PART_NUMBER" "G21497-005"
					( Origin gFrontEnd )
				)
				( attribute "PHYS_PAGE" "240"
					( Origin gFrontEnd )
				)
				( attribute "ROOM" "P3V3_STBY_VR"
					( Origin gFrontEnd )
				)
				( attribute "ROT" "0"
					( Origin gFrontEnd )
				)
				( attribute "SEC" "1"
					( Origin gPackager )
				)
				( attribute "TOLERANCE" "5%"
					( Origin gFrontEnd )
				)
				( attribute "VALUE" "0.0"
					( Origin gFrontEnd )
				)
				( attribute "VER" "1"
					( Origin gFrontEnd )
				)
				( attribute "WATTAGE" "1/16W"
					( Origin gFrontEnd )
				)
				( attribute "XY" "(10475,1725)"
					( Origin gFrontEnd )
				)
				( attribute "CHIPS_PART_NAME" "RES"
					( Origin gPackager )
				)
				( attribute "CDS_PART_NAME" "RES_0402-0.0,5%,1/16W,CHIP,G21A"
					( Origin gPackager )
				)
				( objectStatus "R8F11" )
				( pin "a"
					( attribute "PN" "1"
						( Origin gPackager )
					)
					( objectStatus "R8F11.1" )
				)
				( pin "b"
					( attribute "PN" "2"
						( Origin gPackager )
					)
					( objectStatus "R8F11.2" )
				)
			)
			( gate "@baseboard_fab2_lib.baseboard_fab2(sch_1):page240_i148"
				( attribute "BOM_COST" "P3V3_STBY_VR"
					( Origin gFrontEnd )
				)
				( attribute "CDS_LIB" "mstr_discrete"
					( Origin gPackager )
				)
				( attribute "CDS_LOCATION" "R8F3"
					( Origin gPackager )
				)
				( attribute "CDS_SEC" "1"
					( Origin gPackager )
				)
				( attribute "LOCATION" "R8F3"
					( Origin gFrontEnd )
				)
				( attribute "MATERIAL" "EMPTY"
					( Origin gFrontEnd )
				)
				( attribute "PACK_TYPE" "0402"
					( Origin gFrontEnd )
				)
				( attribute "PART_NUMBER" "G21497-016"
					( Origin gFrontEnd )
				)
				( attribute "PHYS_PAGE" "240"
					( Origin gFrontEnd )
				)
				( attribute "REUSE_ID" "29"
					( Origin gFrontEnd )
				)
				( attribute "ROOM" "P3V3_STBY_VR"
					( Origin gFrontEnd )
				)
				( attribute "ROT" "0"
					( Origin gFrontEnd )
				)
				( attribute "SEC" "1"
					( Origin gPackager )
				)
				( attribute "TOLERANCE" "5%"
					( Origin gFrontEnd )
				)
				( attribute "VALUE" "2.2"
					( Origin gFrontEnd )
				)
				( attribute "VER" "2"
					( Origin gFrontEnd )
				)
				( attribute "WATTAGE" "1/16W"
					( Origin gFrontEnd )
				)
				( attribute "XY" "(10450,3550)"
					( Origin gFrontEnd )
				)
				( attribute "CHIPS_PART_NAME" "RES"
					( Origin gPackager )
				)
				( attribute "CDS_PART_NAME" "RES_0402-2.2,5%,1/16W,EMPTY,G2A"
					( Origin gPackager )
				)
				( objectStatus "R8F3" )
				( pin "a"
					( attribute "PN" "1"
						( Origin gPackager )
					)
					( objectStatus "R8F3.1" )
				)
				( pin "b"
					( attribute "PN" "2"
						( Origin gPackager )
					)
					( objectStatus "R8F3.2" )
				)
			)
			( gate "@baseboard_fab2_lib.baseboard_fab2(sch_1):page240_i152"
				( attribute "BOM_COST" "P3V3_STBY_VR"
					( Origin gFrontEnd )
				)
				( attribute "CDS_LIB" "mstr_discrete"
					( Origin gPackager )
				)
				( attribute "CDS_LOCATION" "R2T4"
					( Origin gPackager )
				)
				( attribute "CDS_SEC" "1"
					( Origin gPackager )
				)
				( attribute "LOCATION" "R2T4"
					( Origin gFrontEnd )
				)
				( attribute "MATERIAL" "CHIP"
					( Origin gFrontEnd )
				)
				( attribute "PACK_TYPE" "0402"
					( Origin gFrontEnd )
				)
				( attribute "PART_NUMBER" "G85996-004"
					( Origin gFrontEnd )
				)
				( attribute "PHYS_PAGE" "240"
					( Origin gFrontEnd )
				)
				( attribute "REUSE_ID" "34"
					( Origin gFrontEnd )
				)
				( attribute "ROOM" "P3V3_STBY_VR"
					( Origin gFrontEnd )
				)
				( attribute "ROT" "0"
					( Origin gFrontEnd )
				)
				( attribute "SEC" "1"
					( Origin gPackager )
				)
				( attribute "TOLERANCE" "0.1%"
					( Origin gFrontEnd )
				)
				( attribute "VALUE" "1.0K"
					( Origin gFrontEnd )
				)
				( attribute "VER" "2"
					( Origin gFrontEnd )
				)
				( attribute "WATTAGE" "1/16W"
					( Origin gFrontEnd )
				)
				( attribute "XY" "(11025,3875)"
					( Origin gFrontEnd )
				)
				( attribute "CHIPS_PART_NAME" "RES"
					( Origin gPackager )
				)
				( attribute "CDS_PART_NAME" "RES_0402-1.0K,0.1%,1/16W,CHIP,A"
					( Origin gPackager )
				)
				( objectStatus "R2T4" )
				( pin "a"
					( attribute "PN" "1"
						( Origin gPackager )
					)
					( objectStatus "R2T4.1" )
				)
				( pin "b"
					( attribute "PN" "2"
						( Origin gPackager )
					)
					( objectStatus "R2T4.2" )
				)
			)
			( gate "@baseboard_fab2_lib.baseboard_fab2(sch_1):page240_i154"
				( attribute "BOM_COST" "P3V3_STBY_VR"
					( Origin gFrontEnd )
				)
				( attribute "CDS_LIB" "mstr_discrete"
					( Origin gPackager )
				)
				( attribute "CDS_LOCATION" "C8F14"
					( Origin gPackager )
				)
				( attribute "CDS_SEC" "1"
					( Origin gPackager )
				)
				( attribute "LOCATION" "C8F14"
					( Origin gFrontEnd )
				)
				( attribute "MATERIAL" "POSCAP"
					( Origin gFrontEnd )
				)
				( attribute "PACK_TYPE" "3018"
					( Origin gFrontEnd )
				)
				( attribute "PART_NUMBER" "724613-091"
					( Origin gFrontEnd )
				)
				( attribute "PHYS_PAGE" "240"
					( Origin gFrontEnd )
				)
				( attribute "REUSE_ID" "28"
					( Origin gFrontEnd )
				)
				( attribute "ROOM" "P3V3_STBY_VR"
					( Origin gFrontEnd )
				)
				( attribute "ROT" "0"
					( Origin gFrontEnd )
				)
				( attribute "SEC" "1"
					( Origin gPackager )
				)
				( attribute "TOLERANCE" "20%"
					( Origin gFrontEnd )
				)
				( attribute "VALUE" "470UF"
					( Origin gFrontEnd )
				)
				( attribute "VER" "1"
					( Origin gFrontEnd )
				)
				( attribute "VOLTAGE" "6.3V"
					( Units "uVoltage" "V" 1.000000)
					( Origin gFrontEnd )
				)
				( attribute "XY" "(11350,3875)"
					( Origin gFrontEnd )
				)
				( attribute "CHIPS_PART_NAME" "CAPP"
					( Origin gPackager )
				)
				( attribute "CDS_PART_NAME" "CAPP_3018-470UF,6.3V,20%,POSCAA"
					( Origin gPackager )
				)
				( objectStatus "C8F14" )
				( pin "a"
					( attribute "PN" "1"
						( Origin gPackager )
					)
					( objectStatus "C8F14.1" )
				)
				( pin "b"
					( attribute "PN" "2"
						( Origin gPackager )
					)
					( objectStatus "C8F14.2" )
				)
			)
			( gate "@baseboard_fab2_lib.baseboard_fab2(sch_1):page240_i155"
				( attribute "BOM_COST" "P3V3_STBY_VR"
					( Origin gFrontEnd )
				)
				( attribute "CDS_LIB" "mstr_discrete"
					( Origin gPackager )
				)
				( attribute "CDS_LOCATION" "C8F8"
					( Origin gPackager )
				)
				( attribute "CDS_SEC" "1"
					( Origin gPackager )
				)
				( attribute "LOCATION" "C8F8"
					( Origin gFrontEnd )
				)
				( attribute "MATERIAL" "POSCAP"
					( Origin gFrontEnd )
				)
				( attribute "PACK_TYPE" "3018"
					( Origin gFrontEnd )
				)
				( attribute "PART_NUMBER" "724613-091"
					( Origin gFrontEnd )
				)
				( attribute "PHYS_PAGE" "240"
					( Origin gFrontEnd )
				)
				( attribute "REUSE_ID" "28"
					( Origin gFrontEnd )
				)
				( attribute "ROOM" "P3V3_STBY_VR"
					( Origin gFrontEnd )
				)
				( attribute "ROT" "0"
					( Origin gFrontEnd )
				)
				( attribute "SEC" "1"
					( Origin gPackager )
				)
				( attribute "TOLERANCE" "20%"
					( Origin gFrontEnd )
				)
				( attribute "VALUE" "470UF"
					( Origin gFrontEnd )
				)
				( attribute "VER" "1"
					( Origin gFrontEnd )
				)
				( attribute "VOLTAGE" "6.3V"
					( Units "uVoltage" "V" 1.000000)
					( Origin gFrontEnd )
				)
				( attribute "XY" "(11675,3875)"
					( Origin gFrontEnd )
				)
				( attribute "CHIPS_PART_NAME" "CAPP"
					( Origin gPackager )
				)
				( attribute "CDS_PART_NAME" "CAPP_3018-470UF,6.3V,20%,POSCAA"
					( Origin gPackager )
				)
				( objectStatus "C8F8" )
				( pin "a"
					( attribute "PN" "1"
						( Origin gPackager )
					)
					( objectStatus "C8F8.1" )
				)
				( pin "b"
					( attribute "PN" "2"
						( Origin gPackager )
					)
					( objectStatus "C8F8.2" )
				)
			)
			( gate "@baseboard_fab2_lib.baseboard_fab2(sch_1):page240_i158"
				( attribute "BOM_COST" "P3V3_STBY_VR"
					( Origin gFrontEnd )
				)
				( attribute "CDS_LIB" "mstr_discrete"
					( Origin gPackager )
				)
				( attribute "CDS_LOCATION" "C2T7"
					( Origin gPackager )
				)
				( attribute "CDS_SEC" "1"
					( Origin gPackager )
				)
				( attribute "LOCATION" "C2T7"
					( Origin gFrontEnd )
				)
				( attribute "MATERIAL" "X6S"
					( Origin gFrontEnd )
				)
				( attribute "PACK_TYPE" "0805"
					( Origin gFrontEnd )
				)
				( attribute "PART_NUMBER" "C95333-008"
					( Origin gFrontEnd )
				)
				( attribute "PHYS_PAGE" "240"
					( Origin gFrontEnd )
				)
				( attribute "REUSE_ID" "33"
					( Origin gFrontEnd )
				)
				( attribute "ROOM" "P3V3_STBY_VR"
					( Origin gFrontEnd )
				)
				( attribute "ROT" "0"
					( Origin gFrontEnd )
				)
				( attribute "SEC" "1"
					( Origin gPackager )
				)
				( attribute "TOLERANCE" "20%"
					( Origin gFrontEnd )
				)
				( attribute "VALUE" "22UF"
					( Origin gFrontEnd )
				)
				( attribute "VER" "1"
					( Origin gFrontEnd )
				)
				( attribute "VOLTAGE" "6.3V"
					( Units "uVoltage" "V" 1.000000)
					( Origin gFrontEnd )
				)
				( attribute "XY" "(11950,3875)"
					( Origin gFrontEnd )
				)
				( attribute "CHIPS_PART_NAME" "CAP"
					( Origin gPackager )
				)
				( attribute "CDS_PART_NAME" "CAP_0805-22UF,6.3V,20%,X6S,C95A"
					( Origin gPackager )
				)
				( objectStatus "C2T7" )
				( pin "a"
					( attribute "PN" "1"
						( Origin gPackager )
					)
					( objectStatus "C2T7.1" )
				)
				( pin "b"
					( attribute "PN" "2"
						( Origin gPackager )
					)
					( objectStatus "C2T7.2" )
				)
			)
			( gate "@baseboard_fab2_lib.baseboard_fab2(sch_1):page240_i160"
				( attribute "BOM_COST" "P3V3_STBY_VR"
					( Origin gFrontEnd )
				)
				( attribute "CDS_LIB" "mstr_discrete"
					( Origin gPackager )
				)
				( attribute "CDS_LOCATION" "C2T6"
					( Origin gPackager )
				)
				( attribute "CDS_SEC" "1"
					( Origin gPackager )
				)
				( attribute "LOCATION" "C2T6"
					( Origin gFrontEnd )
				)
				( attribute "MATERIAL" "X6S"
					( Origin gFrontEnd )
				)
				( attribute "PACK_TYPE" "0805"
					( Origin gFrontEnd )
				)
				( attribute "PART_NUMBER" "C95333-008"
					( Origin gFrontEnd )
				)
				( attribute "PHYS_PAGE" "240"
					( Origin gFrontEnd )
				)
				( attribute "REUSE_ID" "33"
					( Origin gFrontEnd )
				)
				( attribute "ROOM" "P3V3_STBY_VR"
					( Origin gFrontEnd )
				)
				( attribute "ROT" "0"
					( Origin gFrontEnd )
				)
				( attribute "SEC" "1"
					( Origin gPackager )
				)
				( attribute "TOLERANCE" "20%"
					( Origin gFrontEnd )
				)
				( attribute "VALUE" "22UF"
					( Origin gFrontEnd )
				)
				( attribute "VER" "1"
					( Origin gFrontEnd )
				)
				( attribute "VOLTAGE" "6.3V"
					( Units "uVoltage" "V" 1.000000)
					( Origin gFrontEnd )
				)
				( attribute "XY" "(12175,3850)"
					( Origin gFrontEnd )
				)
				( attribute "CHIPS_PART_NAME" "CAP"
					( Origin gPackager )
				)
				( attribute "CDS_PART_NAME" "CAP_0805-22UF,6.3V,20%,X6S,C95A"
					( Origin gPackager )
				)
				( objectStatus "C2T6" )
				( pin "a"
					( attribute "PN" "1"
						( Origin gPackager )
					)
					( objectStatus "C2T6.1" )
				)
				( pin "b"
					( attribute "PN" "2"
						( Origin gPackager )
					)
					( objectStatus "C2T6.2" )
				)
			)
			( gate "@baseboard_fab2_lib.baseboard_fab2(sch_1):page240_i163"
				( attribute "BOM_COST" "P3V3_STBY_VR"
					( Origin gFrontEnd )
				)
				( attribute "CDS_LIB" "mstr_discrete"
					( Origin gPackager )
				)
				( attribute "CDS_LOCATION" "C8F3"
					( Origin gPackager )
				)
				( attribute "CDS_SEC" "1"
					( Origin gPackager )
				)
				( attribute "LOCATION" "C8F3"
					( Origin gFrontEnd )
				)
				( attribute "MATERIAL" "EMPTY"
					( Origin gFrontEnd )
				)
				( attribute "PACK_TYPE" "0402LF"
					( Origin gFrontEnd )
				)
				( attribute "PART_NUMBER" "A36096-091"
					( Origin gFrontEnd )
				)
				( attribute "PHYS_PAGE" "240"
					( Origin gFrontEnd )
				)
				( attribute "REUSE_ID" "26"
					( Origin gFrontEnd )
				)
				( attribute "ROOM" "P3V3_STBY_VR"
					( Origin gFrontEnd )
				)
				( attribute "ROT" "0"
					( Origin gFrontEnd )
				)
				( attribute "SEC" "1"
					( Origin gPackager )
				)
				( attribute "TOLERANCE" "10%"
					( Origin gFrontEnd )
				)
				( attribute "VALUE" "3300PF"
					( Origin gFrontEnd )
				)
				( attribute "VER" "1"
					( Origin gFrontEnd )
				)
				( attribute "VOLTAGE" "50V"
					( Units "uVoltage" "V" 1.000000)
					( Origin gFrontEnd )
				)
				( attribute "XY" "(10450,3900)"
					( Origin gFrontEnd )
				)
				( attribute "CHIPS_PART_NAME" "CAP"
					( Origin gPackager )
				)
				( attribute "CDS_PART_NAME" "CAP_0402LF-3300PF,50V,10%,EMPTA"
					( Origin gPackager )
				)
				( objectStatus "C8F3" )
				( pin "a"
					( attribute "PN" "1"
						( Origin gPackager )
					)
					( objectStatus "C8F3.1" )
				)
				( pin "b"
					( attribute "PN" "2"
						( Origin gPackager )
					)
					( objectStatus "C8F3.2" )
				)
			)
			( gate "@baseboard_fab2_lib.baseboard_fab2(sch_1):page240_i170"
				( attribute "CDS_LIB" "mstr_discrete"
					( Origin gPackager )
				)
				( attribute "CDS_LOCATION" "EU8E1"
					( Origin gPackager )
				)
				( attribute "CDS_SEC" "1"
					( Origin gPackager )
				)
				( attribute "LOCATION" "EU8E1"
					( Origin gFrontEnd )
				)
				( attribute "MATERIAL" "IC"
					( Origin gFrontEnd )
				)
				( attribute "PACK_TYPE" "SM"
					( Origin gFrontEnd )
				)
				( attribute "PART_NUMBER" "H66258-001"
					( Origin gFrontEnd )
				)
				( attribute "PHYS_PAGE" "240"
					( Origin gFrontEnd )
				)
				( attribute "ROOM" "P3V3_STBY_VR"
					( Origin gFrontEnd )
				)
				( attribute "ROT" "0"
					( Origin gFrontEnd )
				)
				( attribute "SEC" "1"
					( Origin gFrontEnd )
				)
				( attribute "SEC_TYPE" "SM"
					( Origin gFrontEnd )
				)
				( attribute "VER" "1"
					( Origin gFrontEnd )
				)
				( attribute "XY" "(9475,3425)"
					( Origin gFrontEnd )
				)
				( attribute "CHIPS_PART_NAME" "CSD87384M"
					( Origin gPackager )
				)
				( attribute "CDS_PART_NAME" "CSD87384M_SM-IC,H66258-001"
					( Origin gPackager )
				)
				( objectStatus "EU8E1" )
				( pin "bg"
					( attribute "PN" "4"
						( Origin gPackager )
					)
					( objectStatus "EU8E1.4" )
				)
				( pin "pgnd"
					( attribute "PN" "3"
						( Origin gPackager )
					)
					( objectStatus "EU8E1.3" )
				)
				( pin "tg"
					( attribute "PN" "1"
						( Origin gPackager )
					)
					( objectStatus "EU8E1.1" )
				)
				( pin "vin"
					( attribute "PN" "2"
						( Origin gPackager )
					)
					( objectStatus "EU8E1.2" )
				)
				( pin "vsw"
					( attribute "PN" "5"
						( Origin gPackager )
					)
					( objectStatus "EU8E1.5" )
				)
			)
			( gate "@baseboard_fab2_lib.baseboard_fab2(sch_1):page240_i171"
				( attribute "CDS_LIB" "mstr_discrete"
					( Origin gPackager )
				)
				( attribute "CDS_LOCATION" "R8F10"
					( Origin gPackager )
				)
				( attribute "CDS_SEC" "1"
					( Origin gPackager )
				)
				( attribute "LOCATION" "R8F10"
					( Origin gFrontEnd )
				)
				( attribute "MATERIAL" "CHIP"
					( Origin gFrontEnd )
				)
				( attribute "PACK_TYPE" "0402"
					( Origin gFrontEnd )
				)
				( attribute "PART_NUMBER" "G21796-250"
					( Origin gFrontEnd )
				)
				( attribute "PHYS_PAGE" "240"
					( Origin gFrontEnd )
				)
				( attribute "ROOM" "P3V3_STBY_VR"
					( Origin gFrontEnd )
				)
				( attribute "ROT" "0"
					( Origin gFrontEnd )
				)
				( attribute "SEC" "1"
					( Origin gFrontEnd )
				)
				( attribute "SEC_TYPE" "0402"
					( Origin gFrontEnd )
				)
				( attribute "TOLERANCE" "1.0%"
					( Origin gFrontEnd )
				)
				( attribute "VALUE" "22.1"
					( Origin gFrontEnd )
				)
				( attribute "VER" "1"
					( Origin gFrontEnd )
				)
				( attribute "WATTAGE" "1/16W"
					( Origin gFrontEnd )
				)
				( attribute "XY" "(7175,3825)"
					( Origin gFrontEnd )
				)
				( attribute "CHIPS_PART_NAME" "RES"
					( Origin gPackager )
				)
				( attribute "CDS_PART_NAME" "RES_0402-22.1,1.0%,1/16W,CHIP,A"
					( Origin gPackager )
				)
				( objectStatus "R8F10" )
				( pin "a"
					( attribute "PN" "1"
						( Origin gPackager )
					)
					( objectStatus "R8F10.1" )
				)
				( pin "b"
					( attribute "PN" "2"
						( Origin gPackager )
					)
					( objectStatus "R8F10.2" )
				)
			)
			( gate "@baseboard_fab2_lib.baseboard_fab2(sch_1):page240_i173"
				( attribute "CDS_LIB" "mstr_discrete"
					( Origin gPackager )
				)
				( attribute "CDS_LOCATION" "L8F1"
					( Origin gPackager )
				)
				( attribute "CDS_SEC" "1"
					( Origin gPackager )
				)
				( attribute "LOCATION" "L8F1"
					( Origin gFrontEnd )
				)
				( attribute "MATERIAL" "IND"
					( Origin gFrontEnd )
				)
				( attribute "PACK_TYPE" "SM"
					( Origin gFrontEnd )
				)
				( attribute "PART_NUMBER" "E98679-006"
					( Origin gFrontEnd )
				)
				( attribute "PHYS_PAGE" "240"
					( Origin gFrontEnd )
				)
				( attribute "ROT" "0"
					( Origin gFrontEnd )
				)
				( attribute "SEC" "1"
					( Origin gPackager )
				)
				( attribute "VALUE" "1.00UH"
					( Origin gFrontEnd )
				)
				( attribute "VER" "1"
					( Origin gFrontEnd )
				)
				( attribute "XY" "(10800,4050)"
					( Origin gFrontEnd )
				)
				( attribute "CHIPS_PART_NAME" "INDUCTOR"
					( Origin gPackager )
				)
				( attribute "CDS_PART_NAME" "INDUCTOR_SM-1.00UH,IND,E98679-A"
					( Origin gPackager )
				)
				( objectStatus "L8F1" )
				( pin "ina"
					( attribute "PN" "1"
						( Origin gPackager )
					)
					( objectStatus "L8F1.1" )
				)
				( pin "inb"
					( attribute "PN" "2"
						( Origin gPackager )
					)
					( objectStatus "L8F1.2" )
				)
			)
			( gate "@baseboard_fab2_lib.baseboard_fab2(sch_1):page240_i174"
				( attribute "BOM_COST" "P3V3_STBY_VR"
					( Origin gFrontEnd )
				)
				( attribute "CDS_LIB" "mstr_discrete"
					( Origin gPackager )
				)
				( attribute "CDS_LOCATION" "C2T9"
					( Origin gPackager )
				)
				( attribute "CDS_SEC" "1"
					( Origin gPackager )
				)
				( attribute "LOCATION" "C2T9"
					( Origin gFrontEnd )
				)
				( attribute "MATERIAL" "X6S"
					( Origin gFrontEnd )
				)
				( attribute "PACK_TYPE" "0805"
					( Origin gFrontEnd )
				)
				( attribute "PART_NUMBER" "C95333-008"
					( Origin gFrontEnd )
				)
				( attribute "PHYS_PAGE" "240"
					( Origin gFrontEnd )
				)
				( attribute "REUSE_ID" "33"
					( Origin gFrontEnd )
				)
				( attribute "ROOM" "P3V3_STBY_VR"
					( Origin gFrontEnd )
				)
				( attribute "ROT" "0"
					( Origin gFrontEnd )
				)
				( attribute "SEC" "1"
					( Origin gPackager )
				)
				( attribute "TOLERANCE" "20%"
					( Origin gFrontEnd )
				)
				( attribute "VALUE" "22UF"
					( Origin gFrontEnd )
				)
				( attribute "VER" "1"
					( Origin gFrontEnd )
				)
				( attribute "VOLTAGE" "6.3V"
					( Units "uVoltage" "V" 1.000000)
					( Origin gFrontEnd )
				)
				( attribute "XY" "(12425,3850)"
					( Origin gFrontEnd )
				)
				( attribute "CHIPS_PART_NAME" "CAP"
					( Origin gPackager )
				)
				( attribute "CDS_PART_NAME" "CAP_0805-22UF,6.3V,20%,X6S,C95A"
					( Origin gPackager )
				)
				( objectStatus "C2T9" )
				( pin "a"
					( attribute "PN" "1"
						( Origin gPackager )
					)
					( objectStatus "C2T9.1" )
				)
				( pin "b"
					( attribute "PN" "2"
						( Origin gPackager )
					)
					( objectStatus "C2T9.2" )
				)
			)
			( gate "@baseboard_fab2_lib.baseboard_fab2(sch_1):page240_i176"
				( attribute "CDS_LIB" "mstr_discrete"
					( Origin gPackager )
				)
				( attribute "CDS_LOCATION" "R8F2"
					( Origin gPackager )
				)
				( attribute "CDS_SEC" "1"
					( Origin gPackager )
				)
				( attribute "LOCATION" "R8F2"
					( Origin gFrontEnd )
				)
				( attribute "MATERIAL" "CHIP"
					( Origin gFrontEnd )
				)
				( attribute "PACK_TYPE" "0402"
					( Origin gFrontEnd )
				)
				( attribute "PART_NUMBER" "G21497-005"
					( Origin gFrontEnd )
				)
				( attribute "PHYS_PAGE" "240"
					( Origin gFrontEnd )
				)
				( attribute "ROOM" "PVCCIN_CPU0_VR"
					( Origin gFrontEnd )
				)
				( attribute "ROT" "0"
					( Origin gFrontEnd )
				)
				( attribute "SEC" "1"
					( Origin gPackager )
				)
				( attribute "TOLERANCE" "5%"
					( Origin gFrontEnd )
				)
				( attribute "VALUE" "0.0"
					( Origin gFrontEnd )
				)
				( attribute "VER" "1"
					( Origin gFrontEnd )
				)
				( attribute "WATTAGE" "1/16W"
					( Origin gFrontEnd )
				)
				( attribute "XY" "(6525,2725)"
					( Origin gFrontEnd )
				)
				( attribute "CHIPS_PART_NAME" "RES"
					( Origin gPackager )
				)
				( attribute "CDS_PART_NAME" "RES_0402-0.0,5%,1/16W,CHIP,G21A"
					( Origin gPackager )
				)
				( objectStatus "R8F2" )
				( pin "a"
					( attribute "PN" "1"
						( Origin gPackager )
					)
					( objectStatus "R8F2.1" )
				)
				( pin "b"
					( attribute "PN" "2"
						( Origin gPackager )
					)
					( objectStatus "R8F2.2" )
				)
			)
			( gate "@baseboard_fab2_lib.baseboard_fab2(sch_1):page240_i177"
				( attribute "BOM_COST" "SM_CONTROLLER"
					( Origin gFrontEnd )
				)
				( attribute "CDS_LIB" "mstr_discrete"
					( Origin gPackager )
				)
				( attribute "CDS_LOCATION" "R8E40"
					( Origin gPackager )
				)
				( attribute "CDS_SEC" "1"
					( Origin gPackager )
				)
				( attribute "LOCATION" "R8E40"
					( Origin gFrontEnd )
				)
				( attribute "MATERIAL" "EMPTY"
					( Origin gFrontEnd )
				)
				( attribute "PACK_TYPE" "0402"
					( Origin gFrontEnd )
				)
				( attribute "PART_NUMBER" "G21796-010"
					( Origin gFrontEnd )
				)
				( attribute "PHYS_PAGE" "240"
					( Origin gFrontEnd )
				)
				( attribute "ROOM" "BMC"
					( Origin gFrontEnd )
				)
				( attribute "ROT" "0"
					( Origin gFrontEnd )
				)
				( attribute "SEC" "1"
					( Origin gPackager )
				)
				( attribute "TOLERANCE" "1%"
					( Origin gFrontEnd )
				)
				( attribute "VALUE" "100.0K"
					( Origin gFrontEnd )
				)
				( attribute "VER" "2"
					( Origin gFrontEnd )
				)
				( attribute "WATTAGE" "1/16W"
					( Origin gFrontEnd )
				)
				( attribute "XY" "(6950,3250)"
					( Origin gFrontEnd )
				)
				( attribute "CHIPS_PART_NAME" "RES"
					( Origin gPackager )
				)
				( attribute "CDS_PART_NAME" "RES_0402-100.0K,1%,1/16W,EMPTYA"
					( Origin gPackager )
				)
				( objectStatus "R8E40" )
				( pin "a"
					( attribute "PN" "1"
						( Origin gPackager )
					)
					( objectStatus "R8E40.1" )
				)
				( pin "b"
					( attribute "PN" "2"
						( Origin gPackager )
					)
					( objectStatus "R8E40.2" )
				)
			)
			( gate "@baseboard_fab2_lib.baseboard_fab2(sch_1):page241_i2"
				( attribute "BOM_COST" "P5V_STBY_VR"
					( Origin gFrontEnd )
				)
				( attribute "CDS_LIB" "mstr_discrete"
					( Origin gPackager )
				)
				( attribute "CDS_LOCATION" "C8E9"
					( Origin gPackager )
				)
				( attribute "CDS_SEC" "1"
					( Origin gPackager )
				)
				( attribute "LOCATION" "C8E9"
					( Origin gFrontEnd )
				)
				( attribute "MATERIAL" "X6S"
					( Origin gFrontEnd )
				)
				( attribute "PACK_TYPE" "0805"
					( Origin gFrontEnd )
				)
				( attribute "PART_NUMBER" "C95333-008"
					( Origin gFrontEnd )
				)
				( attribute "PHYS_PAGE" "241"
					( Origin gFrontEnd )
				)
				( attribute "REUSE_ID" "33"
					( Origin gPackager )
				)
				( attribute "ROOM" "P5V_STBY_VR"
					( Origin gFrontEnd )
				)
				( attribute "ROT" "0"
					( Origin gFrontEnd )
				)
				( attribute "SEC" "1"
					( Origin gFrontEnd )
				)
				( attribute "SEC_TYPE" "0805"
					( Origin gFrontEnd )
				)
				( attribute "TOLERANCE" "20%"
					( Origin gFrontEnd )
				)
				( attribute "VALUE" "22UF"
					( Origin gFrontEnd )
				)
				( attribute "VER" "1"
					( Origin gFrontEnd )
				)
				( attribute "VOLTAGE" "6.3V"
					( Units "uVoltage" "V" 1.000000)
					( Origin gFrontEnd )
				)
				( attribute "XY" "(3700,3875)"
					( Origin gFrontEnd )
				)
				( attribute "CHIPS_PART_NAME" "CAP"
					( Origin gPackager )
				)
				( attribute "CDS_PART_NAME" "CAP_0805-22UF,6.3V,20%,X6S,C95A"
					( Origin gPackager )
				)
				( objectStatus "C8E9" )
				( pin "a"
					( attribute "PN" "1"
						( Origin gPackager )
					)
					( objectStatus "C8E9.1" )
				)
				( pin "b"
					( attribute "PN" "2"
						( Origin gPackager )
					)
					( objectStatus "C8E9.2" )
				)
			)
			( gate "@baseboard_fab2_lib.baseboard_fab2(sch_1):page241_i3"
				( attribute "BOM_COST" "P5V_STBY_VR"
					( Origin gFrontEnd )
				)
				( attribute "CDS_LIB" "mstr_discrete"
					( Origin gPackager )
				)
				( attribute "CDS_LOCATION" "C8E7"
					( Origin gPackager )
				)
				( attribute "CDS_SEC" "1"
					( Origin gPackager )
				)
				( attribute "LOCATION" "C8E7"
					( Origin gFrontEnd )
				)
				( attribute "MATERIAL" "X6S"
					( Origin gFrontEnd )
				)
				( attribute "PACK_TYPE" "0805"
					( Origin gFrontEnd )
				)
				( attribute "PART_NUMBER" "C95333-008"
					( Origin gFrontEnd )
				)
				( attribute "PHYS_PAGE" "241"
					( Origin gFrontEnd )
				)
				( attribute "REUSE_ID" "33"
					( Origin gFrontEnd )
				)
				( attribute "ROOM" "P5V_STBY_VR"
					( Origin gFrontEnd )
				)
				( attribute "ROT" "0"
					( Origin gFrontEnd )
				)
				( attribute "SEC" "1"
					( Origin gFrontEnd )
				)
				( attribute "SEC_TYPE" "0805"
					( Origin gFrontEnd )
				)
				( attribute "TOLERANCE" "20%"
					( Origin gFrontEnd )
				)
				( attribute "VALUE" "22UF"
					( Origin gFrontEnd )
				)
				( attribute "VER" "1"
					( Origin gFrontEnd )
				)
				( attribute "VOLTAGE" "6.3V"
					( Units "uVoltage" "V" 1.000000)
					( Origin gFrontEnd )
				)
				( attribute "XY" "(3325,3900)"
					( Origin gFrontEnd )
				)
				( attribute "CHIPS_PART_NAME" "CAP"
					( Origin gPackager )
				)
				( attribute "CDS_PART_NAME" "CAP_0805-22UF,6.3V,20%,X6S,C95A"
					( Origin gPackager )
				)
				( objectStatus "C8E7" )
				( pin "a"
					( attribute "PN" "1"
						( Origin gPackager )
					)
					( objectStatus "C8E7.1" )
				)
				( pin "b"
					( attribute "PN" "2"
						( Origin gPackager )
					)
					( objectStatus "C8E7.2" )
				)
			)
			( gate "@baseboard_fab2_lib.baseboard_fab2(sch_1):page241_i8"
				( attribute "CDS_LIB" "mstr_discrete"
					( Origin gPackager )
				)
				( attribute "CDS_LOCATION" "C8E4"
					( Origin gPackager )
				)
				( attribute "CDS_SEC" "1"
					( Origin gPackager )
				)
				( attribute "LOCATION" "C8E4"
					( Origin gFrontEnd )
				)
				( attribute "MATERIAL" "POSCAP"
					( Origin gFrontEnd )
				)
				( attribute "PACK_TYPE" "3018"
					( Origin gFrontEnd )
				)
				( attribute "PART_NUMBER" "724613-091"
					( Origin gFrontEnd )
				)
				( attribute "PHYS_PAGE" "241"
					( Origin gFrontEnd )
				)
				( attribute "REUSE_ID" "28"
					( Origin gFrontEnd )
				)
				( attribute "ROT" "6"
					( Origin gFrontEnd )
				)
				( attribute "SEC" "1"
					( Origin gFrontEnd )
				)
				( attribute "SEC_TYPE" "3018"
					( Origin gFrontEnd )
				)
				( attribute "TOLERANCE" "20%"
					( Origin gFrontEnd )
				)
				( attribute "VALUE" "470UF"
					( Origin gFrontEnd )
				)
				( attribute "VER" "3"
					( Origin gFrontEnd )
				)
				( attribute "VOLTAGE" "6.3V"
					( Units "uVoltage" "V" 1.000000)
					( Origin gFrontEnd )
				)
				( attribute "XY" "(2950,3875)"
					( Origin gFrontEnd )
				)
				( attribute "CHIPS_PART_NAME" "CAPP"
					( Origin gPackager )
				)
				( attribute "CDS_PART_NAME" "CAPP_3018-470UF,6.3V,20%,POSCAA"
					( Origin gPackager )
				)
				( objectStatus "C8E4" )
				( pin "a"
					( attribute "PN" "1"
						( Origin gPackager )
					)
					( objectStatus "C8E4.1" )
				)
				( pin "b"
					( attribute "PN" "2"
						( Origin gPackager )
					)
					( objectStatus "C8E4.2" )
				)
			)
			( gate "@baseboard_fab2_lib.baseboard_fab2(sch_1):page241_i9"
				( attribute "BOM_COST" "P5V_STBY_VR"
					( Origin gFrontEnd )
				)
				( attribute "CDS_LIB" "mstr_discrete"
					( Origin gPackager )
				)
				( attribute "CDS_LOCATION" "R8E18"
					( Origin gPackager )
				)
				( attribute "CDS_SEC" "1"
					( Origin gPackager )
				)
				( attribute "LOCATION" "R8E18"
					( Origin gFrontEnd )
				)
				( attribute "MATERIAL" "CHIP"
					( Origin gFrontEnd )
				)
				( attribute "PACK_TYPE" "0402"
					( Origin gFrontEnd )
				)
				( attribute "PART_NUMBER" "G85996-004"
					( Origin gFrontEnd )
				)
				( attribute "PHYS_PAGE" "241"
					( Origin gFrontEnd )
				)
				( attribute "REUSE_ID" "34"
					( Origin gFrontEnd )
				)
				( attribute "ROOM" "P5V_STBY_VR"
					( Origin gFrontEnd )
				)
				( attribute "ROT" "0"
					( Origin gFrontEnd )
				)
				( attribute "SEC" "1"
					( Origin gFrontEnd )
				)
				( attribute "SEC_TYPE" "0402"
					( Origin gFrontEnd )
				)
				( attribute "TOLERANCE" "0.1%"
					( Origin gFrontEnd )
				)
				( attribute "VALUE" "1.0K"
					( Origin gFrontEnd )
				)
				( attribute "VER" "2"
					( Origin gFrontEnd )
				)
				( attribute "WATTAGE" "1/16W"
					( Origin gFrontEnd )
				)
				( attribute "XY" "(2550,3875)"
					( Origin gFrontEnd )
				)
				( attribute "CHIPS_PART_NAME" "RES"
					( Origin gPackager )
				)
				( attribute "CDS_PART_NAME" "RES_0402-1.0K,0.1%,1/16W,CHIP,A"
					( Origin gPackager )
				)
				( objectStatus "R8E18" )
				( pin "a"
					( attribute "PN" "1"
						( Origin gPackager )
					)
					( objectStatus "R8E18.1" )
				)
				( pin "b"
					( attribute "PN" "2"
						( Origin gPackager )
					)
					( objectStatus "R8E18.2" )
				)
			)
			( gate "@baseboard_fab2_lib.baseboard_fab2(sch_1):page241_i11"
				( attribute "BOM_COST" "P5V_STBY_VR"
					( Origin gFrontEnd )
				)
				( attribute "CDS_LIB" "mstr_discrete"
					( Origin gPackager )
				)
				( attribute "CDS_LOCATION" "R7E12"
					( Origin gPackager )
				)
				( attribute "CDS_SEC" "1"
					( Origin gPackager )
				)
				( attribute "LOCATION" "R7E12"
					( Origin gFrontEnd )
				)
				( attribute "MATERIAL" "CHIP"
					( Origin gFrontEnd )
				)
				( attribute "PACK_TYPE" "0402"
					( Origin gFrontEnd )
				)
				( attribute "PART_NUMBER" "G21796-026"
					( Origin gFrontEnd )
				)
				( attribute "PHYS_PAGE" "241"
					( Origin gFrontEnd )
				)
				( attribute "REUSE_ID" "21"
					( Origin gFrontEnd )
				)
				( attribute "ROOM" "P5V_STBY_VR"
					( Origin gFrontEnd )
				)
				( attribute "ROT" "0"
					( Origin gFrontEnd )
				)
				( attribute "SEC" "1"
					( Origin gFrontEnd )
				)
				( attribute "SEC_TYPE" "0402"
					( Origin gFrontEnd )
				)
				( attribute "TOLERANCE" "1%"
					( Origin gFrontEnd )
				)
				( attribute "VALUE" "1.00K"
					( Origin gFrontEnd )
				)
				( attribute "VER" "2"
					( Origin gFrontEnd )
				)
				( attribute "WATTAGE" "1/16W"
					( Origin gFrontEnd )
				)
				( attribute "XY" "(1225,4850)"
					( Origin gFrontEnd )
				)
				( attribute "CHIPS_PART_NAME" "RES"
					( Origin gPackager )
				)
				( attribute "CDS_PART_NAME" "RES_0402-1.00K,1%,1/16W,CHIP,GA"
					( Origin gPackager )
				)
				( objectStatus "R7E12" )
				( pin "a"
					( attribute "PN" "1"
						( Origin gPackager )
					)
					( objectStatus "R7E12.1" )
				)
				( pin "b"
					( attribute "PN" "2"
						( Origin gPackager )
					)
					( objectStatus "R7E12.2" )
				)
			)
			( gate "@baseboard_fab2_lib.baseboard_fab2(sch_1):page241_i12"
				( attribute "BOM_COST" "P5V_STBY_VR"
					( Origin gFrontEnd )
				)
				( attribute "CDS_LIB" "mstr_discrete"
					( Origin gPackager )
				)
				( attribute "CDS_LOCATION" "C8E6"
					( Origin gPackager )
				)
				( attribute "CDS_SEC" "1"
					( Origin gPackager )
				)
				( attribute "LOCATION" "C8E6"
					( Origin gFrontEnd )
				)
				( attribute "MATERIAL" "X7R"
					( Origin gFrontEnd )
				)
				( attribute "PACK_TYPE" "0603LF"
					( Origin gFrontEnd )
				)
				( attribute "PART_NUMBER" "602433-020"
					( Origin gFrontEnd )
				)
				( attribute "PHYS_PAGE" "241"
					( Origin gFrontEnd )
				)
				( attribute "REUSE_ID" "27"
					( Origin gFrontEnd )
				)
				( attribute "ROOM" "P5V_STBY_VR"
					( Origin gFrontEnd )
				)
				( attribute "ROT" "0"
					( Origin gFrontEnd )
				)
				( attribute "SEC" "1"
					( Origin gFrontEnd )
				)
				( attribute "SEC_TYPE" "0603LF"
					( Origin gFrontEnd )
				)
				( attribute "SPOF" "TRUE"
					( Origin gFrontEnd )
				)
				( attribute "TOLERANCE" "10%"
					( Origin gFrontEnd )
				)
				( attribute "VALUE" "0.1UF"
					( Origin gFrontEnd )
				)
				( attribute "VER" "2"
					( Origin gFrontEnd )
				)
				( attribute "VOLTAGE" "25V"
					( Units "uVoltage" "V" 1.000000)
					( Origin gFrontEnd )
				)
				( attribute "XY" "(1025,3675)"
					( Origin gFrontEnd )
				)
				( attribute "CHIPS_PART_NAME" "CAP"
					( Origin gPackager )
				)
				( attribute "CDS_PART_NAME" "CAP_0603LF-0.1UF,25V,10%,X7R,6A"
					( Origin gPackager )
				)
				( objectStatus "C8E6" )
				( pin "a"
					( attribute "PN" "1"
						( Origin gPackager )
					)
					( objectStatus "C8E6.1" )
				)
				( pin "b"
					( attribute "PN" "2"
						( Origin gPackager )
					)
					( objectStatus "C8E6.2" )
				)
			)
			( gate "@baseboard_fab2_lib.baseboard_fab2(sch_1):page241_i14"
				( attribute "BOM_COST" "P5V_STBY_VR"
					( Origin gFrontEnd )
				)
				( attribute "CDS_LIB" "mstr_discrete"
					( Origin gPackager )
				)
				( attribute "CDS_LOCATION" "C7E10"
					( Origin gPackager )
				)
				( attribute "CDS_SEC" "1"
					( Origin gPackager )
				)
				( attribute "LOCATION" "C7E10"
					( Origin gFrontEnd )
				)
				( attribute "MATERIAL" "X7R"
					( Origin gFrontEnd )
				)
				( attribute "PACK_TYPE" "0402LF"
					( Origin gFrontEnd )
				)
				( attribute "PART_NUMBER" "A36096-046"
					( Origin gFrontEnd )
				)
				( attribute "PHYS_PAGE" "241"
					( Origin gFrontEnd )
				)
				( attribute "REUSE_ID" "17"
					( Origin gFrontEnd )
				)
				( attribute "ROOM" "P5V_STBY_VR"
					( Origin gFrontEnd )
				)
				( attribute "ROT" "0"
					( Origin gFrontEnd )
				)
				( attribute "SEC" "1"
					( Origin gFrontEnd )
				)
				( attribute "SEC_TYPE" "0402LF"
					( Origin gFrontEnd )
				)
				( attribute "TOLERANCE" "10%"
					( Origin gFrontEnd )
				)
				( attribute "VALUE" "1000PF"
					( Origin gFrontEnd )
				)
				( attribute "VER" "1"
					( Origin gFrontEnd )
				)
				( attribute "VOLTAGE" "50V"
					( Units "uVoltage" "V" 1.000000)
					( Origin gFrontEnd )
				)
				( attribute "XY" "(1500,4400)"
					( Origin gFrontEnd )
				)
				( attribute "CHIPS_PART_NAME" "CAP"
					( Origin gPackager )
				)
				( attribute "CDS_PART_NAME" "CAP_0402LF-1000PF,50V,10%,X7R,A"
					( Origin gPackager )
				)
				( objectStatus "C7E10" )
				( pin "a"
					( attribute "PN" "1"
						( Origin gPackager )
					)
					( objectStatus "C7E10.1" )
				)
				( pin "b"
					( attribute "PN" "2"
						( Origin gPackager )
					)
					( objectStatus "C7E10.2" )
				)
			)
			( gate "@baseboard_fab2_lib.baseboard_fab2(sch_1):page241_i18"
				( attribute "BOM_COST" "P5V_STBY_VR"
					( Origin gFrontEnd )
				)
				( attribute "CDS_LIB" "mstr_discrete"
					( Origin gPackager )
				)
				( attribute "CDS_LOCATION" "R7E14"
					( Origin gPackager )
				)
				( attribute "CDS_SEC" "1"
					( Origin gPackager )
				)
				( attribute "LOCATION" "R7E14"
					( Origin gFrontEnd )
				)
				( attribute "MATERIAL" "CHIP"
					( Origin gFrontEnd )
				)
				( attribute "PACK_TYPE" "0402"
					( Origin gFrontEnd )
				)
				( attribute "PART_NUMBER" "G21796-224"
					( Origin gFrontEnd )
				)
				( attribute "PHYS_PAGE" "241"
					( Origin gFrontEnd )
				)
				( attribute "REUSE_ID" "8"
					( Origin gFrontEnd )
				)
				( attribute "ROOM" "P5V_STBY_VR"
					( Origin gFrontEnd )
				)
				( attribute "ROT" "0"
					( Origin gFrontEnd )
				)
				( attribute "SEC" "1"
					( Origin gFrontEnd )
				)
				( attribute "SEC_TYPE" "0402"
					( Origin gFrontEnd )
				)
				( attribute "TOLERANCE" "1%"
					( Origin gFrontEnd )
				)
				( attribute "VALUE" "75K"
					( Origin gFrontEnd )
				)
				( attribute "VER" "2"
					( Origin gFrontEnd )
				)
				( attribute "WATTAGE" "1/16W"
					( Origin gFrontEnd )
				)
				( attribute "XY" "(-825,2600)"
					( Origin gFrontEnd )
				)
				( attribute "CHIPS_PART_NAME" "RES"
					( Origin gPackager )
				)
				( attribute "CDS_PART_NAME" "RES_0402-75K,1%,1/16W,CHIP,G21A"
					( Origin gPackager )
				)
				( objectStatus "R7E14" )
				( pin "a"
					( attribute "PN" "1"
						( Origin gPackager )
					)
					( objectStatus "R7E14.1" )
				)
				( pin "b"
					( attribute "PN" "2"
						( Origin gPackager )
					)
					( objectStatus "R7E14.2" )
				)
			)
			( gate "@baseboard_fab2_lib.baseboard_fab2(sch_1):page241_i30"
				( attribute "BOM_COST" "P5V_STBY_VR"
					( Origin gFrontEnd )
				)
				( attribute "CDS_LIB" "mstr_discrete"
					( Origin gPackager )
				)
				( attribute "CDS_LOCATION" "C7E14"
					( Origin gPackager )
				)
				( attribute "CDS_SEC" "1"
					( Origin gPackager )
				)
				( attribute "FIN" "VR_1P2"
					( Origin gFrontEnd )
				)
				( attribute "LOCATION" "C7E14"
					( Origin gFrontEnd )
				)
				( attribute "MATERIAL" "X6S"
					( Origin gFrontEnd )
				)
				( attribute "PACK_TYPE" "0402"
					( Origin gFrontEnd )
				)
				( attribute "PART_NUMBER" "D97712-011"
					( Origin gFrontEnd )
				)
				( attribute "PHYS_PAGE" "241"
					( Origin gFrontEnd )
				)
				( attribute "REUSE_ID" "1"
					( Origin gFrontEnd )
				)
				( attribute "ROOM" "P5V_STBY_VR"
					( Origin gFrontEnd )
				)
				( attribute "ROT" "0"
					( Origin gFrontEnd )
				)
				( attribute "SEC" "1"
					( Origin gFrontEnd )
				)
				( attribute "SEC_TYPE" "0402"
					( Origin gFrontEnd )
				)
				( attribute "TOLERANCE" "10%"
					( Origin gFrontEnd )
				)
				( attribute "VALUE" "1.0UF"
					( Origin gFrontEnd )
				)
				( attribute "VER" "1"
					( Origin gFrontEnd )
				)
				( attribute "VOLTAGE" "16V"
					( Units "uVoltage" "V" 1.000000)
					( Origin gFrontEnd )
				)
				( attribute "XY" "(-2150,3850)"
					( Origin gFrontEnd )
				)
				( attribute "CHIPS_PART_NAME" "CAP"
					( Origin gPackager )
				)
				( attribute "CDS_PART_NAME" "CAP_0402-1.0UF,16V,10%,X6S,D97A"
					( Origin gPackager )
				)
				( objectStatus "C7E14" )
				( pin "a"
					( attribute "PN" "1"
						( Origin gPackager )
					)
					( objectStatus "C7E14.1" )
				)
				( pin "b"
					( attribute "PN" "2"
						( Origin gPackager )
					)
					( objectStatus "C7E14.2" )
				)
			)
			( gate "@baseboard_fab2_lib.baseboard_fab2(sch_1):page241_i37"
				( attribute "BOM_COST" "P5V_STBY_VR"
					( Origin gFrontEnd )
				)
				( attribute "CDS_LIB" "mstr_discrete"
					( Origin gPackager )
				)
				( attribute "CDS_LOCATION" "R7E17"
					( Origin gPackager )
				)
				( attribute "CDS_SEC" "1"
					( Origin gPackager )
				)
				( attribute "LOCATION" "R7E17"
					( Origin gFrontEnd )
				)
				( attribute "MATERIAL" "CHIP"
					( Origin gFrontEnd )
				)
				( attribute "NO_XNET_CONNECTION" "1"
					( Origin gFrontEnd )
				)
				( attribute "PACK_TYPE" "0402"
					( Origin gFrontEnd )
				)
				( attribute "PART_NUMBER" "G21497-005"
					( Origin gFrontEnd )
				)
				( attribute "PHYS_PAGE" "241"
					( Origin gFrontEnd )
				)
				( attribute "REUSE_ID" "13"
					( Origin gPackager )
				)
				( attribute "ROOM" "P5V_STBY_VR"
					( Origin gFrontEnd )
				)
				( attribute "ROT" "0"
					( Origin gFrontEnd )
				)
				( attribute "SEC" "1"
					( Origin gFrontEnd )
				)
				( attribute "SEC_TYPE" "0402"
					( Origin gFrontEnd )
				)
				( attribute "TOLERANCE" "5%"
					( Origin gFrontEnd )
				)
				( attribute "VALUE" "0.0"
					( Origin gFrontEnd )
				)
				( attribute "VER" "2"
					( Origin gFrontEnd )
				)
				( attribute "WATTAGE" "1/16W"
					( Origin gFrontEnd )
				)
				( attribute "XY" "(-2150,4200)"
					( Origin gFrontEnd )
				)
				( attribute "CHIPS_PART_NAME" "RES"
					( Origin gPackager )
				)
				( attribute "CDS_PART_NAME" "RES_0402-0.0,5%,1/16W,CHIP,G21A"
					( Origin gPackager )
				)
				( objectStatus "R7E17" )
				( pin "a"
					( attribute "PN" "1"
						( Origin gPackager )
					)
					( objectStatus "R7E17.1" )
				)
				( pin "b"
					( attribute "PN" "2"
						( Origin gPackager )
					)
					( objectStatus "R7E17.2" )
				)
			)
			( gate "@baseboard_fab2_lib.baseboard_fab2(sch_1):page241_i39"
				( attribute "BOM_COST" "P5V_STBY_VR"
					( Origin gFrontEnd )
				)
				( attribute "CDS_LIB" "mstr_discrete"
					( Origin gPackager )
				)
				( attribute "CDS_LOCATION" "C7E11"
					( Origin gPackager )
				)
				( attribute "CDS_SEC" "1"
					( Origin gPackager )
				)
				( attribute "LOCATION" "C7E11"
					( Origin gFrontEnd )
				)
				( attribute "MATERIAL" "X6S"
					( Origin gFrontEnd )
				)
				( attribute "PACK_TYPE" "1206LF"
					( Origin gFrontEnd )
				)
				( attribute "PART_NUMBER" "D38464-005"
					( Origin gFrontEnd )
				)
				( attribute "PHYS_PAGE" "241"
					( Origin gFrontEnd )
				)
				( attribute "ROOM" "P5V_STBY_VR"
					( Origin gFrontEnd )
				)
				( attribute "ROT" "0"
					( Origin gFrontEnd )
				)
				( attribute "SEC" "1"
					( Origin gFrontEnd )
				)
				( attribute "SEC_TYPE" "1206LF"
					( Origin gFrontEnd )
				)
				( attribute "TOLERANCE" "10%"
					( Origin gFrontEnd )
				)
				( attribute "VALUE" "22UF"
					( Origin gFrontEnd )
				)
				( attribute "VER" "1"
					( Origin gFrontEnd )
				)
				( attribute "VOLTAGE" "16V"
					( Units "uVoltage" "V" 1.000000)
					( Origin gFrontEnd )
				)
				( attribute "XY" "(-2550,4250)"
					( Origin gFrontEnd )
				)
				( attribute "CHIPS_PART_NAME" "CAP"
					( Origin gPackager )
				)
				( attribute "CDS_PART_NAME" "CAP_1206LF-22UF,16V,10%,X6S,D3A"
					( Origin gPackager )
				)
				( objectStatus "C7E11" )
				( pin "a"
					( attribute "PN" "1"
						( Origin gPackager )
					)
					( objectStatus "C7E11.1" )
				)
				( pin "b"
					( attribute "PN" "2"
						( Origin gPackager )
					)
					( objectStatus "C7E11.2" )
				)
			)
			( gate "@baseboard_fab2_lib.baseboard_fab2(sch_1):page241_i41"
				( attribute "BOM_COST" "P5V_STBY_VR"
					( Origin gFrontEnd )
				)
				( attribute "CDS_LIB" "mstr_discrete"
					( Origin gPackager )
				)
				( attribute "CDS_LOCATION" "C8E13"
					( Origin gPackager )
				)
				( attribute "CDS_SEC" "1"
					( Origin gPackager )
				)
				( attribute "FIN" "VR_1P2"
					( Origin gFrontEnd )
				)
				( attribute "LOCATION" "C8E13"
					( Origin gFrontEnd )
				)
				( attribute "MATERIAL" "EMPTY"
					( Origin gFrontEnd )
				)
				( attribute "PACK_TYPE" "0402LF"
					( Origin gFrontEnd )
				)
				( attribute "PART_NUMBER" "A36096-046"
					( Origin gFrontEnd )
				)
				( attribute "PHYS_PAGE" "241"
					( Origin gFrontEnd )
				)
				( attribute "REUSE_ID" "1"
					( Origin gFrontEnd )
				)
				( attribute "ROOM" "P5V_STBY_VR"
					( Origin gFrontEnd )
				)
				( attribute "ROT" "2"
					( Origin gFrontEnd )
				)
				( attribute "SEC" "1"
					( Origin gFrontEnd )
				)
				( attribute "SEC_TYPE" "0402LF"
					( Origin gFrontEnd )
				)
				( attribute "TOLERANCE" "10%"
					( Origin gFrontEnd )
				)
				( attribute "VALUE" "1000PF"
					( Origin gFrontEnd )
				)
				( attribute "VER" "1"
					( Origin gFrontEnd )
				)
				( attribute "VOLTAGE" "50V"
					( Units "uVoltage" "V" 1.000000)
					( Origin gFrontEnd )
				)
				( attribute "XY" "(-2000,3075)"
					( Origin gFrontEnd )
				)
				( attribute "CHIPS_PART_NAME" "CAP"
					( Origin gPackager )
				)
				( attribute "CDS_PART_NAME" "CAP_0402LF-1000PF,50V,10%,EMPTA"
					( Origin gPackager )
				)
				( objectStatus "C8E13" )
				( pin "a"
					( attribute "PN" "1"
						( Origin gPackager )
					)
					( objectStatus "C8E13.1" )
				)
				( pin "b"
					( attribute "PN" "2"
						( Origin gPackager )
					)
					( objectStatus "C8E13.2" )
				)
			)
			( gate "@baseboard_fab2_lib.baseboard_fab2(sch_1):page241_i45"
				( attribute "BOM_COST" "P5V_STBY_VR"
					( Origin gFrontEnd )
				)
				( attribute "CDS_LIB" "mstr_discrete"
					( Origin gPackager )
				)
				( attribute "CDS_LOCATION" "C7E13"
					( Origin gPackager )
				)
				( attribute "CDS_SEC" "1"
					( Origin gPackager )
				)
				( attribute "LOCATION" "C7E13"
					( Origin gFrontEnd )
				)
				( attribute "MATERIAL" "X6S"
					( Origin gFrontEnd )
				)
				( attribute "PACK_TYPE" "1210"
					( Origin gFrontEnd )
				)
				( attribute "PART_NUMBER" "D38464-007"
					( Origin gFrontEnd )
				)
				( attribute "PHYS_PAGE" "241"
					( Origin gFrontEnd )
				)
				( attribute "ROOM" "P5V_STBY_VR"
					( Origin gFrontEnd )
				)
				( attribute "ROT" "0"
					( Origin gFrontEnd )
				)
				( attribute "SEC" "1"
					( Origin gFrontEnd )
				)
				( attribute "SEC_TYPE" "1210"
					( Origin gFrontEnd )
				)
				( attribute "TOLERANCE" "20%"
					( Origin gFrontEnd )
				)
				( attribute "VALUE" "47UF"
					( Origin gFrontEnd )
				)
				( attribute "VER" "1"
					( Origin gFrontEnd )
				)
				( attribute "VOLTAGE" "16V"
					( Units "uVoltage" "V" 1.000000)
					( Origin gFrontEnd )
				)
				( attribute "XY" "(-2875,4275)"
					( Origin gFrontEnd )
				)
				( attribute "CHIPS_PART_NAME" "CAP"
					( Origin gPackager )
				)
				( attribute "CDS_PART_NAME" "CAP_1210-47UF,16V,20%,X6S,D384A"
					( Origin gPackager )
				)
				( objectStatus "C7E13" )
				( pin "a"
					( attribute "PN" "1"
						( Origin gPackager )
					)
					( objectStatus "C7E13.1" )
				)
				( pin "b"
					( attribute "PN" "2"
						( Origin gPackager )
					)
					( objectStatus "C7E13.2" )
				)
			)
			( gate "@baseboard_fab2_lib.baseboard_fab2(sch_1):page241_i47"
				( attribute "BOM_COST" "P5V_STBY_VR"
					( Origin gFrontEnd )
				)
				( attribute "CDS_LIB" "mstr_discrete"
					( Origin gPackager )
				)
				( attribute "CDS_LOCATION" "C7E12"
					( Origin gPackager )
				)
				( attribute "CDS_SEC" "1"
					( Origin gPackager )
				)
				( attribute "LOCATION" "C7E12"
					( Origin gFrontEnd )
				)
				( attribute "MATERIAL" "X6S"
					( Origin gFrontEnd )
				)
				( attribute "PACK_TYPE" "1210"
					( Origin gFrontEnd )
				)
				( attribute "PART_NUMBER" "D38464-007"
					( Origin gFrontEnd )
				)
				( attribute "PHYS_PAGE" "241"
					( Origin gFrontEnd )
				)
				( attribute "ROOM" "P5V_STBY_VR"
					( Origin gFrontEnd )
				)
				( attribute "ROT" "0"
					( Origin gFrontEnd )
				)
				( attribute "SEC" "1"
					( Origin gFrontEnd )
				)
				( attribute "SEC_TYPE" "1210"
					( Origin gFrontEnd )
				)
				( attribute "TOLERANCE" "20%"
					( Origin gFrontEnd )
				)
				( attribute "VALUE" "47UF"
					( Origin gFrontEnd )
				)
				( attribute "VER" "1"
					( Origin gFrontEnd )
				)
				( attribute "VOLTAGE" "16V"
					( Units "uVoltage" "V" 1.000000)
					( Origin gFrontEnd )
				)
				( attribute "XY" "(-3225,4275)"
					( Origin gFrontEnd )
				)
				( attribute "CHIPS_PART_NAME" "CAP"
					( Origin gPackager )
				)
				( attribute "CDS_PART_NAME" "CAP_1210-47UF,16V,20%,X6S,D384A"
					( Origin gPackager )
				)
				( objectStatus "C7E12" )
				( pin "a"
					( attribute "PN" "1"
						( Origin gPackager )
					)
					( objectStatus "C7E12.1" )
				)
				( pin "b"
					( attribute "PN" "2"
						( Origin gPackager )
					)
					( objectStatus "C7E12.2" )
				)
			)
			( gate "@baseboard_fab2_lib.baseboard_fab2(sch_1):page241_i50"
				( attribute "BOM_COST" "P5V_STBY_VR"
					( Origin gFrontEnd )
				)
				( attribute "CDS_LIB" "mstr_discrete"
					( Origin gPackager )
				)
				( attribute "CDS_LOCATION" "R7F1"
					( Origin gPackager )
				)
				( attribute "CDS_SEC" "1"
					( Origin gPackager )
				)
				( attribute "LOCATION" "R7F1"
					( Origin gFrontEnd )
				)
				( attribute "MATERIAL" "CHIP"
					( Origin gFrontEnd )
				)
				( attribute "PACK_TYPE" "0402"
					( Origin gFrontEnd )
				)
				( attribute "PART_NUMBER" "G21796-016"
					( Origin gFrontEnd )
				)
				( attribute "PHYS_PAGE" "241"
					( Origin gFrontEnd )
				)
				( attribute "REUSE_ID" "9"
					( Origin gFrontEnd )
				)
				( attribute "ROOM" "P5V_STBY_VR"
					( Origin gFrontEnd )
				)
				( attribute "ROT" "0"
					( Origin gFrontEnd )
				)
				( attribute "SEC" "1"
					( Origin gFrontEnd )
				)
				( attribute "SEC_TYPE" "0402"
					( Origin gFrontEnd )
				)
				( attribute "SPOF" "TRUE"
					( Origin gFrontEnd )
				)
				( attribute "TOLERANCE" "1%"
					( Origin gFrontEnd )
				)
				( attribute "VALUE" "10.0K"
					( Origin gFrontEnd )
				)
				( attribute "VER" "2"
					( Origin gFrontEnd )
				)
				( attribute "WATTAGE" "1/16W"
					( Origin gFrontEnd )
				)
				( attribute "XY" "(1750,3425)"
					( Origin gFrontEnd )
				)
				( attribute "CHIPS_PART_NAME" "RES"
					( Origin gPackager )
				)
				( attribute "CDS_PART_NAME" "RES_0402-10.0K,1%,1/16W,CHIP,GA"
					( Origin gPackager )
				)
				( objectStatus "R7F1" )
				( pin "a"
					( attribute "PN" "1"
						( Origin gPackager )
					)
					( objectStatus "R7F1.1" )
				)
				( pin "b"
					( attribute "PN" "2"
						( Origin gPackager )
					)
					( objectStatus "R7F1.2" )
				)
			)
			( gate "@baseboard_fab2_lib.baseboard_fab2(sch_1):page241_i51"
				( attribute "BOM_COST" "P5V_STBY_VR"
					( Origin gFrontEnd )
				)
				( attribute "CDS_LIB" "mstr_discrete"
					( Origin gPackager )
				)
				( attribute "CDS_LOCATION" "R7E16"
					( Origin gPackager )
				)
				( attribute "CDS_SEC" "1"
					( Origin gPackager )
				)
				( attribute "LOCATION" "R7E16"
					( Origin gFrontEnd )
				)
				( attribute "MATERIAL" "CHIP"
					( Origin gFrontEnd )
				)
				( attribute "PACK_TYPE" "0402"
					( Origin gFrontEnd )
				)
				( attribute "PART_NUMBER" "G21796-095"
					( Origin gFrontEnd )
				)
				( attribute "PHYS_PAGE" "241"
					( Origin gFrontEnd )
				)
				( attribute "REUSE_ID" "7"
					( Origin gFrontEnd )
				)
				( attribute "ROOM" "P5V_STBY_VR"
					( Origin gFrontEnd )
				)
				( attribute "ROT" "0"
					( Origin gFrontEnd )
				)
				( attribute "SEC" "1"
					( Origin gFrontEnd )
				)
				( attribute "SEC_TYPE" "0402"
					( Origin gFrontEnd )
				)
				( attribute "SPOF" "TRUE"
					( Origin gFrontEnd )
				)
				( attribute "TOLERANCE" "1%"
					( Origin gFrontEnd )
				)
				( attribute "VALUE" "1.37K"
					( Origin gFrontEnd )
				)
				( attribute "VER" "2"
					( Origin gFrontEnd )
				)
				( attribute "WATTAGE" "1/16W"
					( Origin gFrontEnd )
				)
				( attribute "XY" "(1750,2900)"
					( Origin gFrontEnd )
				)
				( attribute "CHIPS_PART_NAME" "RES"
					( Origin gPackager )
				)
				( attribute "CDS_PART_NAME" "RES_0402-1.37K,1%,1/16W,CHIP,GA"
					( Origin gPackager )
				)
				( objectStatus "R7E16" )
				( pin "a"
					( attribute "PN" "1"
						( Origin gPackager )
					)
					( objectStatus "R7E16.1" )
				)
				( pin "b"
					( attribute "PN" "2"
						( Origin gPackager )
					)
					( objectStatus "R7E16.2" )
				)
			)
			( gate "@baseboard_fab2_lib.baseboard_fab2(sch_1):page241_i53"
				( attribute "BOM_COST" "P5V_STBY_VR"
					( Origin gFrontEnd )
				)
				( attribute "CDS_LIB" "mstr_discrete"
					( Origin gPackager )
				)
				( attribute "CDS_LOCATION" "C8E16"
					( Origin gPackager )
				)
				( attribute "CDS_SEC" "1"
					( Origin gPackager )
				)
				( attribute "LOCATION" "C8E16"
					( Origin gFrontEnd )
				)
				( attribute "MATERIAL" "X7R"
					( Origin gFrontEnd )
				)
				( attribute "PACK_TYPE" "0402LF"
					( Origin gFrontEnd )
				)
				( attribute "PART_NUMBER" "A36096-065"
					( Origin gFrontEnd )
				)
				( attribute "PHYS_PAGE" "241"
					( Origin gFrontEnd )
				)
				( attribute "REUSE_ID" "4"
					( Origin gFrontEnd )
				)
				( attribute "ROOM" "P5V_STBY_VR"
					( Origin gFrontEnd )
				)
				( attribute "ROT" "0"
					( Origin gFrontEnd )
				)
				( attribute "SEC" "1"
					( Origin gFrontEnd )
				)
				( attribute "SEC_TYPE" "0402LF"
					( Origin gFrontEnd )
				)
				( attribute "TOLERANCE" "10%"
					( Origin gFrontEnd )
				)
				( attribute "VALUE" "270PF"
					( Origin gFrontEnd )
				)
				( attribute "VER" "2"
					( Origin gFrontEnd )
				)
				( attribute "VOLTAGE" "50V"
					( Units "uVoltage" "V" 1.000000)
					( Origin gFrontEnd )
				)
				( attribute "XY" "(200,2575)"
					( Origin gFrontEnd )
				)
				( attribute "CHIPS_PART_NAME" "CAP"
					( Origin gPackager )
				)
				( attribute "CDS_PART_NAME" "CAP_0402LF-270PF,50V,10%,X7R,AA"
					( Origin gPackager )
				)
				( objectStatus "C8E16" )
				( pin "a"
					( attribute "PN" "1"
						( Origin gPackager )
					)
					( objectStatus "C8E16.1" )
				)
				( pin "b"
					( attribute "PN" "2"
						( Origin gPackager )
					)
					( objectStatus "C8E16.2" )
				)
			)
			( gate "@baseboard_fab2_lib.baseboard_fab2(sch_1):page241_i54"
				( attribute "BOM_COST" "P5V_STBY_VR"
					( Origin gFrontEnd )
				)
				( attribute "CDS_LIB" "mstr_discrete"
					( Origin gPackager )
				)
				( attribute "CDS_LOCATION" "R8E39"
					( Origin gPackager )
				)
				( attribute "CDS_SEC" "1"
					( Origin gPackager )
				)
				( attribute "LOCATION" "R8E39"
					( Origin gFrontEnd )
				)
				( attribute "MATERIAL" "CHIP"
					( Origin gFrontEnd )
				)
				( attribute "PACK_TYPE" "0402"
					( Origin gFrontEnd )
				)
				( attribute "PART_NUMBER" "G21796-254"
					( Origin gFrontEnd )
				)
				( attribute "PHYS_PAGE" "241"
					( Origin gFrontEnd )
				)
				( attribute "REUSE_ID" "10"
					( Origin gFrontEnd )
				)
				( attribute "ROOM" "P5V_STBY_VR"
					( Origin gFrontEnd )
				)
				( attribute "ROT" "0"
					( Origin gFrontEnd )
				)
				( attribute "SEC" "1"
					( Origin gFrontEnd )
				)
				( attribute "SEC_TYPE" "0402"
					( Origin gFrontEnd )
				)
				( attribute "TOLERANCE" "1%"
					( Origin gFrontEnd )
				)
				( attribute "VALUE" "24.9K"
					( Origin gFrontEnd )
				)
				( attribute "VER" "1"
					( Origin gFrontEnd )
				)
				( attribute "WATTAGE" "1/16W"
					( Origin gFrontEnd )
				)
				( attribute "XY" "(-200,2200)"
					( Origin gFrontEnd )
				)
				( attribute "CHIPS_PART_NAME" "RES"
					( Origin gPackager )
				)
				( attribute "CDS_PART_NAME" "RES_0402-24.9K,1%,1/16W,CHIP,GA"
					( Origin gPackager )
				)
				( objectStatus "R8E39" )
				( pin "a"
					( attribute "PN" "1"
						( Origin gPackager )
					)
					( objectStatus "R8E39.1" )
				)
				( pin "b"
					( attribute "PN" "2"
						( Origin gPackager )
					)
					( objectStatus "R8E39.2" )
				)
			)
			( gate "@baseboard_fab2_lib.baseboard_fab2(sch_1):page241_i57"
				( attribute "BOM_COST" "P5V_STBY_VR"
					( Origin gFrontEnd )
				)
				( attribute "CDS_LIB" "mstr_discrete"
					( Origin gPackager )
				)
				( attribute "CDS_LOCATION" "C8F1"
					( Origin gPackager )
				)
				( attribute "CDS_SEC" "1"
					( Origin gPackager )
				)
				( attribute "LOCATION" "C8F1"
					( Origin gFrontEnd )
				)
				( attribute "MATERIAL" "X7R"
					( Origin gFrontEnd )
				)
				( attribute "PACK_TYPE" "0402LF"
					( Origin gFrontEnd )
				)
				( attribute "PART_NUMBER" "A36096-075"
					( Origin gFrontEnd )
				)
				( attribute "PHYS_PAGE" "241"
					( Origin gFrontEnd )
				)
				( attribute "REUSE_ID" "5"
					( Origin gFrontEnd )
				)
				( attribute "ROOM" "P5V_STBY_VR"
					( Origin gFrontEnd )
				)
				( attribute "ROT" "0"
					( Origin gFrontEnd )
				)
				( attribute "SEC" "1"
					( Origin gFrontEnd )
				)
				( attribute "SEC_TYPE" "0402LF"
					( Origin gFrontEnd )
				)
				( attribute "TOLERANCE" "10%"
					( Origin gFrontEnd )
				)
				( attribute "VALUE" "2200PF"
					( Origin gFrontEnd )
				)
				( attribute "VER" "2"
					( Origin gFrontEnd )
				)
				( attribute "VOLTAGE" "50V"
					( Units "uVoltage" "V" 1.000000)
					( Origin gFrontEnd )
				)
				( attribute "XY" "(575,2200)"
					( Origin gFrontEnd )
				)
				( attribute "CHIPS_PART_NAME" "CAP"
					( Origin gPackager )
				)
				( attribute "CDS_PART_NAME" "CAP_0402LF-2200PF,50V,10%,X7R,A"
					( Origin gPackager )
				)
				( objectStatus "C8F1" )
				( pin "a"
					( attribute "PN" "1"
						( Origin gPackager )
					)
					( objectStatus "C8F1.1" )
				)
				( pin "b"
					( attribute "PN" "2"
						( Origin gPackager )
					)
					( objectStatus "C8F1.2" )
				)
			)
			( gate "@baseboard_fab2_lib.baseboard_fab2(sch_1):page241_i58"
				( attribute "BOM_COST" "P5V_STBY_VR"
					( Origin gFrontEnd )
				)
				( attribute "CDS_LIB" "mstr_discrete"
					( Origin gPackager )
				)
				( attribute "CDS_LOCATION" "R7E13"
					( Origin gPackager )
				)
				( attribute "CDS_SEC" "1"
					( Origin gPackager )
				)
				( attribute "LOCATION" "R7E13"
					( Origin gFrontEnd )
				)
				( attribute "MATERIAL" "CHIP"
					( Origin gFrontEnd )
				)
				( attribute "PACK_TYPE" "0402"
					( Origin gFrontEnd )
				)
				( attribute "PART_NUMBER" "G21497-005"
					( Origin gFrontEnd )
				)
				( attribute "PHYS_PAGE" "241"
					( Origin gFrontEnd )
				)
				( attribute "REUSE_ID" "13"
					( Origin gPackager )
				)
				( attribute "ROOM" "P5V_STBY_VR"
					( Origin gFrontEnd )
				)
				( attribute "ROT" "0"
					( Origin gFrontEnd )
				)
				( attribute "SEC" "1"
					( Origin gFrontEnd )
				)
				( attribute "SEC_TYPE" "0402"
					( Origin gFrontEnd )
				)
				( attribute "SPOF" "TRUE"
					( Origin gFrontEnd )
				)
				( attribute "TOLERANCE" "5%"
					( Origin gFrontEnd )
				)
				( attribute "VALUE" "0.0"
					( Origin gFrontEnd )
				)
				( attribute "VER" "1"
					( Origin gFrontEnd )
				)
				( attribute "WATTAGE" "1/16W"
					( Origin gFrontEnd )
				)
				( attribute "XY" "(1575,1550)"
					( Origin gFrontEnd )
				)
				( attribute "CHIPS_PART_NAME" "RES"
					( Origin gPackager )
				)
				( attribute "CDS_PART_NAME" "RES_0402-0.0,5%,1/16W,CHIP,G21A"
					( Origin gPackager )
				)
				( objectStatus "R7E13" )
				( pin "a"
					( attribute "PN" "1"
						( Origin gPackager )
					)
					( objectStatus "R7E13.1" )
				)
				( pin "b"
					( attribute "PN" "2"
						( Origin gPackager )
					)
					( objectStatus "R7E13.2" )
				)
			)
			( gate "@baseboard_fab2_lib.baseboard_fab2(sch_1):page241_i63"
				( attribute "BOM_COST" "P5V_STBY_VR"
					( Origin gFrontEnd )
				)
				( attribute "CDS_LIB" "mstr_discrete"
					( Origin gPackager )
				)
				( attribute "CDS_LOCATION" "C8E15"
					( Origin gPackager )
				)
				( attribute "CDS_SEC" "1"
					( Origin gPackager )
				)
				( attribute "LOCATION" "C8E15"
					( Origin gFrontEnd )
				)
				( attribute "MATERIAL" "X7R"
					( Origin gFrontEnd )
				)
				( attribute "PACK_TYPE" "0402LF"
					( Origin gFrontEnd )
				)
				( attribute "PART_NUMBER" "A36096-073"
					( Origin gFrontEnd )
				)
				( attribute "PHYS_PAGE" "241"
					( Origin gFrontEnd )
				)
				( attribute "REUSE_ID" "16"
					( Origin gFrontEnd )
				)
				( attribute "ROOM" "P5V_STBY_VR"
					( Origin gFrontEnd )
				)
				( attribute "ROT" "2"
					( Origin gFrontEnd )
				)
				( attribute "SEC" "1"
					( Origin gFrontEnd )
				)
				( attribute "SEC_TYPE" "0402LF"
					( Origin gFrontEnd )
				)
				( attribute "TOLERANCE" "10%"
					( Origin gFrontEnd )
				)
				( attribute "VALUE" "0.022UF"
					( Origin gFrontEnd )
				)
				( attribute "VER" "1"
					( Origin gFrontEnd )
				)
				( attribute "VOLTAGE" "16V"
					( Units "uVoltage" "V" 1.000000)
					( Origin gFrontEnd )
				)
				( attribute "XY" "(-1025,3000)"
					( Origin gFrontEnd )
				)
				( attribute "CHIPS_PART_NAME" "CAP"
					( Origin gPackager )
				)
				( attribute "CDS_PART_NAME" "CAP_0402LF-0.022UF,16V,10%,X7RA"
					( Origin gPackager )
				)
				( objectStatus "C8E15" )
				( pin "a"
					( attribute "PN" "1"
						( Origin gPackager )
					)
					( objectStatus "C8E15.1" )
				)
				( pin "b"
					( attribute "PN" "2"
						( Origin gPackager )
					)
					( objectStatus "C8E15.2" )
				)
			)
			( gate "@baseboard_fab2_lib.baseboard_fab2(sch_1):page241_i78"
				( attribute "BOM_COST" "P5V_STBY_VR"
					( Origin gFrontEnd )
				)
				( attribute "CDS_LIB" "mstr_discrete"
					( Origin gPackager )
				)
				( attribute "CDS_LOCATION" "R8E37"
					( Origin gPackager )
				)
				( attribute "CDS_SEC" "1"
					( Origin gPackager )
				)
				( attribute "LOCATION" "R8E37"
					( Origin gFrontEnd )
				)
				( attribute "MATERIAL" "CHIP"
					( Origin gFrontEnd )
				)
				( attribute "PACK_TYPE" "0402"
					( Origin gFrontEnd )
				)
				( attribute "PART_NUMBER" "G21497-005"
					( Origin gFrontEnd )
				)
				( attribute "PHYS_PAGE" "241"
					( Origin gFrontEnd )
				)
				( attribute "ROOM" "P5V_STBY_VR"
					( Origin gFrontEnd )
				)
				( attribute "ROT" "0"
					( Origin gFrontEnd )
				)
				( attribute "SEC" "1"
					( Origin gFrontEnd )
				)
				( attribute "SEC_TYPE" "0402"
					( Origin gFrontEnd )
				)
				( attribute "SPOF" "TRUE"
					( Origin gFrontEnd )
				)
				( attribute "TOLERANCE" "5%"
					( Origin gFrontEnd )
				)
				( attribute "VALUE" "0.0"
					( Origin gFrontEnd )
				)
				( attribute "VER" "1"
					( Origin gFrontEnd )
				)
				( attribute "WATTAGE" "1/16W"
					( Origin gFrontEnd )
				)
				( attribute "XY" "(2075,3650)"
					( Origin gFrontEnd )
				)
				( attribute "CHIPS_PART_NAME" "RES"
					( Origin gPackager )
				)
				( attribute "CDS_PART_NAME" "RES_0402-0.0,5%,1/16W,CHIP,G21A"
					( Origin gPackager )
				)
				( objectStatus "R8E37" )
				( pin "a"
					( attribute "PN" "1"
						( Origin gPackager )
					)
					( objectStatus "R8E37.1" )
				)
				( pin "b"
					( attribute "PN" "2"
						( Origin gPackager )
					)
					( objectStatus "R8E37.2" )
				)
			)
			( gate "@baseboard_fab2_lib.baseboard_fab2(sch_1):page241_i82"
				( attribute "BOM_COST" "P5V_STBY_VR"
					( Origin gFrontEnd )
				)
				( attribute "CDS_LIB" "mstr_discrete"
					( Origin gPackager )
				)
				( attribute "CDS_LOCATION" "FB7E1"
					( Origin gPackager )
				)
				( attribute "CDS_SEC" "1"
					( Origin gPackager )
				)
				( attribute "LOCATION" "FB7E1"
					( Origin gFrontEnd )
				)
				( attribute "MATERIAL" "FB"
					( Origin gFrontEnd )
				)
				( attribute "PACK_TYPE" "SM"
					( Origin gFrontEnd )
				)
				( attribute "PART_NUMBER" "656554-051"
					( Origin gFrontEnd )
				)
				( attribute "PHYS_PAGE" "241"
					( Origin gFrontEnd )
				)
				( attribute "ROOM" "P5V_STBY_VR"
					( Origin gFrontEnd )
				)
				( attribute "ROT" "0"
					( Origin gFrontEnd )
				)
				( attribute "SEC" "1"
					( Origin gPackager )
				)
				( attribute "VALUE" "22"
					( Origin gFrontEnd )
				)
				( attribute "VER" "1"
					( Origin gFrontEnd )
				)
				( attribute "XY" "(-3300,4675)"
					( Origin gFrontEnd )
				)
				( attribute "CHIPS_PART_NAME" "FERRITE"
					( Origin gPackager )
				)
				( attribute "CDS_PART_NAME" "FERRITE_SM-22,FB,656554-051"
					( Origin gPackager )
				)
				( objectStatus "FB7E1" )
				( pin "a"
					( attribute "PN" "1"
						( Origin gPackager )
					)
					( objectStatus "FB7E1.1" )
				)
				( pin "b"
					( attribute "PN" "2"
						( Origin gPackager )
					)
					( objectStatus "FB7E1.2" )
				)
			)
			( gate "@baseboard_fab2_lib.baseboard_fab2(sch_1):page241_i83"
				( attribute "BOM_COST" "P5V_STBY_VR"
					( Origin gFrontEnd )
				)
				( attribute "CDS_LIB" "mstr_vreg"
					( Origin gPackager )
				)
				( attribute "CDS_LOCATION" "EU7E2"
					( Origin gPackager )
				)
				( attribute "CDS_SEC" "1"
					( Origin gPackager )
				)
				( attribute "LOCATION" "EU7E2"
					( Origin gFrontEnd )
				)
				( attribute "MATERIAL" "IC"
					( Origin gFrontEnd )
				)
				( attribute "PACK_TYPE" "LCC"
					( Origin gFrontEnd )
				)
				( attribute "PART_NUMBER" "H63269-001"
					( Origin gFrontEnd )
				)
				( attribute "PHYS_PAGE" "241"
					( Origin gFrontEnd )
				)
				( attribute "ROOM" "P5V_STBY_VR"
					( Origin gFrontEnd )
				)
				( attribute "ROT" "0"
					( Origin gFrontEnd )
				)
				( attribute "SEC" "1"
					( Origin gFrontEnd )
				)
				( attribute "SEC_TYPE" "LCC"
					( Origin gFrontEnd )
				)
				( attribute "VER" "1"
					( Origin gFrontEnd )
				)
				( attribute "XY" "(125,3575)"
					( Origin gFrontEnd )
				)
				( attribute "CHIPS_PART_NAME" "TPS54821"
					( Origin gPackager )
				)
				( attribute "CDS_PART_NAME" "TPS54821_LCC-IC,H63269-001"
					( Origin gPackager )
				)
				( objectStatus "EU7E2" )
				( pin "boot"
					( attribute "PN" "13"
						( Origin gPackager )
					)
					( objectStatus "EU7E2.13" )
				)
				( pin "comp"
					( attribute "PN" "8"
						( Origin gPackager )
					)
					( objectStatus "EU7E2.8" )
				)
				( pin "en"
					( attribute "PN" "10"
						( Origin gPackager )
					)
					( objectStatus "EU7E2.10" )
				)
				( pin "gnd(0)"
					( attribute "PN" "2"
						( Origin gPackager )
					)
					( objectStatus "EU7E2.2" )
				)
				( pin "gnd(1)"
					( attribute "PN" "3"
						( Origin gPackager )
					)
					( objectStatus "EU7E2.3" )
				)
				( pin "ph(0)"
					( attribute "PN" "11"
						( Origin gPackager )
					)
					( objectStatus "EU7E2.11" )
				)
				( pin "ph(1)"
					( attribute "PN" "12"
						( Origin gPackager )
					)
					( objectStatus "EU7E2.12" )
				)
				( pin "pvin(0)"
					( attribute "PN" "4"
						( Origin gPackager )
					)
					( objectStatus "EU7E2.4" )
				)
				( pin "pvin(1)"
					( attribute "PN" "5"
						( Origin gPackager )
					)
					( objectStatus "EU7E2.5" )
				)
				( pin "pwrgd"
					( attribute "PN" "14"
						( Origin gPackager )
					)
					( objectStatus "EU7E2.14" )
				)
				( pin "rt_clk"
					( attribute "PN" "1"
						( Origin gPackager )
					)
					( objectStatus "EU7E2.1" )
				)
				( pin "ss_tr"
					( attribute "PN" "9"
						( Origin gPackager )
					)
					( objectStatus "EU7E2.9" )
				)
				( pin "thpad"
					( attribute "PN" "15"
						( Origin gPackager )
					)
					( objectStatus "EU7E2.15" )
				)
				( pin "vin"
					( attribute "PN" "6"
						( Origin gPackager )
					)
					( objectStatus "EU7E2.6" )
				)
				( pin "vsense"
					( attribute "PN" "7"
						( Origin gPackager )
					)
					( objectStatus "EU7E2.7" )
				)
			)
			( gate "@baseboard_fab2_lib.baseboard_fab2(sch_1):page241_i89"
				( attribute "CDS_LIB" "mstr_discrete"
					( Origin gPackager )
				)
				( attribute "CDS_LOCATION" "R7E15"
					( Origin gPackager )
				)
				( attribute "CDS_SEC" "1"
					( Origin gPackager )
				)
				( attribute "LOCATION" "R7E15"
					( Origin gFrontEnd )
				)
				( attribute "MATERIAL" "CHIP"
					( Origin gFrontEnd )
				)
				( attribute "PACK_TYPE" "0402"
					( Origin gFrontEnd )
				)
				( attribute "PART_NUMBER" "G21796-250"
					( Origin gFrontEnd )
				)
				( attribute "PHYS_PAGE" "241"
					( Origin gFrontEnd )
				)
				( attribute "ROOM" "P5V_STBY_VR"
					( Origin gFrontEnd )
				)
				( attribute "ROT" "0"
					( Origin gFrontEnd )
				)
				( attribute "SEC" "1"
					( Origin gFrontEnd )
				)
				( attribute "SEC_TYPE" "0402"
					( Origin gFrontEnd )
				)
				( attribute "TOLERANCE" "1.0%"
					( Origin gFrontEnd )
				)
				( attribute "VALUE" "22.1"
					( Origin gFrontEnd )
				)
				( attribute "VER" "1"
					( Origin gFrontEnd )
				)
				( attribute "WATTAGE" "1/16W"
					( Origin gFrontEnd )
				)
				( attribute "XY" "(2250,4625)"
					( Origin gFrontEnd )
				)
				( attribute "CHIPS_PART_NAME" "RES"
					( Origin gPackager )
				)
				( attribute "CDS_PART_NAME" "RES_0402-22.1,1.0%,1/16W,CHIP,A"
					( Origin gPackager )
				)
				( objectStatus "R7E15" )
				( pin "a"
					( attribute "PN" "1"
						( Origin gPackager )
					)
					( objectStatus "R7E15.1" )
				)
				( pin "b"
					( attribute "PN" "2"
						( Origin gPackager )
					)
					( objectStatus "R7E15.2" )
				)
			)
			( gate "@baseboard_fab2_lib.baseboard_fab2(sch_1):page241_i90"
				( attribute "CDS_LIB" "mstr_discrete"
					( Origin gPackager )
				)
				( attribute "CDS_LOCATION" "L8E1"
					( Origin gPackager )
				)
				( attribute "CDS_SEC" "1"
					( Origin gPackager )
				)
				( attribute "LOCATION" "L8E1"
					( Origin gFrontEnd )
				)
				( attribute "MATERIAL" "IND"
					( Origin gFrontEnd )
				)
				( attribute "PACK_TYPE" "SM"
					( Origin gFrontEnd )
				)
				( attribute "PART_NUMBER" "E98761-003"
					( Origin gFrontEnd )
				)
				( attribute "PHYS_PAGE" "241"
					( Origin gFrontEnd )
				)
				( attribute "ROT" "0"
					( Origin gFrontEnd )
				)
				( attribute "SEC" "1"
					( Origin gPackager )
				)
				( attribute "VALUE" "2.2UH"
					( Origin gFrontEnd )
				)
				( attribute "VER" "1"
					( Origin gFrontEnd )
				)
				( attribute "XY" "(2150,4075)"
					( Origin gFrontEnd )
				)
				( attribute "CHIPS_PART_NAME" "INDUCTOR"
					( Origin gPackager )
				)
				( attribute "CDS_PART_NAME" "INDUCTOR_SM-2.2UH,IND,E98761-0A"
					( Origin gPackager )
				)
				( objectStatus "L8E1" )
				( pin "ina"
					( attribute "PN" "1"
						( Origin gPackager )
					)
					( objectStatus "L8E1.1" )
				)
				( pin "inb"
					( attribute "PN" "2"
						( Origin gPackager )
					)
					( objectStatus "L8E1.2" )
				)
			)
			( gate "@baseboard_fab2_lib.baseboard_fab2(sch_1):page241_i91"
				( attribute "CDS_LIB" "mstr_discrete"
					( Origin gPackager )
				)
				( attribute "CDS_LOCATION" "R8E33"
					( Origin gPackager )
				)
				( attribute "CDS_SEC" "1"
					( Origin gPackager )
				)
				( attribute "LOCATION" "R8E33"
					( Origin gFrontEnd )
				)
				( attribute "MATERIAL" "CHIP"
					( Origin gFrontEnd )
				)
				( attribute "PACK_TYPE" "0402"
					( Origin gFrontEnd )
				)
				( attribute "PART_NUMBER" "G21497-005"
					( Origin gFrontEnd )
				)
				( attribute "PHYS_PAGE" "241"
					( Origin gFrontEnd )
				)
				( attribute "ROOM" "PVCCIN_CPU0_VR"
					( Origin gFrontEnd )
				)
				( attribute "ROT" "0"
					( Origin gFrontEnd )
				)
				( attribute "SEC" "1"
					( Origin gFrontEnd )
				)
				( attribute "SEC_TYPE" "0402"
					( Origin gFrontEnd )
				)
				( attribute "TOLERANCE" "5%"
					( Origin gFrontEnd )
				)
				( attribute "VALUE" "0.0"
					( Origin gFrontEnd )
				)
				( attribute "VER" "1"
					( Origin gFrontEnd )
				)
				( attribute "WATTAGE" "1/16W"
					( Origin gFrontEnd )
				)
				( attribute "XY" "(-1625,3475)"
					( Origin gFrontEnd )
				)
				( attribute "CHIPS_PART_NAME" "RES"
					( Origin gPackager )
				)
				( attribute "CDS_PART_NAME" "RES_0402-0.0,5%,1/16W,CHIP,G21A"
					( Origin gPackager )
				)
				( objectStatus "R8E33" )
				( pin "a"
					( attribute "PN" "1"
						( Origin gPackager )
					)
					( objectStatus "R8E33.1" )
				)
				( pin "b"
					( attribute "PN" "2"
						( Origin gPackager )
					)
					( objectStatus "R8E33.2" )
				)
			)
			( gate "@baseboard_fab2_lib.baseboard_fab2(sch_1):page243_i88"
				( attribute "CDS_LIB" "dev_discrete"
					( Origin gPackager )
				)
				( attribute "LOCATION" "C5G106"
					( Origin gFrontEnd )
				)
				( attribute "MATERIAL" "X6S"
					( Origin gFrontEnd )
				)
				( attribute "PACK_TYPE" "0603V"
					( Origin gFrontEnd )
				)
				( attribute "PART_NUMBER" "E15431-004"
					( Origin gFrontEnd )
				)
				( attribute "PHYS_PAGE" "243"
					( Origin gFrontEnd )
				)
				( attribute "ROOM" "PVDDQ_KLM"
					( Origin gFrontEnd )
				)
				( attribute "ROT" "0"
					( Origin gFrontEnd )
				)
				( attribute "TOLERANCE" "20%"
					( Origin gFrontEnd )
				)
				( attribute "VALUE" "22.0UF"
					( Origin gFrontEnd )
				)
				( attribute "VER" "1"
					( Origin gFrontEnd )
				)
				( attribute "VOLTAGE" "4V"
					( Units "uVoltage" "V" 1.000000)
					( Origin gFrontEnd )
				)
				( attribute "XY" "(-3600,1475)"
					( Origin gFrontEnd )
				)
				( attribute "CHIPS_PART_NAME" "CAP_A"
					( Origin gPackager )
				)
				( attribute "CDS_PART_NAME" "CAP_A_0603V-22.0UF,4V,20%,X6S,A"
					( Origin gPackager )
				)
				( attribute "CDS_LOCATION" "C5G106"
					( Origin gPackager )
				)
				( attribute "CDS_SEC" "1"
					( Origin gPackager )
				)
				( attribute "SEC" "1"
					( Origin gPackager )
				)
				( attribute "SIDE_SKU" "1S"
					( Origin gFrontEnd )
				)
				( objectStatus "C5G106" )
				( pin "a"
					( attribute "PN" "1"
						( Origin gPackager )
					)
					( objectStatus "C5G106.1" )
				)
				( pin "b"
					( attribute "PN" "2"
						( Origin gPackager )
					)
					( objectStatus "C5G106.2" )
				)
			)
			( gate "@baseboard_fab2_lib.baseboard_fab2(sch_1):page243_i87"
				( attribute "CDS_LIB" "dev_discrete"
					( Origin gPackager )
				)
				( attribute "LOCATION" "C5G107"
					( Origin gFrontEnd )
				)
				( attribute "MATERIAL" "X6S"
					( Origin gFrontEnd )
				)
				( attribute "PACK_TYPE" "0603V"
					( Origin gFrontEnd )
				)
				( attribute "PART_NUMBER" "E15431-004"
					( Origin gFrontEnd )
				)
				( attribute "PHYS_PAGE" "243"
					( Origin gFrontEnd )
				)
				( attribute "ROOM" "PVDDQ_KLM"
					( Origin gFrontEnd )
				)
				( attribute "ROT" "0"
					( Origin gFrontEnd )
				)
				( attribute "TOLERANCE" "20%"
					( Origin gFrontEnd )
				)
				( attribute "VALUE" "22.0UF"
					( Origin gFrontEnd )
				)
				( attribute "VER" "1"
					( Origin gFrontEnd )
				)
				( attribute "VOLTAGE" "4V"
					( Units "uVoltage" "V" 1.000000)
					( Origin gFrontEnd )
				)
				( attribute "XY" "(-3300,1475)"
					( Origin gFrontEnd )
				)
				( attribute "CHIPS_PART_NAME" "CAP_A"
					( Origin gPackager )
				)
				( attribute "CDS_PART_NAME" "CAP_A_0603V-22.0UF,4V,20%,X6S,A"
					( Origin gPackager )
				)
				( attribute "CDS_LOCATION" "C5G107"
					( Origin gPackager )
				)
				( attribute "CDS_SEC" "1"
					( Origin gPackager )
				)
				( attribute "SEC" "1"
					( Origin gPackager )
				)
				( attribute "SIDE_SKU" "1S"
					( Origin gFrontEnd )
				)
				( objectStatus "C5G107" )
				( pin "a"
					( attribute "PN" "1"
						( Origin gPackager )
					)
					( objectStatus "C5G107.1" )
				)
				( pin "b"
					( attribute "PN" "2"
						( Origin gPackager )
					)
					( objectStatus "C5G107.2" )
				)
			)
			( gate "@baseboard_fab2_lib.baseboard_fab2(sch_1):page243_i86"
				( attribute "CDS_LIB" "dev_discrete"
					( Origin gPackager )
				)
				( attribute "LOCATION" "C5G108"
					( Origin gFrontEnd )
				)
				( attribute "MATERIAL" "X6S"
					( Origin gFrontEnd )
				)
				( attribute "PACK_TYPE" "0603V"
					( Origin gFrontEnd )
				)
				( attribute "PART_NUMBER" "E15431-004"
					( Origin gFrontEnd )
				)
				( attribute "PHYS_PAGE" "243"
					( Origin gFrontEnd )
				)
				( attribute "ROOM" "PVDDQ_KLM"
					( Origin gFrontEnd )
				)
				( attribute "ROT" "0"
					( Origin gFrontEnd )
				)
				( attribute "TOLERANCE" "20%"
					( Origin gFrontEnd )
				)
				( attribute "VALUE" "22.0UF"
					( Origin gFrontEnd )
				)
				( attribute "VER" "1"
					( Origin gFrontEnd )
				)
				( attribute "VOLTAGE" "4V"
					( Units "uVoltage" "V" 1.000000)
					( Origin gFrontEnd )
				)
				( attribute "XY" "(-3000,1475)"
					( Origin gFrontEnd )
				)
				( attribute "CHIPS_PART_NAME" "CAP_A"
					( Origin gPackager )
				)
				( attribute "CDS_PART_NAME" "CAP_A_0603V-22.0UF,4V,20%,X6S,A"
					( Origin gPackager )
				)
				( attribute "CDS_LOCATION" "C5G108"
					( Origin gPackager )
				)
				( attribute "CDS_SEC" "1"
					( Origin gPackager )
				)
				( attribute "SEC" "1"
					( Origin gPackager )
				)
				( attribute "SIDE_SKU" "1S"
					( Origin gFrontEnd )
				)
				( objectStatus "C5G108" )
				( pin "a"
					( attribute "PN" "1"
						( Origin gPackager )
					)
					( objectStatus "C5G108.1" )
				)
				( pin "b"
					( attribute "PN" "2"
						( Origin gPackager )
					)
					( objectStatus "C5G108.2" )
				)
			)
			( gate "@baseboard_fab2_lib.baseboard_fab2(sch_1):page243_i85"
				( attribute "CDS_LIB" "dev_discrete"
					( Origin gPackager )
				)
				( attribute "LOCATION" "C5G109"
					( Origin gFrontEnd )
				)
				( attribute "MATERIAL" "X6S"
					( Origin gFrontEnd )
				)
				( attribute "PACK_TYPE" "0603V"
					( Origin gFrontEnd )
				)
				( attribute "PART_NUMBER" "E15431-004"
					( Origin gFrontEnd )
				)
				( attribute "PHYS_PAGE" "243"
					( Origin gFrontEnd )
				)
				( attribute "ROOM" "PVDDQ_KLM"
					( Origin gFrontEnd )
				)
				( attribute "ROT" "0"
					( Origin gFrontEnd )
				)
				( attribute "TOLERANCE" "20%"
					( Origin gFrontEnd )
				)
				( attribute "VALUE" "22.0UF"
					( Origin gFrontEnd )
				)
				( attribute "VER" "1"
					( Origin gFrontEnd )
				)
				( attribute "VOLTAGE" "4V"
					( Units "uVoltage" "V" 1.000000)
					( Origin gFrontEnd )
				)
				( attribute "XY" "(-2650,1475)"
					( Origin gFrontEnd )
				)
				( attribute "CHIPS_PART_NAME" "CAP_A"
					( Origin gPackager )
				)
				( attribute "CDS_PART_NAME" "CAP_A_0603V-22.0UF,4V,20%,X6S,A"
					( Origin gPackager )
				)
				( attribute "CDS_LOCATION" "C5G109"
					( Origin gPackager )
				)
				( attribute "CDS_SEC" "1"
					( Origin gPackager )
				)
				( attribute "SEC" "1"
					( Origin gPackager )
				)
				( attribute "SIDE_SKU" "1S"
					( Origin gFrontEnd )
				)
				( objectStatus "C5G109" )
				( pin "a"
					( attribute "PN" "1"
						( Origin gPackager )
					)
					( objectStatus "C5G109.1" )
				)
				( pin "b"
					( attribute "PN" "2"
						( Origin gPackager )
					)
					( objectStatus "C5G109.2" )
				)
			)
			( gate "@baseboard_fab2_lib.baseboard_fab2(sch_1):page243_i84"
				( attribute "CDS_LIB" "dev_discrete"
					( Origin gPackager )
				)
				( attribute "LOCATION" "C5G110"
					( Origin gFrontEnd )
				)
				( attribute "MATERIAL" "X6S"
					( Origin gFrontEnd )
				)
				( attribute "PACK_TYPE" "0603V"
					( Origin gFrontEnd )
				)
				( attribute "PART_NUMBER" "E15431-004"
					( Origin gFrontEnd )
				)
				( attribute "PHYS_PAGE" "243"
					( Origin gFrontEnd )
				)
				( attribute "ROOM" "PVDDQ_KLM"
					( Origin gFrontEnd )
				)
				( attribute "ROT" "0"
					( Origin gFrontEnd )
				)
				( attribute "TOLERANCE" "20%"
					( Origin gFrontEnd )
				)
				( attribute "VALUE" "22.0UF"
					( Origin gFrontEnd )
				)
				( attribute "VER" "1"
					( Origin gFrontEnd )
				)
				( attribute "VOLTAGE" "4V"
					( Units "uVoltage" "V" 1.000000)
					( Origin gFrontEnd )
				)
				( attribute "XY" "(-2350,1475)"
					( Origin gFrontEnd )
				)
				( attribute "CHIPS_PART_NAME" "CAP_A"
					( Origin gPackager )
				)
				( attribute "CDS_PART_NAME" "CAP_A_0603V-22.0UF,4V,20%,X6S,A"
					( Origin gPackager )
				)
				( attribute "CDS_LOCATION" "C5G110"
					( Origin gPackager )
				)
				( attribute "CDS_SEC" "1"
					( Origin gPackager )
				)
				( attribute "SEC" "1"
					( Origin gPackager )
				)
				( attribute "SIDE_SKU" "1S"
					( Origin gFrontEnd )
				)
				( objectStatus "C5G110" )
				( pin "a"
					( attribute "PN" "1"
						( Origin gPackager )
					)
					( objectStatus "C5G110.1" )
				)
				( pin "b"
					( attribute "PN" "2"
						( Origin gPackager )
					)
					( objectStatus "C5G110.2" )
				)
			)
			( gate "@baseboard_fab2_lib.baseboard_fab2(sch_1):page242_i11"
				( attribute "BOM_COST" "MEM_VRD_PVDDQ_CD"
					( Origin gFrontEnd )
				)
				( attribute "CDS_LIB" "mstr_discrete"
					( Origin gPackager )
				)
				( attribute "CDS_LOCATION" "C5G21"
					( Origin gPackager )
				)
				( attribute "CDS_SEC" "1"
					( Origin gPackager )
				)
				( attribute "LOCATION" "C5G21"
					( Origin gFrontEnd )
				)
				( attribute "MATERIAL" "X5R"
					( Origin gFrontEnd )
				)
				( attribute "PACK_TYPE" "0805"
					( Origin gFrontEnd )
				)
				( attribute "PART_NUMBER" "602433-112"
					( Origin gFrontEnd )
				)
				( attribute "PHYS_PAGE" "242"
					( Origin gFrontEnd )
				)
				( attribute "ROOM" "VDDQ_KLM_PWR_VR"
					( Origin gFrontEnd )
				)
				( attribute "ROT" "0"
					( Origin gFrontEnd )
				)
				( attribute "SEC" "1"
					( Origin gPackager )
				)
				( attribute "TOLERANCE" "20%"
					( Origin gFrontEnd )
				)
				( attribute "VALUE" "100UF"
					( Origin gFrontEnd )
				)
				( attribute "VER" "1"
					( Origin gFrontEnd )
				)
				( attribute "VOLTAGE" "4V"
					( Units "uVoltage" "V" 1.000000)
					( Origin gFrontEnd )
				)
				( attribute "XY" "(-7400,3900)"
					( Origin gFrontEnd )
				)
				( attribute "CHIPS_PART_NAME" "CAP"
					( Origin gPackager )
				)
				( attribute "CDS_PART_NAME" "CAP_0805-100UF,4V,20%,X5R,6024A"
					( Origin gPackager )
				)
				( attribute "SIDE_SKU" "1S"
					( Origin gFrontEnd )
				)
				( objectStatus "C5G21" )
				( pin "a"
					( attribute "PN" "1"
						( Origin gPackager )
					)
					( objectStatus "C5G21.1" )
				)
				( pin "b"
					( attribute "PN" "2"
						( Origin gPackager )
					)
					( objectStatus "C5G21.2" )
				)
			)
			( gate "@baseboard_fab2_lib.baseboard_fab2(sch_1):page243_i83"
				( attribute "CDS_LIB" "dev_discrete"
					( Origin gPackager )
				)
				( attribute "LOCATION" "C5G111"
					( Origin gFrontEnd )
				)
				( attribute "MATERIAL" "X6S"
					( Origin gFrontEnd )
				)
				( attribute "PACK_TYPE" "0603V"
					( Origin gFrontEnd )
				)
				( attribute "PART_NUMBER" "E15431-004"
					( Origin gFrontEnd )
				)
				( attribute "PHYS_PAGE" "243"
					( Origin gFrontEnd )
				)
				( attribute "ROOM" "PVDDQ_KLM"
					( Origin gFrontEnd )
				)
				( attribute "ROT" "0"
					( Origin gFrontEnd )
				)
				( attribute "TOLERANCE" "20%"
					( Origin gFrontEnd )
				)
				( attribute "VALUE" "22.0UF"
					( Origin gFrontEnd )
				)
				( attribute "VER" "1"
					( Origin gFrontEnd )
				)
				( attribute "VOLTAGE" "4V"
					( Units "uVoltage" "V" 1.000000)
					( Origin gFrontEnd )
				)
				( attribute "XY" "(-2050,1475)"
					( Origin gFrontEnd )
				)
				( attribute "CHIPS_PART_NAME" "CAP_A"
					( Origin gPackager )
				)
				( attribute "CDS_PART_NAME" "CAP_A_0603V-22.0UF,4V,20%,X6S,A"
					( Origin gPackager )
				)
				( attribute "CDS_LOCATION" "C5G111"
					( Origin gPackager )
				)
				( attribute "CDS_SEC" "1"
					( Origin gPackager )
				)
				( attribute "SEC" "1"
					( Origin gPackager )
				)
				( attribute "SIDE_SKU" "1S"
					( Origin gFrontEnd )
				)
				( objectStatus "C5G111" )
				( pin "a"
					( attribute "PN" "1"
						( Origin gPackager )
					)
					( objectStatus "C5G111.1" )
				)
				( pin "b"
					( attribute "PN" "2"
						( Origin gPackager )
					)
					( objectStatus "C5G111.2" )
				)
			)
			( gate "@baseboard_fab2_lib.baseboard_fab2(sch_1):page243_i82"
				( attribute "CDS_LIB" "dev_discrete"
					( Origin gPackager )
				)
				( attribute "LOCATION" "C5G112"
					( Origin gFrontEnd )
				)
				( attribute "MATERIAL" "X6S"
					( Origin gFrontEnd )
				)
				( attribute "PACK_TYPE" "0603V"
					( Origin gFrontEnd )
				)
				( attribute "PART_NUMBER" "E15431-004"
					( Origin gFrontEnd )
				)
				( attribute "PHYS_PAGE" "243"
					( Origin gFrontEnd )
				)
				( attribute "ROOM" "PVDDQ_KLM"
					( Origin gFrontEnd )
				)
				( attribute "ROT" "0"
					( Origin gFrontEnd )
				)
				( attribute "TOLERANCE" "20%"
					( Origin gFrontEnd )
				)
				( attribute "VALUE" "22.0UF"
					( Origin gFrontEnd )
				)
				( attribute "VER" "1"
					( Origin gFrontEnd )
				)
				( attribute "VOLTAGE" "4V"
					( Units "uVoltage" "V" 1.000000)
					( Origin gFrontEnd )
				)
				( attribute "XY" "(-1750,1475)"
					( Origin gFrontEnd )
				)
				( attribute "CHIPS_PART_NAME" "CAP_A"
					( Origin gPackager )
				)
				( attribute "CDS_PART_NAME" "CAP_A_0603V-22.0UF,4V,20%,X6S,A"
					( Origin gPackager )
				)
				( attribute "CDS_LOCATION" "C5G112"
					( Origin gPackager )
				)
				( attribute "CDS_SEC" "1"
					( Origin gPackager )
				)
				( attribute "SEC" "1"
					( Origin gPackager )
				)
				( attribute "SIDE_SKU" "1S"
					( Origin gFrontEnd )
				)
				( objectStatus "C5G112" )
				( pin "a"
					( attribute "PN" "1"
						( Origin gPackager )
					)
					( objectStatus "C5G112.1" )
				)
				( pin "b"
					( attribute "PN" "2"
						( Origin gPackager )
					)
					( objectStatus "C5G112.2" )
				)
			)
			( gate "@baseboard_fab2_lib.baseboard_fab2(sch_1):page243_i81"
				( attribute "CDS_LIB" "dev_discrete"
					( Origin gPackager )
				)
				( attribute "LOCATION" "C5G113"
					( Origin gFrontEnd )
				)
				( attribute "MATERIAL" "X6S"
					( Origin gFrontEnd )
				)
				( attribute "PACK_TYPE" "0603V"
					( Origin gFrontEnd )
				)
				( attribute "PART_NUMBER" "E15431-004"
					( Origin gFrontEnd )
				)
				( attribute "PHYS_PAGE" "243"
					( Origin gFrontEnd )
				)
				( attribute "ROOM" "PVDDQ_KLM"
					( Origin gFrontEnd )
				)
				( attribute "ROT" "0"
					( Origin gFrontEnd )
				)
				( attribute "TOLERANCE" "20%"
					( Origin gFrontEnd )
				)
				( attribute "VALUE" "22.0UF"
					( Origin gFrontEnd )
				)
				( attribute "VER" "1"
					( Origin gFrontEnd )
				)
				( attribute "VOLTAGE" "4V"
					( Units "uVoltage" "V" 1.000000)
					( Origin gFrontEnd )
				)
				( attribute "XY" "(-1450,1475)"
					( Origin gFrontEnd )
				)
				( attribute "CHIPS_PART_NAME" "CAP_A"
					( Origin gPackager )
				)
				( attribute "CDS_PART_NAME" "CAP_A_0603V-22.0UF,4V,20%,X6S,A"
					( Origin gPackager )
				)
				( attribute "CDS_LOCATION" "C5G113"
					( Origin gPackager )
				)
				( attribute "CDS_SEC" "1"
					( Origin gPackager )
				)
				( attribute "SEC" "1"
					( Origin gPackager )
				)
				( attribute "SIDE_SKU" "1S"
					( Origin gFrontEnd )
				)
				( objectStatus "C5G113" )
				( pin "a"
					( attribute "PN" "1"
						( Origin gPackager )
					)
					( objectStatus "C5G113.1" )
				)
				( pin "b"
					( attribute "PN" "2"
						( Origin gPackager )
					)
					( objectStatus "C5G113.2" )
				)
			)
			( gate "@baseboard_fab2_lib.baseboard_fab2(sch_1):page242_i15"
				( attribute "BOM_COST" "MEM_VRD_PVDDQ_CD"
					( Origin gFrontEnd )
				)
				( attribute "CDS_LIB" "mstr_discrete"
					( Origin gPackager )
				)
				( attribute "CDS_LOCATION" "C5G22"
					( Origin gPackager )
				)
				( attribute "CDS_SEC" "1"
					( Origin gPackager )
				)
				( attribute "LOCATION" "C5G22"
					( Origin gFrontEnd )
				)
				( attribute "MATERIAL" "X5R"
					( Origin gFrontEnd )
				)
				( attribute "PACK_TYPE" "0805"
					( Origin gFrontEnd )
				)
				( attribute "PART_NUMBER" "602433-112"
					( Origin gFrontEnd )
				)
				( attribute "PHYS_PAGE" "242"
					( Origin gFrontEnd )
				)
				( attribute "ROOM" "VDDQ_KLM_PWR_VR"
					( Origin gFrontEnd )
				)
				( attribute "ROT" "0"
					( Origin gFrontEnd )
				)
				( attribute "SEC" "1"
					( Origin gPackager )
				)
				( attribute "TOLERANCE" "20%"
					( Origin gFrontEnd )
				)
				( attribute "VALUE" "100UF"
					( Origin gFrontEnd )
				)
				( attribute "VER" "1"
					( Origin gFrontEnd )
				)
				( attribute "VOLTAGE" "4V"
					( Units "uVoltage" "V" 1.000000)
					( Origin gFrontEnd )
				)
				( attribute "XY" "(-7000,3900)"
					( Origin gFrontEnd )
				)
				( attribute "CHIPS_PART_NAME" "CAP"
					( Origin gPackager )
				)
				( attribute "CDS_PART_NAME" "CAP_0805-100UF,4V,20%,X5R,6024A"
					( Origin gPackager )
				)
				( attribute "SIDE_SKU" "1S"
					( Origin gFrontEnd )
				)
				( objectStatus "C5G22" )
				( pin "a"
					( attribute "PN" "1"
						( Origin gPackager )
					)
					( objectStatus "C5G22.1" )
				)
				( pin "b"
					( attribute "PN" "2"
						( Origin gPackager )
					)
					( objectStatus "C5G22.2" )
				)
			)
			( gate "@baseboard_fab2_lib.baseboard_fab2(sch_1):page243_i80"
				( attribute "CDS_LIB" "dev_discrete"
					( Origin gPackager )
				)
				( attribute "LOCATION" "C5G114"
					( Origin gFrontEnd )
				)
				( attribute "MATERIAL" "X6S"
					( Origin gFrontEnd )
				)
				( attribute "PACK_TYPE" "0603V"
					( Origin gFrontEnd )
				)
				( attribute "PART_NUMBER" "E15431-004"
					( Origin gFrontEnd )
				)
				( attribute "PHYS_PAGE" "243"
					( Origin gFrontEnd )
				)
				( attribute "ROOM" "PVDDQ_KLM"
					( Origin gFrontEnd )
				)
				( attribute "ROT" "0"
					( Origin gFrontEnd )
				)
				( attribute "TOLERANCE" "20%"
					( Origin gFrontEnd )
				)
				( attribute "VALUE" "22.0UF"
					( Origin gFrontEnd )
				)
				( attribute "VER" "1"
					( Origin gFrontEnd )
				)
				( attribute "VOLTAGE" "4V"
					( Units "uVoltage" "V" 1.000000)
					( Origin gFrontEnd )
				)
				( attribute "XY" "(-1150,1475)"
					( Origin gFrontEnd )
				)
				( attribute "CHIPS_PART_NAME" "CAP_A"
					( Origin gPackager )
				)
				( attribute "CDS_PART_NAME" "CAP_A_0603V-22.0UF,4V,20%,X6S,A"
					( Origin gPackager )
				)
				( attribute "CDS_LOCATION" "C5G114"
					( Origin gPackager )
				)
				( attribute "CDS_SEC" "1"
					( Origin gPackager )
				)
				( attribute "SEC" "1"
					( Origin gPackager )
				)
				( attribute "SIDE_SKU" "1S"
					( Origin gFrontEnd )
				)
				( objectStatus "C5G114" )
				( pin "a"
					( attribute "PN" "1"
						( Origin gPackager )
					)
					( objectStatus "C5G114.1" )
				)
				( pin "b"
					( attribute "PN" "2"
						( Origin gPackager )
					)
					( objectStatus "C5G114.2" )
				)
			)
			( gate "@baseboard_fab2_lib.baseboard_fab2(sch_1):page243_i79"
				( attribute "CDS_LIB" "dev_discrete"
					( Origin gPackager )
				)
				( attribute "LOCATION" "C5G97"
					( Origin gFrontEnd )
				)
				( attribute "MATERIAL" "X6S"
					( Origin gFrontEnd )
				)
				( attribute "PACK_TYPE" "0603V"
					( Origin gFrontEnd )
				)
				( attribute "PART_NUMBER" "E15431-004"
					( Origin gFrontEnd )
				)
				( attribute "PHYS_PAGE" "243"
					( Origin gFrontEnd )
				)
				( attribute "ROOM" "PVDDQ_KLM"
					( Origin gFrontEnd )
				)
				( attribute "ROT" "0"
					( Origin gFrontEnd )
				)
				( attribute "TOLERANCE" "20%"
					( Origin gFrontEnd )
				)
				( attribute "VALUE" "22.0UF"
					( Origin gFrontEnd )
				)
				( attribute "VER" "1"
					( Origin gFrontEnd )
				)
				( attribute "VOLTAGE" "4V"
					( Units "uVoltage" "V" 1.000000)
					( Origin gFrontEnd )
				)
				( attribute "XY" "(-3600,2575)"
					( Origin gFrontEnd )
				)
				( attribute "CHIPS_PART_NAME" "CAP_A"
					( Origin gPackager )
				)
				( attribute "CDS_PART_NAME" "CAP_A_0603V-22.0UF,4V,20%,X6S,A"
					( Origin gPackager )
				)
				( attribute "CDS_LOCATION" "C5G97"
					( Origin gPackager )
				)
				( attribute "CDS_SEC" "1"
					( Origin gPackager )
				)
				( attribute "SEC" "1"
					( Origin gPackager )
				)
				( attribute "SIDE_SKU" "1S"
					( Origin gFrontEnd )
				)
				( objectStatus "C5G97" )
				( pin "a"
					( attribute "PN" "1"
						( Origin gPackager )
					)
					( objectStatus "C5G97.1" )
				)
				( pin "b"
					( attribute "PN" "2"
						( Origin gPackager )
					)
					( objectStatus "C5G97.2" )
				)
			)
			( gate "@baseboard_fab2_lib.baseboard_fab2(sch_1):page243_i78"
				( attribute "CDS_LIB" "dev_discrete"
					( Origin gPackager )
				)
				( attribute "LOCATION" "C5G98"
					( Origin gFrontEnd )
				)
				( attribute "MATERIAL" "X6S"
					( Origin gFrontEnd )
				)
				( attribute "PACK_TYPE" "0603V"
					( Origin gFrontEnd )
				)
				( attribute "PART_NUMBER" "E15431-004"
					( Origin gFrontEnd )
				)
				( attribute "PHYS_PAGE" "243"
					( Origin gFrontEnd )
				)
				( attribute "ROOM" "PVDDQ_KLM"
					( Origin gFrontEnd )
				)
				( attribute "ROT" "0"
					( Origin gFrontEnd )
				)
				( attribute "TOLERANCE" "20%"
					( Origin gFrontEnd )
				)
				( attribute "VALUE" "22.0UF"
					( Origin gFrontEnd )
				)
				( attribute "VER" "1"
					( Origin gFrontEnd )
				)
				( attribute "VOLTAGE" "4V"
					( Units "uVoltage" "V" 1.000000)
					( Origin gFrontEnd )
				)
				( attribute "XY" "(-3300,2575)"
					( Origin gFrontEnd )
				)
				( attribute "CHIPS_PART_NAME" "CAP_A"
					( Origin gPackager )
				)
				( attribute "CDS_PART_NAME" "CAP_A_0603V-22.0UF,4V,20%,X6S,A"
					( Origin gPackager )
				)
				( attribute "CDS_LOCATION" "C5G98"
					( Origin gPackager )
				)
				( attribute "CDS_SEC" "1"
					( Origin gPackager )
				)
				( attribute "SEC" "1"
					( Origin gPackager )
				)
				( attribute "SIDE_SKU" "1S"
					( Origin gFrontEnd )
				)
				( objectStatus "C5G98" )
				( pin "a"
					( attribute "PN" "1"
						( Origin gPackager )
					)
					( objectStatus "C5G98.1" )
				)
				( pin "b"
					( attribute "PN" "2"
						( Origin gPackager )
					)
					( objectStatus "C5G98.2" )
				)
			)
			( gate "@baseboard_fab2_lib.baseboard_fab2(sch_1):page243_i77"
				( attribute "CDS_LIB" "dev_discrete"
					( Origin gPackager )
				)
				( attribute "LOCATION" "C5G99"
					( Origin gFrontEnd )
				)
				( attribute "MATERIAL" "X6S"
					( Origin gFrontEnd )
				)
				( attribute "PACK_TYPE" "0603V"
					( Origin gFrontEnd )
				)
				( attribute "PART_NUMBER" "E15431-004"
					( Origin gFrontEnd )
				)
				( attribute "PHYS_PAGE" "243"
					( Origin gFrontEnd )
				)
				( attribute "ROOM" "PVDDQ_KLM"
					( Origin gFrontEnd )
				)
				( attribute "ROT" "0"
					( Origin gFrontEnd )
				)
				( attribute "TOLERANCE" "20%"
					( Origin gFrontEnd )
				)
				( attribute "VALUE" "22.0UF"
					( Origin gFrontEnd )
				)
				( attribute "VER" "1"
					( Origin gFrontEnd )
				)
				( attribute "VOLTAGE" "4V"
					( Units "uVoltage" "V" 1.000000)
					( Origin gFrontEnd )
				)
				( attribute "XY" "(-3000,2575)"
					( Origin gFrontEnd )
				)
				( attribute "CHIPS_PART_NAME" "CAP_A"
					( Origin gPackager )
				)
				( attribute "CDS_PART_NAME" "CAP_A_0603V-22.0UF,4V,20%,X6S,A"
					( Origin gPackager )
				)
				( attribute "CDS_LOCATION" "C5G99"
					( Origin gPackager )
				)
				( attribute "CDS_SEC" "1"
					( Origin gPackager )
				)
				( attribute "SEC" "1"
					( Origin gPackager )
				)
				( attribute "SIDE_SKU" "1S"
					( Origin gFrontEnd )
				)
				( objectStatus "C5G99" )
				( pin "a"
					( attribute "PN" "1"
						( Origin gPackager )
					)
					( objectStatus "C5G99.1" )
				)
				( pin "b"
					( attribute "PN" "2"
						( Origin gPackager )
					)
					( objectStatus "C5G99.2" )
				)
			)
			( gate "@baseboard_fab2_lib.baseboard_fab2(sch_1):page243_i76"
				( attribute "CDS_LIB" "dev_discrete"
					( Origin gPackager )
				)
				( attribute "LOCATION" "C5G100"
					( Origin gFrontEnd )
				)
				( attribute "MATERIAL" "X6S"
					( Origin gFrontEnd )
				)
				( attribute "PACK_TYPE" "0603V"
					( Origin gFrontEnd )
				)
				( attribute "PART_NUMBER" "E15431-004"
					( Origin gFrontEnd )
				)
				( attribute "PHYS_PAGE" "243"
					( Origin gFrontEnd )
				)
				( attribute "ROOM" "PVDDQ_KLM"
					( Origin gFrontEnd )
				)
				( attribute "ROT" "0"
					( Origin gFrontEnd )
				)
				( attribute "TOLERANCE" "20%"
					( Origin gFrontEnd )
				)
				( attribute "VALUE" "22.0UF"
					( Origin gFrontEnd )
				)
				( attribute "VER" "1"
					( Origin gFrontEnd )
				)
				( attribute "VOLTAGE" "4V"
					( Units "uVoltage" "V" 1.000000)
					( Origin gFrontEnd )
				)
				( attribute "XY" "(-2650,2575)"
					( Origin gFrontEnd )
				)
				( attribute "CHIPS_PART_NAME" "CAP_A"
					( Origin gPackager )
				)
				( attribute "CDS_PART_NAME" "CAP_A_0603V-22.0UF,4V,20%,X6S,A"
					( Origin gPackager )
				)
				( attribute "CDS_LOCATION" "C5G100"
					( Origin gPackager )
				)
				( attribute "CDS_SEC" "1"
					( Origin gPackager )
				)
				( attribute "SEC" "1"
					( Origin gPackager )
				)
				( attribute "SIDE_SKU" "1S"
					( Origin gFrontEnd )
				)
				( objectStatus "C5G100" )
				( pin "a"
					( attribute "PN" "1"
						( Origin gPackager )
					)
					( objectStatus "C5G100.1" )
				)
				( pin "b"
					( attribute "PN" "2"
						( Origin gPackager )
					)
					( objectStatus "C5G100.2" )
				)
			)
			( gate "@baseboard_fab2_lib.baseboard_fab2(sch_1):page243_i75"
				( attribute "CDS_LIB" "dev_discrete"
					( Origin gPackager )
				)
				( attribute "LOCATION" "C5G101"
					( Origin gFrontEnd )
				)
				( attribute "MATERIAL" "X6S"
					( Origin gFrontEnd )
				)
				( attribute "PACK_TYPE" "0603V"
					( Origin gFrontEnd )
				)
				( attribute "PART_NUMBER" "E15431-004"
					( Origin gFrontEnd )
				)
				( attribute "PHYS_PAGE" "243"
					( Origin gFrontEnd )
				)
				( attribute "ROOM" "PVDDQ_KLM"
					( Origin gFrontEnd )
				)
				( attribute "ROT" "0"
					( Origin gFrontEnd )
				)
				( attribute "TOLERANCE" "20%"
					( Origin gFrontEnd )
				)
				( attribute "VALUE" "22.0UF"
					( Origin gFrontEnd )
				)
				( attribute "VER" "1"
					( Origin gFrontEnd )
				)
				( attribute "VOLTAGE" "4V"
					( Units "uVoltage" "V" 1.000000)
					( Origin gFrontEnd )
				)
				( attribute "XY" "(-2350,2575)"
					( Origin gFrontEnd )
				)
				( attribute "CHIPS_PART_NAME" "CAP_A"
					( Origin gPackager )
				)
				( attribute "CDS_PART_NAME" "CAP_A_0603V-22.0UF,4V,20%,X6S,A"
					( Origin gPackager )
				)
				( attribute "CDS_LOCATION" "C5G101"
					( Origin gPackager )
				)
				( attribute "CDS_SEC" "1"
					( Origin gPackager )
				)
				( attribute "SEC" "1"
					( Origin gPackager )
				)
				( attribute "SIDE_SKU" "1S"
					( Origin gFrontEnd )
				)
				( objectStatus "C5G101" )
				( pin "a"
					( attribute "PN" "1"
						( Origin gPackager )
					)
					( objectStatus "C5G101.1" )
				)
				( pin "b"
					( attribute "PN" "2"
						( Origin gPackager )
					)
					( objectStatus "C5G101.2" )
				)
			)
			( gate "@baseboard_fab2_lib.baseboard_fab2(sch_1):page243_i74"
				( attribute "CDS_LIB" "dev_discrete"
					( Origin gPackager )
				)
				( attribute "LOCATION" "C5G102"
					( Origin gFrontEnd )
				)
				( attribute "MATERIAL" "X6S"
					( Origin gFrontEnd )
				)
				( attribute "PACK_TYPE" "0603V"
					( Origin gFrontEnd )
				)
				( attribute "PART_NUMBER" "E15431-004"
					( Origin gFrontEnd )
				)
				( attribute "PHYS_PAGE" "243"
					( Origin gFrontEnd )
				)
				( attribute "ROOM" "PVDDQ_KLM"
					( Origin gFrontEnd )
				)
				( attribute "ROT" "0"
					( Origin gFrontEnd )
				)
				( attribute "TOLERANCE" "20%"
					( Origin gFrontEnd )
				)
				( attribute "VALUE" "22.0UF"
					( Origin gFrontEnd )
				)
				( attribute "VER" "1"
					( Origin gFrontEnd )
				)
				( attribute "VOLTAGE" "4V"
					( Units "uVoltage" "V" 1.000000)
					( Origin gFrontEnd )
				)
				( attribute "XY" "(-2050,2575)"
					( Origin gFrontEnd )
				)
				( attribute "CHIPS_PART_NAME" "CAP_A"
					( Origin gPackager )
				)
				( attribute "CDS_PART_NAME" "CAP_A_0603V-22.0UF,4V,20%,X6S,A"
					( Origin gPackager )
				)
				( attribute "CDS_LOCATION" "C5G102"
					( Origin gPackager )
				)
				( attribute "CDS_SEC" "1"
					( Origin gPackager )
				)
				( attribute "SEC" "1"
					( Origin gPackager )
				)
				( attribute "SIDE_SKU" "1S"
					( Origin gFrontEnd )
				)
				( objectStatus "C5G102" )
				( pin "a"
					( attribute "PN" "1"
						( Origin gPackager )
					)
					( objectStatus "C5G102.1" )
				)
				( pin "b"
					( attribute "PN" "2"
						( Origin gPackager )
					)
					( objectStatus "C5G102.2" )
				)
			)
			( gate "@baseboard_fab2_lib.baseboard_fab2(sch_1):page243_i73"
				( attribute "CDS_LIB" "dev_discrete"
					( Origin gPackager )
				)
				( attribute "LOCATION" "C5G105"
					( Origin gFrontEnd )
				)
				( attribute "MATERIAL" "X6S"
					( Origin gFrontEnd )
				)
				( attribute "PACK_TYPE" "0603V"
					( Origin gFrontEnd )
				)
				( attribute "PART_NUMBER" "E15431-004"
					( Origin gFrontEnd )
				)
				( attribute "PHYS_PAGE" "243"
					( Origin gFrontEnd )
				)
				( attribute "ROOM" "PVDDQ_KLM"
					( Origin gFrontEnd )
				)
				( attribute "ROT" "0"
					( Origin gFrontEnd )
				)
				( attribute "TOLERANCE" "20%"
					( Origin gFrontEnd )
				)
				( attribute "VALUE" "22.0UF"
					( Origin gFrontEnd )
				)
				( attribute "VER" "1"
					( Origin gFrontEnd )
				)
				( attribute "VOLTAGE" "4V"
					( Units "uVoltage" "V" 1.000000)
					( Origin gFrontEnd )
				)
				( attribute "XY" "(-1150,2575)"
					( Origin gFrontEnd )
				)
				( attribute "CHIPS_PART_NAME" "CAP_A"
					( Origin gPackager )
				)
				( attribute "CDS_PART_NAME" "CAP_A_0603V-22.0UF,4V,20%,X6S,A"
					( Origin gPackager )
				)
				( attribute "CDS_LOCATION" "C5G105"
					( Origin gPackager )
				)
				( attribute "CDS_SEC" "1"
					( Origin gPackager )
				)
				( attribute "SEC" "1"
					( Origin gPackager )
				)
				( attribute "SIDE_SKU" "1S"
					( Origin gFrontEnd )
				)
				( objectStatus "C5G105" )
				( pin "a"
					( attribute "PN" "1"
						( Origin gPackager )
					)
					( objectStatus "C5G105.1" )
				)
				( pin "b"
					( attribute "PN" "2"
						( Origin gPackager )
					)
					( objectStatus "C5G105.2" )
				)
			)
			( gate "@baseboard_fab2_lib.baseboard_fab2(sch_1):page243_i72"
				( attribute "CDS_LIB" "dev_discrete"
					( Origin gPackager )
				)
				( attribute "LOCATION" "C5G104"
					( Origin gFrontEnd )
				)
				( attribute "MATERIAL" "X6S"
					( Origin gFrontEnd )
				)
				( attribute "PACK_TYPE" "0603V"
					( Origin gFrontEnd )
				)
				( attribute "PART_NUMBER" "E15431-004"
					( Origin gFrontEnd )
				)
				( attribute "PHYS_PAGE" "243"
					( Origin gFrontEnd )
				)
				( attribute "ROOM" "PVDDQ_KLM"
					( Origin gFrontEnd )
				)
				( attribute "ROT" "0"
					( Origin gFrontEnd )
				)
				( attribute "TOLERANCE" "20%"
					( Origin gFrontEnd )
				)
				( attribute "VALUE" "22.0UF"
					( Origin gFrontEnd )
				)
				( attribute "VER" "1"
					( Origin gFrontEnd )
				)
				( attribute "VOLTAGE" "4V"
					( Units "uVoltage" "V" 1.000000)
					( Origin gFrontEnd )
				)
				( attribute "XY" "(-1450,2575)"
					( Origin gFrontEnd )
				)
				( attribute "CHIPS_PART_NAME" "CAP_A"
					( Origin gPackager )
				)
				( attribute "CDS_PART_NAME" "CAP_A_0603V-22.0UF,4V,20%,X6S,A"
					( Origin gPackager )
				)
				( attribute "CDS_LOCATION" "C5G104"
					( Origin gPackager )
				)
				( attribute "CDS_SEC" "1"
					( Origin gPackager )
				)
				( attribute "SEC" "1"
					( Origin gPackager )
				)
				( attribute "SIDE_SKU" "1S"
					( Origin gFrontEnd )
				)
				( objectStatus "C5G104" )
				( pin "a"
					( attribute "PN" "1"
						( Origin gPackager )
					)
					( objectStatus "C5G104.1" )
				)
				( pin "b"
					( attribute "PN" "2"
						( Origin gPackager )
					)
					( objectStatus "C5G104.2" )
				)
			)
			( gate "@baseboard_fab2_lib.baseboard_fab2(sch_1):page243_i71"
				( attribute "CDS_LIB" "dev_discrete"
					( Origin gPackager )
				)
				( attribute "LOCATION" "C5G103"
					( Origin gFrontEnd )
				)
				( attribute "MATERIAL" "X6S"
					( Origin gFrontEnd )
				)
				( attribute "PACK_TYPE" "0603V"
					( Origin gFrontEnd )
				)
				( attribute "PART_NUMBER" "E15431-004"
					( Origin gFrontEnd )
				)
				( attribute "PHYS_PAGE" "243"
					( Origin gFrontEnd )
				)
				( attribute "ROOM" "PVDDQ_KLM"
					( Origin gFrontEnd )
				)
				( attribute "ROT" "0"
					( Origin gFrontEnd )
				)
				( attribute "TOLERANCE" "20%"
					( Origin gFrontEnd )
				)
				( attribute "VALUE" "22.0UF"
					( Origin gFrontEnd )
				)
				( attribute "VER" "1"
					( Origin gFrontEnd )
				)
				( attribute "VOLTAGE" "4V"
					( Units "uVoltage" "V" 1.000000)
					( Origin gFrontEnd )
				)
				( attribute "XY" "(-1750,2575)"
					( Origin gFrontEnd )
				)
				( attribute "CHIPS_PART_NAME" "CAP_A"
					( Origin gPackager )
				)
				( attribute "CDS_PART_NAME" "CAP_A_0603V-22.0UF,4V,20%,X6S,A"
					( Origin gPackager )
				)
				( attribute "CDS_LOCATION" "C5G103"
					( Origin gPackager )
				)
				( attribute "CDS_SEC" "1"
					( Origin gPackager )
				)
				( attribute "SEC" "1"
					( Origin gPackager )
				)
				( attribute "SIDE_SKU" "1S"
					( Origin gFrontEnd )
				)
				( objectStatus "C5G103" )
				( pin "a"
					( attribute "PN" "1"
						( Origin gPackager )
					)
					( objectStatus "C5G103.1" )
				)
				( pin "b"
					( attribute "PN" "2"
						( Origin gPackager )
					)
					( objectStatus "C5G103.2" )
				)
			)
			( gate "@baseboard_fab2_lib.baseboard_fab2(sch_1):page243_i70"
				( attribute "CDS_LIB" "dev_discrete"
					( Origin gPackager )
				)
				( attribute "LOCATION" "C5G88"
					( Origin gFrontEnd )
				)
				( attribute "MATERIAL" "X6S"
					( Origin gFrontEnd )
				)
				( attribute "PACK_TYPE" "0603V"
					( Origin gFrontEnd )
				)
				( attribute "PART_NUMBER" "E15431-004"
					( Origin gFrontEnd )
				)
				( attribute "PHYS_PAGE" "243"
					( Origin gFrontEnd )
				)
				( attribute "ROOM" "PVDDQ_KLM"
					( Origin gFrontEnd )
				)
				( attribute "ROT" "0"
					( Origin gFrontEnd )
				)
				( attribute "TOLERANCE" "20%"
					( Origin gFrontEnd )
				)
				( attribute "VALUE" "22.0UF"
					( Origin gFrontEnd )
				)
				( attribute "VER" "1"
					( Origin gFrontEnd )
				)
				( attribute "VOLTAGE" "4V"
					( Units "uVoltage" "V" 1.000000)
					( Origin gFrontEnd )
				)
				( attribute "XY" "(-7100,1375)"
					( Origin gFrontEnd )
				)
				( attribute "CHIPS_PART_NAME" "CAP_A"
					( Origin gPackager )
				)
				( attribute "CDS_PART_NAME" "CAP_A_0603V-22.0UF,4V,20%,X6S,A"
					( Origin gPackager )
				)
				( attribute "CDS_LOCATION" "C5G88"
					( Origin gPackager )
				)
				( attribute "CDS_SEC" "1"
					( Origin gPackager )
				)
				( attribute "SEC" "1"
					( Origin gPackager )
				)
				( attribute "SIDE_SKU" "1S"
					( Origin gFrontEnd )
				)
				( objectStatus "C5G88" )
				( pin "a"
					( attribute "PN" "1"
						( Origin gPackager )
					)
					( objectStatus "C5G88.1" )
				)
				( pin "b"
					( attribute "PN" "2"
						( Origin gPackager )
					)
					( objectStatus "C5G88.2" )
				)
			)
			( gate "@baseboard_fab2_lib.baseboard_fab2(sch_1):page243_i69"
				( attribute "CDS_LIB" "dev_discrete"
					( Origin gPackager )
				)
				( attribute "LOCATION" "C5G89"
					( Origin gFrontEnd )
				)
				( attribute "MATERIAL" "X6S"
					( Origin gFrontEnd )
				)
				( attribute "PACK_TYPE" "0603V"
					( Origin gFrontEnd )
				)
				( attribute "PART_NUMBER" "E15431-004"
					( Origin gFrontEnd )
				)
				( attribute "PHYS_PAGE" "243"
					( Origin gFrontEnd )
				)
				( attribute "ROOM" "PVDDQ_KLM"
					( Origin gFrontEnd )
				)
				( attribute "ROT" "0"
					( Origin gFrontEnd )
				)
				( attribute "TOLERANCE" "20%"
					( Origin gFrontEnd )
				)
				( attribute "VALUE" "22.0UF"
					( Origin gFrontEnd )
				)
				( attribute "VER" "1"
					( Origin gFrontEnd )
				)
				( attribute "VOLTAGE" "4V"
					( Units "uVoltage" "V" 1.000000)
					( Origin gFrontEnd )
				)
				( attribute "XY" "(-6775,1375)"
					( Origin gFrontEnd )
				)
				( attribute "CHIPS_PART_NAME" "CAP_A"
					( Origin gPackager )
				)
				( attribute "CDS_PART_NAME" "CAP_A_0603V-22.0UF,4V,20%,X6S,A"
					( Origin gPackager )
				)
				( attribute "CDS_LOCATION" "C5G89"
					( Origin gPackager )
				)
				( attribute "CDS_SEC" "1"
					( Origin gPackager )
				)
				( attribute "SEC" "1"
					( Origin gPackager )
				)
				( attribute "SIDE_SKU" "1S"
					( Origin gFrontEnd )
				)
				( objectStatus "C5G89" )
				( pin "a"
					( attribute "PN" "1"
						( Origin gPackager )
					)
					( objectStatus "C5G89.1" )
				)
				( pin "b"
					( attribute "PN" "2"
						( Origin gPackager )
					)
					( objectStatus "C5G89.2" )
				)
			)
			( gate "@baseboard_fab2_lib.baseboard_fab2(sch_1):page243_i68"
				( attribute "CDS_LIB" "dev_discrete"
					( Origin gPackager )
				)
				( attribute "LOCATION" "C5G90"
					( Origin gFrontEnd )
				)
				( attribute "MATERIAL" "X6S"
					( Origin gFrontEnd )
				)
				( attribute "PACK_TYPE" "0603V"
					( Origin gFrontEnd )
				)
				( attribute "PART_NUMBER" "E15431-004"
					( Origin gFrontEnd )
				)
				( attribute "PHYS_PAGE" "243"
					( Origin gFrontEnd )
				)
				( attribute "ROOM" "PVDDQ_KLM"
					( Origin gFrontEnd )
				)
				( attribute "ROT" "0"
					( Origin gFrontEnd )
				)
				( attribute "TOLERANCE" "20%"
					( Origin gFrontEnd )
				)
				( attribute "VALUE" "22.0UF"
					( Origin gFrontEnd )
				)
				( attribute "VER" "1"
					( Origin gFrontEnd )
				)
				( attribute "VOLTAGE" "4V"
					( Units "uVoltage" "V" 1.000000)
					( Origin gFrontEnd )
				)
				( attribute "XY" "(-6450,1375)"
					( Origin gFrontEnd )
				)
				( attribute "CHIPS_PART_NAME" "CAP_A"
					( Origin gPackager )
				)
				( attribute "CDS_PART_NAME" "CAP_A_0603V-22.0UF,4V,20%,X6S,A"
					( Origin gPackager )
				)
				( attribute "CDS_LOCATION" "C5G90"
					( Origin gPackager )
				)
				( attribute "CDS_SEC" "1"
					( Origin gPackager )
				)
				( attribute "SEC" "1"
					( Origin gPackager )
				)
				( attribute "SIDE_SKU" "1S"
					( Origin gFrontEnd )
				)
				( objectStatus "C5G90" )
				( pin "a"
					( attribute "PN" "1"
						( Origin gPackager )
					)
					( objectStatus "C5G90.1" )
				)
				( pin "b"
					( attribute "PN" "2"
						( Origin gPackager )
					)
					( objectStatus "C5G90.2" )
				)
			)
			( gate "@baseboard_fab2_lib.baseboard_fab2(sch_1):page243_i67"
				( attribute "CDS_LIB" "dev_discrete"
					( Origin gPackager )
				)
				( attribute "LOCATION" "C5G91"
					( Origin gFrontEnd )
				)
				( attribute "MATERIAL" "X6S"
					( Origin gFrontEnd )
				)
				( attribute "PACK_TYPE" "0603V"
					( Origin gFrontEnd )
				)
				( attribute "PART_NUMBER" "E15431-004"
					( Origin gFrontEnd )
				)
				( attribute "PHYS_PAGE" "243"
					( Origin gFrontEnd )
				)
				( attribute "ROOM" "PVDDQ_KLM"
					( Origin gFrontEnd )
				)
				( attribute "ROT" "0"
					( Origin gFrontEnd )
				)
				( attribute "TOLERANCE" "20%"
					( Origin gFrontEnd )
				)
				( attribute "VALUE" "22.0UF"
					( Origin gFrontEnd )
				)
				( attribute "VER" "1"
					( Origin gFrontEnd )
				)
				( attribute "VOLTAGE" "4V"
					( Units "uVoltage" "V" 1.000000)
					( Origin gFrontEnd )
				)
				( attribute "XY" "(-6150,1375)"
					( Origin gFrontEnd )
				)
				( attribute "CHIPS_PART_NAME" "CAP_A"
					( Origin gPackager )
				)
				( attribute "CDS_PART_NAME" "CAP_A_0603V-22.0UF,4V,20%,X6S,A"
					( Origin gPackager )
				)
				( attribute "CDS_LOCATION" "C5G91"
					( Origin gPackager )
				)
				( attribute "CDS_SEC" "1"
					( Origin gPackager )
				)
				( attribute "SEC" "1"
					( Origin gPackager )
				)
				( attribute "SIDE_SKU" "1S"
					( Origin gFrontEnd )
				)
				( objectStatus "C5G91" )
				( pin "a"
					( attribute "PN" "1"
						( Origin gPackager )
					)
					( objectStatus "C5G91.1" )
				)
				( pin "b"
					( attribute "PN" "2"
						( Origin gPackager )
					)
					( objectStatus "C5G91.2" )
				)
			)
			( gate "@baseboard_fab2_lib.baseboard_fab2(sch_1):page243_i66"
				( attribute "CDS_LIB" "dev_discrete"
					( Origin gPackager )
				)
				( attribute "LOCATION" "C5G92"
					( Origin gFrontEnd )
				)
				( attribute "MATERIAL" "X6S"
					( Origin gFrontEnd )
				)
				( attribute "PACK_TYPE" "0603V"
					( Origin gFrontEnd )
				)
				( attribute "PART_NUMBER" "E15431-004"
					( Origin gFrontEnd )
				)
				( attribute "PHYS_PAGE" "243"
					( Origin gFrontEnd )
				)
				( attribute "ROOM" "PVDDQ_KLM"
					( Origin gFrontEnd )
				)
				( attribute "ROT" "0"
					( Origin gFrontEnd )
				)
				( attribute "TOLERANCE" "20%"
					( Origin gFrontEnd )
				)
				( attribute "VALUE" "22.0UF"
					( Origin gFrontEnd )
				)
				( attribute "VER" "1"
					( Origin gFrontEnd )
				)
				( attribute "VOLTAGE" "4V"
					( Units "uVoltage" "V" 1.000000)
					( Origin gFrontEnd )
				)
				( attribute "XY" "(-5850,1375)"
					( Origin gFrontEnd )
				)
				( attribute "CHIPS_PART_NAME" "CAP_A"
					( Origin gPackager )
				)
				( attribute "CDS_PART_NAME" "CAP_A_0603V-22.0UF,4V,20%,X6S,A"
					( Origin gPackager )
				)
				( attribute "CDS_LOCATION" "C5G92"
					( Origin gPackager )
				)
				( attribute "CDS_SEC" "1"
					( Origin gPackager )
				)
				( attribute "SEC" "1"
					( Origin gPackager )
				)
				( attribute "SIDE_SKU" "1S"
					( Origin gFrontEnd )
				)
				( objectStatus "C5G92" )
				( pin "a"
					( attribute "PN" "1"
						( Origin gPackager )
					)
					( objectStatus "C5G92.1" )
				)
				( pin "b"
					( attribute "PN" "2"
						( Origin gPackager )
					)
					( objectStatus "C5G92.2" )
				)
			)
			( gate "@baseboard_fab2_lib.baseboard_fab2(sch_1):page242_i37"
				( attribute "BOM_COST" "MEM_VRD_PVDDQ_CD"
					( Origin gFrontEnd )
				)
				( attribute "CDS_LIB" "mstr_discrete"
					( Origin gPackager )
				)
				( attribute "CDS_LOCATION" "C5G77"
					( Origin gPackager )
				)
				( attribute "CDS_SEC" "1"
					( Origin gPackager )
				)
				( attribute "LOCATION" "C5G77"
					( Origin gFrontEnd )
				)
				( attribute "MATERIAL" "X5R"
					( Origin gFrontEnd )
				)
				( attribute "PACK_TYPE" "0805"
					( Origin gFrontEnd )
				)
				( attribute "PART_NUMBER" "602433-112"
					( Origin gFrontEnd )
				)
				( attribute "PHYS_PAGE" "242"
					( Origin gFrontEnd )
				)
				( attribute "ROOM" "VDDQ_KLM_PWR_VR"
					( Origin gFrontEnd )
				)
				( attribute "ROT" "0"
					( Origin gFrontEnd )
				)
				( attribute "SEC" "1"
					( Origin gPackager )
				)
				( attribute "TOLERANCE" "20%"
					( Origin gFrontEnd )
				)
				( attribute "VALUE" "100UF"
					( Origin gFrontEnd )
				)
				( attribute "VER" "1"
					( Origin gFrontEnd )
				)
				( attribute "VOLTAGE" "4V"
					( Units "uVoltage" "V" 1.000000)
					( Origin gFrontEnd )
				)
				( attribute "XY" "(-3150,3925)"
					( Origin gFrontEnd )
				)
				( attribute "CHIPS_PART_NAME" "CAP"
					( Origin gPackager )
				)
				( attribute "CDS_PART_NAME" "CAP_0805-100UF,4V,20%,X5R,6024A"
					( Origin gPackager )
				)
				( attribute "SIDE_SKU" "1S"
					( Origin gFrontEnd )
				)
				( objectStatus "C5G77" )
				( pin "a"
					( attribute "PN" "1"
						( Origin gPackager )
					)
					( objectStatus "C5G77.1" )
				)
				( pin "b"
					( attribute "PN" "2"
						( Origin gPackager )
					)
					( objectStatus "C5G77.2" )
				)
			)
			( gate "@baseboard_fab2_lib.baseboard_fab2(sch_1):page243_i65"
				( attribute "CDS_LIB" "dev_discrete"
					( Origin gPackager )
				)
				( attribute "LOCATION" "C5G93"
					( Origin gFrontEnd )
				)
				( attribute "MATERIAL" "X6S"
					( Origin gFrontEnd )
				)
				( attribute "PACK_TYPE" "0603V"
					( Origin gFrontEnd )
				)
				( attribute "PART_NUMBER" "E15431-004"
					( Origin gFrontEnd )
				)
				( attribute "PHYS_PAGE" "243"
					( Origin gFrontEnd )
				)
				( attribute "ROOM" "PVDDQ_KLM"
					( Origin gFrontEnd )
				)
				( attribute "ROT" "0"
					( Origin gFrontEnd )
				)
				( attribute "TOLERANCE" "20%"
					( Origin gFrontEnd )
				)
				( attribute "VALUE" "22.0UF"
					( Origin gFrontEnd )
				)
				( attribute "VER" "1"
					( Origin gFrontEnd )
				)
				( attribute "VOLTAGE" "4V"
					( Units "uVoltage" "V" 1.000000)
					( Origin gFrontEnd )
				)
				( attribute "XY" "(-5550,1375)"
					( Origin gFrontEnd )
				)
				( attribute "CHIPS_PART_NAME" "CAP_A"
					( Origin gPackager )
				)
				( attribute "CDS_PART_NAME" "CAP_A_0603V-22.0UF,4V,20%,X6S,A"
					( Origin gPackager )
				)
				( attribute "CDS_LOCATION" "C5G93"
					( Origin gPackager )
				)
				( attribute "CDS_SEC" "1"
					( Origin gPackager )
				)
				( attribute "SEC" "1"
					( Origin gPackager )
				)
				( attribute "SIDE_SKU" "1S"
					( Origin gFrontEnd )
				)
				( objectStatus "C5G93" )
				( pin "a"
					( attribute "PN" "1"
						( Origin gPackager )
					)
					( objectStatus "C5G93.1" )
				)
				( pin "b"
					( attribute "PN" "2"
						( Origin gPackager )
					)
					( objectStatus "C5G93.2" )
				)
			)
			( gate "@baseboard_fab2_lib.baseboard_fab2(sch_1):page243_i64"
				( attribute "CDS_LIB" "dev_discrete"
					( Origin gPackager )
				)
				( attribute "LOCATION" "C5G94"
					( Origin gFrontEnd )
				)
				( attribute "MATERIAL" "X6S"
					( Origin gFrontEnd )
				)
				( attribute "PACK_TYPE" "0603V"
					( Origin gFrontEnd )
				)
				( attribute "PART_NUMBER" "E15431-004"
					( Origin gFrontEnd )
				)
				( attribute "PHYS_PAGE" "243"
					( Origin gFrontEnd )
				)
				( attribute "ROOM" "PVDDQ_KLM"
					( Origin gFrontEnd )
				)
				( attribute "ROT" "0"
					( Origin gFrontEnd )
				)
				( attribute "TOLERANCE" "20%"
					( Origin gFrontEnd )
				)
				( attribute "VALUE" "22.0UF"
					( Origin gFrontEnd )
				)
				( attribute "VER" "1"
					( Origin gFrontEnd )
				)
				( attribute "VOLTAGE" "4V"
					( Units "uVoltage" "V" 1.000000)
					( Origin gFrontEnd )
				)
				( attribute "XY" "(-5250,1375)"
					( Origin gFrontEnd )
				)
				( attribute "CHIPS_PART_NAME" "CAP_A"
					( Origin gPackager )
				)
				( attribute "CDS_PART_NAME" "CAP_A_0603V-22.0UF,4V,20%,X6S,A"
					( Origin gPackager )
				)
				( attribute "CDS_LOCATION" "C5G94"
					( Origin gPackager )
				)
				( attribute "CDS_SEC" "1"
					( Origin gPackager )
				)
				( attribute "SEC" "1"
					( Origin gPackager )
				)
				( attribute "SIDE_SKU" "1S"
					( Origin gFrontEnd )
				)
				( objectStatus "C5G94" )
				( pin "a"
					( attribute "PN" "1"
						( Origin gPackager )
					)
					( objectStatus "C5G94.1" )
				)
				( pin "b"
					( attribute "PN" "2"
						( Origin gPackager )
					)
					( objectStatus "C5G94.2" )
				)
			)
			( gate "@baseboard_fab2_lib.baseboard_fab2(sch_1):page243_i63"
				( attribute "CDS_LIB" "dev_discrete"
					( Origin gPackager )
				)
				( attribute "LOCATION" "C5G95"
					( Origin gFrontEnd )
				)
				( attribute "MATERIAL" "X6S"
					( Origin gFrontEnd )
				)
				( attribute "PACK_TYPE" "0603V"
					( Origin gFrontEnd )
				)
				( attribute "PART_NUMBER" "E15431-004"
					( Origin gFrontEnd )
				)
				( attribute "PHYS_PAGE" "243"
					( Origin gFrontEnd )
				)
				( attribute "ROOM" "PVDDQ_KLM"
					( Origin gFrontEnd )
				)
				( attribute "ROT" "0"
					( Origin gFrontEnd )
				)
				( attribute "TOLERANCE" "20%"
					( Origin gFrontEnd )
				)
				( attribute "VALUE" "22.0UF"
					( Origin gFrontEnd )
				)
				( attribute "VER" "1"
					( Origin gFrontEnd )
				)
				( attribute "VOLTAGE" "4V"
					( Units "uVoltage" "V" 1.000000)
					( Origin gFrontEnd )
				)
				( attribute "XY" "(-4950,1375)"
					( Origin gFrontEnd )
				)
				( attribute "CHIPS_PART_NAME" "CAP_A"
					( Origin gPackager )
				)
				( attribute "CDS_PART_NAME" "CAP_A_0603V-22.0UF,4V,20%,X6S,A"
					( Origin gPackager )
				)
				( attribute "CDS_LOCATION" "C5G95"
					( Origin gPackager )
				)
				( attribute "CDS_SEC" "1"
					( Origin gPackager )
				)
				( attribute "SEC" "1"
					( Origin gPackager )
				)
				( attribute "SIDE_SKU" "1S"
					( Origin gFrontEnd )
				)
				( objectStatus "C5G95" )
				( pin "a"
					( attribute "PN" "1"
						( Origin gPackager )
					)
					( objectStatus "C5G95.1" )
				)
				( pin "b"
					( attribute "PN" "2"
						( Origin gPackager )
					)
					( objectStatus "C5G95.2" )
				)
			)
			( gate "@baseboard_fab2_lib.baseboard_fab2(sch_1):page242_i41"
				( attribute "BOM_COST" "MEM_VRD_PVDDQ_CD"
					( Origin gFrontEnd )
				)
				( attribute "CDS_LIB" "mstr_discrete"
					( Origin gPackager )
				)
				( attribute "CDS_LOCATION" "C5G78"
					( Origin gPackager )
				)
				( attribute "CDS_SEC" "1"
					( Origin gPackager )
				)
				( attribute "LOCATION" "C5G78"
					( Origin gFrontEnd )
				)
				( attribute "MATERIAL" "X5R"
					( Origin gFrontEnd )
				)
				( attribute "PACK_TYPE" "0805"
					( Origin gFrontEnd )
				)
				( attribute "PART_NUMBER" "602433-112"
					( Origin gFrontEnd )
				)
				( attribute "PHYS_PAGE" "242"
					( Origin gFrontEnd )
				)
				( attribute "ROOM" "VDDQ_KLM_PWR_VR"
					( Origin gFrontEnd )
				)
				( attribute "ROT" "0"
					( Origin gFrontEnd )
				)
				( attribute "SEC" "1"
					( Origin gPackager )
				)
				( attribute "TOLERANCE" "20%"
					( Origin gFrontEnd )
				)
				( attribute "VALUE" "100UF"
					( Origin gFrontEnd )
				)
				( attribute "VER" "1"
					( Origin gFrontEnd )
				)
				( attribute "VOLTAGE" "4V"
					( Units "uVoltage" "V" 1.000000)
					( Origin gFrontEnd )
				)
				( attribute "XY" "(-2750,3925)"
					( Origin gFrontEnd )
				)
				( attribute "CHIPS_PART_NAME" "CAP"
					( Origin gPackager )
				)
				( attribute "CDS_PART_NAME" "CAP_0805-100UF,4V,20%,X5R,6024A"
					( Origin gPackager )
				)
				( attribute "SIDE_SKU" "1S"
					( Origin gFrontEnd )
				)
				( objectStatus "C5G78" )
				( pin "a"
					( attribute "PN" "1"
						( Origin gPackager )
					)
					( objectStatus "C5G78.1" )
				)
				( pin "b"
					( attribute "PN" "2"
						( Origin gPackager )
					)
					( objectStatus "C5G78.2" )
				)
			)
			( gate "@baseboard_fab2_lib.baseboard_fab2(sch_1):page243_i62"
				( attribute "CDS_LIB" "dev_discrete"
					( Origin gPackager )
				)
				( attribute "LOCATION" "C5G96"
					( Origin gFrontEnd )
				)
				( attribute "MATERIAL" "X6S"
					( Origin gFrontEnd )
				)
				( attribute "PACK_TYPE" "0603V"
					( Origin gFrontEnd )
				)
				( attribute "PART_NUMBER" "E15431-004"
					( Origin gFrontEnd )
				)
				( attribute "PHYS_PAGE" "243"
					( Origin gFrontEnd )
				)
				( attribute "ROOM" "PVDDQ_KLM"
					( Origin gFrontEnd )
				)
				( attribute "ROT" "0"
					( Origin gFrontEnd )
				)
				( attribute "TOLERANCE" "20%"
					( Origin gFrontEnd )
				)
				( attribute "VALUE" "22.0UF"
					( Origin gFrontEnd )
				)
				( attribute "VER" "1"
					( Origin gFrontEnd )
				)
				( attribute "VOLTAGE" "4V"
					( Units "uVoltage" "V" 1.000000)
					( Origin gFrontEnd )
				)
				( attribute "XY" "(-4650,1375)"
					( Origin gFrontEnd )
				)
				( attribute "CHIPS_PART_NAME" "CAP_A"
					( Origin gPackager )
				)
				( attribute "CDS_PART_NAME" "CAP_A_0603V-22.0UF,4V,20%,X6S,A"
					( Origin gPackager )
				)
				( attribute "CDS_LOCATION" "C5G96"
					( Origin gPackager )
				)
				( attribute "CDS_SEC" "1"
					( Origin gPackager )
				)
				( attribute "SEC" "1"
					( Origin gPackager )
				)
				( attribute "SIDE_SKU" "1S"
					( Origin gFrontEnd )
				)
				( objectStatus "C5G96" )
				( pin "a"
					( attribute "PN" "1"
						( Origin gPackager )
					)
					( objectStatus "C5G96.1" )
				)
				( pin "b"
					( attribute "PN" "2"
						( Origin gPackager )
					)
					( objectStatus "C5G96.2" )
				)
			)
			( gate "@baseboard_fab2_lib.baseboard_fab2(sch_1):page243_i61"
				( attribute "CDS_LIB" "dev_discrete"
					( Origin gPackager )
				)
				( attribute "LOCATION" "C5G80"
					( Origin gFrontEnd )
				)
				( attribute "MATERIAL" "X6S"
					( Origin gFrontEnd )
				)
				( attribute "PACK_TYPE" "0603V"
					( Origin gFrontEnd )
				)
				( attribute "PART_NUMBER" "E15431-004"
					( Origin gFrontEnd )
				)
				( attribute "PHYS_PAGE" "243"
					( Origin gFrontEnd )
				)
				( attribute "ROOM" "PVDDQ_KLM"
					( Origin gFrontEnd )
				)
				( attribute "ROT" "0"
					( Origin gFrontEnd )
				)
				( attribute "TOLERANCE" "20%"
					( Origin gFrontEnd )
				)
				( attribute "VALUE" "22.0UF"
					( Origin gFrontEnd )
				)
				( attribute "VER" "1"
					( Origin gFrontEnd )
				)
				( attribute "VOLTAGE" "4V"
					( Units "uVoltage" "V" 1.000000)
					( Origin gFrontEnd )
				)
				( attribute "XY" "(-6800,2500)"
					( Origin gFrontEnd )
				)
				( attribute "CHIPS_PART_NAME" "CAP_A"
					( Origin gPackager )
				)
				( attribute "CDS_PART_NAME" "CAP_A_0603V-22.0UF,4V,20%,X6S,A"
					( Origin gPackager )
				)
				( attribute "CDS_LOCATION" "C5G80"
					( Origin gPackager )
				)
				( attribute "CDS_SEC" "1"
					( Origin gPackager )
				)
				( attribute "SEC" "1"
					( Origin gPackager )
				)
				( attribute "SIDE_SKU" "1S"
					( Origin gFrontEnd )
				)
				( objectStatus "C5G80" )
				( pin "a"
					( attribute "PN" "1"
						( Origin gPackager )
					)
					( objectStatus "C5G80.1" )
				)
				( pin "b"
					( attribute "PN" "2"
						( Origin gPackager )
					)
					( objectStatus "C5G80.2" )
				)
			)
			( gate "@baseboard_fab2_lib.baseboard_fab2(sch_1):page243_i60"
				( attribute "CDS_LIB" "dev_discrete"
					( Origin gPackager )
				)
				( attribute "LOCATION" "C5G81"
					( Origin gFrontEnd )
				)
				( attribute "MATERIAL" "X6S"
					( Origin gFrontEnd )
				)
				( attribute "PACK_TYPE" "0603V"
					( Origin gFrontEnd )
				)
				( attribute "PART_NUMBER" "E15431-004"
					( Origin gFrontEnd )
				)
				( attribute "PHYS_PAGE" "243"
					( Origin gFrontEnd )
				)
				( attribute "ROOM" "PVDDQ_KLM"
					( Origin gFrontEnd )
				)
				( attribute "ROT" "0"
					( Origin gFrontEnd )
				)
				( attribute "TOLERANCE" "20%"
					( Origin gFrontEnd )
				)
				( attribute "VALUE" "22.0UF"
					( Origin gFrontEnd )
				)
				( attribute "VER" "1"
					( Origin gFrontEnd )
				)
				( attribute "VOLTAGE" "4V"
					( Units "uVoltage" "V" 1.000000)
					( Origin gFrontEnd )
				)
				( attribute "XY" "(-6500,2500)"
					( Origin gFrontEnd )
				)
				( attribute "CHIPS_PART_NAME" "CAP_A"
					( Origin gPackager )
				)
				( attribute "CDS_PART_NAME" "CAP_A_0603V-22.0UF,4V,20%,X6S,A"
					( Origin gPackager )
				)
				( attribute "CDS_LOCATION" "C5G81"
					( Origin gPackager )
				)
				( attribute "CDS_SEC" "1"
					( Origin gPackager )
				)
				( attribute "SEC" "1"
					( Origin gPackager )
				)
				( attribute "SIDE_SKU" "1S"
					( Origin gFrontEnd )
				)
				( objectStatus "C5G81" )
				( pin "a"
					( attribute "PN" "1"
						( Origin gPackager )
					)
					( objectStatus "C5G81.1" )
				)
				( pin "b"
					( attribute "PN" "2"
						( Origin gPackager )
					)
					( objectStatus "C5G81.2" )
				)
			)
			( gate "@baseboard_fab2_lib.baseboard_fab2(sch_1):page243_i59"
				( attribute "CDS_LIB" "dev_discrete"
					( Origin gPackager )
				)
				( attribute "LOCATION" "C5G82"
					( Origin gFrontEnd )
				)
				( attribute "MATERIAL" "X6S"
					( Origin gFrontEnd )
				)
				( attribute "PACK_TYPE" "0603V"
					( Origin gFrontEnd )
				)
				( attribute "PART_NUMBER" "E15431-004"
					( Origin gFrontEnd )
				)
				( attribute "PHYS_PAGE" "243"
					( Origin gFrontEnd )
				)
				( attribute "ROOM" "PVDDQ_KLM"
					( Origin gFrontEnd )
				)
				( attribute "ROT" "0"
					( Origin gFrontEnd )
				)
				( attribute "TOLERANCE" "20%"
					( Origin gFrontEnd )
				)
				( attribute "VALUE" "22.0UF"
					( Origin gFrontEnd )
				)
				( attribute "VER" "1"
					( Origin gFrontEnd )
				)
				( attribute "VOLTAGE" "4V"
					( Units "uVoltage" "V" 1.000000)
					( Origin gFrontEnd )
				)
				( attribute "XY" "(-6150,2500)"
					( Origin gFrontEnd )
				)
				( attribute "CHIPS_PART_NAME" "CAP_A"
					( Origin gPackager )
				)
				( attribute "CDS_PART_NAME" "CAP_A_0603V-22.0UF,4V,20%,X6S,A"
					( Origin gPackager )
				)
				( attribute "CDS_LOCATION" "C5G82"
					( Origin gPackager )
				)
				( attribute "CDS_SEC" "1"
					( Origin gPackager )
				)
				( attribute "SEC" "1"
					( Origin gPackager )
				)
				( attribute "SIDE_SKU" "1S"
					( Origin gFrontEnd )
				)
				( objectStatus "C5G82" )
				( pin "a"
					( attribute "PN" "1"
						( Origin gPackager )
					)
					( objectStatus "C5G82.1" )
				)
				( pin "b"
					( attribute "PN" "2"
						( Origin gPackager )
					)
					( objectStatus "C5G82.2" )
				)
			)
			( gate "@baseboard_fab2_lib.baseboard_fab2(sch_1):page243_i58"
				( attribute "CDS_LIB" "dev_discrete"
					( Origin gPackager )
				)
				( attribute "LOCATION" "C5G83"
					( Origin gFrontEnd )
				)
				( attribute "MATERIAL" "X6S"
					( Origin gFrontEnd )
				)
				( attribute "PACK_TYPE" "0603V"
					( Origin gFrontEnd )
				)
				( attribute "PART_NUMBER" "E15431-004"
					( Origin gFrontEnd )
				)
				( attribute "PHYS_PAGE" "243"
					( Origin gFrontEnd )
				)
				( attribute "ROOM" "PVDDQ_KLM"
					( Origin gFrontEnd )
				)
				( attribute "ROT" "0"
					( Origin gFrontEnd )
				)
				( attribute "TOLERANCE" "20%"
					( Origin gFrontEnd )
				)
				( attribute "VALUE" "22.0UF"
					( Origin gFrontEnd )
				)
				( attribute "VER" "1"
					( Origin gFrontEnd )
				)
				( attribute "VOLTAGE" "4V"
					( Units "uVoltage" "V" 1.000000)
					( Origin gFrontEnd )
				)
				( attribute "XY" "(-5850,2500)"
					( Origin gFrontEnd )
				)
				( attribute "CHIPS_PART_NAME" "CAP_A"
					( Origin gPackager )
				)
				( attribute "CDS_PART_NAME" "CAP_A_0603V-22.0UF,4V,20%,X6S,A"
					( Origin gPackager )
				)
				( attribute "CDS_LOCATION" "C5G83"
					( Origin gPackager )
				)
				( attribute "CDS_SEC" "1"
					( Origin gPackager )
				)
				( attribute "SEC" "1"
					( Origin gPackager )
				)
				( attribute "SIDE_SKU" "1S"
					( Origin gFrontEnd )
				)
				( objectStatus "C5G83" )
				( pin "a"
					( attribute "PN" "1"
						( Origin gPackager )
					)
					( objectStatus "C5G83.1" )
				)
				( pin "b"
					( attribute "PN" "2"
						( Origin gPackager )
					)
					( objectStatus "C5G83.2" )
				)
			)
			( gate "@baseboard_fab2_lib.baseboard_fab2(sch_1):page243_i57"
				( attribute "CDS_LIB" "dev_discrete"
					( Origin gPackager )
				)
				( attribute "LOCATION" "C5G84"
					( Origin gFrontEnd )
				)
				( attribute "MATERIAL" "X6S"
					( Origin gFrontEnd )
				)
				( attribute "PACK_TYPE" "0603V"
					( Origin gFrontEnd )
				)
				( attribute "PART_NUMBER" "E15431-004"
					( Origin gFrontEnd )
				)
				( attribute "PHYS_PAGE" "243"
					( Origin gFrontEnd )
				)
				( attribute "ROOM" "PVDDQ_KLM"
					( Origin gFrontEnd )
				)
				( attribute "ROT" "0"
					( Origin gFrontEnd )
				)
				( attribute "TOLERANCE" "20%"
					( Origin gFrontEnd )
				)
				( attribute "VALUE" "22.0UF"
					( Origin gFrontEnd )
				)
				( attribute "VER" "1"
					( Origin gFrontEnd )
				)
				( attribute "VOLTAGE" "4V"
					( Units "uVoltage" "V" 1.000000)
					( Origin gFrontEnd )
				)
				( attribute "XY" "(-5550,2500)"
					( Origin gFrontEnd )
				)
				( attribute "CHIPS_PART_NAME" "CAP_A"
					( Origin gPackager )
				)
				( attribute "CDS_PART_NAME" "CAP_A_0603V-22.0UF,4V,20%,X6S,A"
					( Origin gPackager )
				)
				( attribute "CDS_LOCATION" "C5G84"
					( Origin gPackager )
				)
				( attribute "CDS_SEC" "1"
					( Origin gPackager )
				)
				( attribute "SEC" "1"
					( Origin gPackager )
				)
				( attribute "SIDE_SKU" "1S"
					( Origin gFrontEnd )
				)
				( objectStatus "C5G84" )
				( pin "a"
					( attribute "PN" "1"
						( Origin gPackager )
					)
					( objectStatus "C5G84.1" )
				)
				( pin "b"
					( attribute "PN" "2"
						( Origin gPackager )
					)
					( objectStatus "C5G84.2" )
				)
			)
			( gate "@baseboard_fab2_lib.baseboard_fab2(sch_1):page243_i56"
				( attribute "CDS_LIB" "dev_discrete"
					( Origin gPackager )
				)
				( attribute "LOCATION" "C5G85"
					( Origin gFrontEnd )
				)
				( attribute "MATERIAL" "X6S"
					( Origin gFrontEnd )
				)
				( attribute "PACK_TYPE" "0603V"
					( Origin gFrontEnd )
				)
				( attribute "PART_NUMBER" "E15431-004"
					( Origin gFrontEnd )
				)
				( attribute "PHYS_PAGE" "243"
					( Origin gFrontEnd )
				)
				( attribute "ROOM" "PVDDQ_KLM"
					( Origin gFrontEnd )
				)
				( attribute "ROT" "0"
					( Origin gFrontEnd )
				)
				( attribute "TOLERANCE" "20%"
					( Origin gFrontEnd )
				)
				( attribute "VALUE" "22.0UF"
					( Origin gFrontEnd )
				)
				( attribute "VER" "1"
					( Origin gFrontEnd )
				)
				( attribute "VOLTAGE" "4V"
					( Units "uVoltage" "V" 1.000000)
					( Origin gFrontEnd )
				)
				( attribute "XY" "(-5250,2500)"
					( Origin gFrontEnd )
				)
				( attribute "CHIPS_PART_NAME" "CAP_A"
					( Origin gPackager )
				)
				( attribute "CDS_PART_NAME" "CAP_A_0603V-22.0UF,4V,20%,X6S,A"
					( Origin gPackager )
				)
				( attribute "CDS_LOCATION" "C5G85"
					( Origin gPackager )
				)
				( attribute "CDS_SEC" "1"
					( Origin gPackager )
				)
				( attribute "SEC" "1"
					( Origin gPackager )
				)
				( attribute "SIDE_SKU" "1S"
					( Origin gFrontEnd )
				)
				( objectStatus "C5G85" )
				( pin "a"
					( attribute "PN" "1"
						( Origin gPackager )
					)
					( objectStatus "C5G85.1" )
				)
				( pin "b"
					( attribute "PN" "2"
						( Origin gPackager )
					)
					( objectStatus "C5G85.2" )
				)
			)
			( gate "@baseboard_fab2_lib.baseboard_fab2(sch_1):page243_i55"
				( attribute "CDS_LIB" "dev_discrete"
					( Origin gPackager )
				)
				( attribute "LOCATION" "C5G86"
					( Origin gFrontEnd )
				)
				( attribute "MATERIAL" "X6S"
					( Origin gFrontEnd )
				)
				( attribute "PACK_TYPE" "0603V"
					( Origin gFrontEnd )
				)
				( attribute "PART_NUMBER" "E15431-004"
					( Origin gFrontEnd )
				)
				( attribute "PHYS_PAGE" "243"
					( Origin gFrontEnd )
				)
				( attribute "ROOM" "PVDDQ_KLM"
					( Origin gFrontEnd )
				)
				( attribute "ROT" "0"
					( Origin gFrontEnd )
				)
				( attribute "TOLERANCE" "20%"
					( Origin gFrontEnd )
				)
				( attribute "VALUE" "22.0UF"
					( Origin gFrontEnd )
				)
				( attribute "VER" "1"
					( Origin gFrontEnd )
				)
				( attribute "VOLTAGE" "4V"
					( Units "uVoltage" "V" 1.000000)
					( Origin gFrontEnd )
				)
				( attribute "XY" "(-4950,2500)"
					( Origin gFrontEnd )
				)
				( attribute "CHIPS_PART_NAME" "CAP_A"
					( Origin gPackager )
				)
				( attribute "CDS_PART_NAME" "CAP_A_0603V-22.0UF,4V,20%,X6S,A"
					( Origin gPackager )
				)
				( attribute "CDS_LOCATION" "C5G86"
					( Origin gPackager )
				)
				( attribute "CDS_SEC" "1"
					( Origin gPackager )
				)
				( attribute "SEC" "1"
					( Origin gPackager )
				)
				( attribute "SIDE_SKU" "1S"
					( Origin gFrontEnd )
				)
				( objectStatus "C5G86" )
				( pin "a"
					( attribute "PN" "1"
						( Origin gPackager )
					)
					( objectStatus "C5G86.1" )
				)
				( pin "b"
					( attribute "PN" "2"
						( Origin gPackager )
					)
					( objectStatus "C5G86.2" )
				)
			)
			( gate "@baseboard_fab2_lib.baseboard_fab2(sch_1):page243_i54"
				( attribute "CDS_LIB" "dev_discrete"
					( Origin gPackager )
				)
				( attribute "LOCATION" "C5G87"
					( Origin gFrontEnd )
				)
				( attribute "MATERIAL" "X6S"
					( Origin gFrontEnd )
				)
				( attribute "PACK_TYPE" "0603V"
					( Origin gFrontEnd )
				)
				( attribute "PART_NUMBER" "E15431-004"
					( Origin gFrontEnd )
				)
				( attribute "PHYS_PAGE" "243"
					( Origin gFrontEnd )
				)
				( attribute "ROOM" "PVDDQ_KLM"
					( Origin gFrontEnd )
				)
				( attribute "ROT" "0"
					( Origin gFrontEnd )
				)
				( attribute "TOLERANCE" "20%"
					( Origin gFrontEnd )
				)
				( attribute "VALUE" "22.0UF"
					( Origin gFrontEnd )
				)
				( attribute "VER" "1"
					( Origin gFrontEnd )
				)
				( attribute "VOLTAGE" "4V"
					( Units "uVoltage" "V" 1.000000)
					( Origin gFrontEnd )
				)
				( attribute "XY" "(-4650,2500)"
					( Origin gFrontEnd )
				)
				( attribute "CHIPS_PART_NAME" "CAP_A"
					( Origin gPackager )
				)
				( attribute "CDS_PART_NAME" "CAP_A_0603V-22.0UF,4V,20%,X6S,A"
					( Origin gPackager )
				)
				( attribute "CDS_LOCATION" "C5G87"
					( Origin gPackager )
				)
				( attribute "CDS_SEC" "1"
					( Origin gPackager )
				)
				( attribute "SEC" "1"
					( Origin gPackager )
				)
				( attribute "SIDE_SKU" "1S"
					( Origin gFrontEnd )
				)
				( objectStatus "C5G87" )
				( pin "a"
					( attribute "PN" "1"
						( Origin gPackager )
					)
					( objectStatus "C5G87.1" )
				)
				( pin "b"
					( attribute "PN" "2"
						( Origin gPackager )
					)
					( objectStatus "C5G87.2" )
				)
			)
			( gate "@baseboard_fab2_lib.baseboard_fab2(sch_1):page243_i53"
				( attribute "CDS_LIB" "dev_discrete"
					( Origin gPackager )
				)
				( attribute "LOCATION" "C5G79"
					( Origin gFrontEnd )
				)
				( attribute "MATERIAL" "X6S"
					( Origin gFrontEnd )
				)
				( attribute "PACK_TYPE" "0603V"
					( Origin gFrontEnd )
				)
				( attribute "PART_NUMBER" "E15431-004"
					( Origin gFrontEnd )
				)
				( attribute "PHYS_PAGE" "243"
					( Origin gFrontEnd )
				)
				( attribute "ROOM" "PVDDQ_KLM"
					( Origin gFrontEnd )
				)
				( attribute "ROT" "0"
					( Origin gFrontEnd )
				)
				( attribute "TOLERANCE" "20%"
					( Origin gFrontEnd )
				)
				( attribute "VALUE" "22.0UF"
					( Origin gFrontEnd )
				)
				( attribute "VER" "1"
					( Origin gFrontEnd )
				)
				( attribute "VOLTAGE" "4V"
					( Units "uVoltage" "V" 1.000000)
					( Origin gFrontEnd )
				)
				( attribute "XY" "(-7125,2500)"
					( Origin gFrontEnd )
				)
				( attribute "CHIPS_PART_NAME" "CAP_A"
					( Origin gPackager )
				)
				( attribute "CDS_PART_NAME" "CAP_A_0603V-22.0UF,4V,20%,X6S,A"
					( Origin gPackager )
				)
				( attribute "CDS_LOCATION" "C5G79"
					( Origin gPackager )
				)
				( attribute "CDS_SEC" "1"
					( Origin gPackager )
				)
				( attribute "SEC" "1"
					( Origin gPackager )
				)
				( attribute "SIDE_SKU" "1S"
					( Origin gFrontEnd )
				)
				( objectStatus "C5G79" )
				( pin "a"
					( attribute "PN" "1"
						( Origin gPackager )
					)
					( objectStatus "C5G79.1" )
				)
				( pin "b"
					( attribute "PN" "2"
						( Origin gPackager )
					)
					( objectStatus "C5G79.2" )
				)
			)
			( gate "@baseboard_fab2_lib.baseboard_fab2(sch_1):page243_i12"
				( attribute "BOM_COST" "MEM_VRD_PVDDQ_CD"
					( Origin gFrontEnd )
				)
				( attribute "CDS_LIB" "mstr_discrete"
					( Origin gPackager )
				)
				( attribute "CDS_LOCATION" "C5G117"
					( Origin gPackager )
				)
				( attribute "CDS_SEC" "1"
					( Origin gPackager )
				)
				( attribute "LOCATION" "C5G117"
					( Origin gFrontEnd )
				)
				( attribute "MATERIAL" "X5R"
					( Origin gFrontEnd )
				)
				( attribute "PACK_TYPE" "0805"
					( Origin gFrontEnd )
				)
				( attribute "PART_NUMBER" "602433-112"
					( Origin gFrontEnd )
				)
				( attribute "PHYS_PAGE" "243"
					( Origin gFrontEnd )
				)
				( attribute "ROOM" "VDDQ_KLM_PWR_VR"
					( Origin gFrontEnd )
				)
				( attribute "ROT" "0"
					( Origin gFrontEnd )
				)
				( attribute "SEC" "1"
					( Origin gPackager )
				)
				( attribute "TOLERANCE" "20%"
					( Origin gFrontEnd )
				)
				( attribute "VALUE" "100UF"
					( Origin gFrontEnd )
				)
				( attribute "VER" "1"
					( Origin gFrontEnd )
				)
				( attribute "VOLTAGE" "4V"
					( Units "uVoltage" "V" 1.000000)
					( Origin gFrontEnd )
				)
				( attribute "XY" "(-7125,3650)"
					( Origin gFrontEnd )
				)
				( attribute "CHIPS_PART_NAME" "CAP"
					( Origin gPackager )
				)
				( attribute "CDS_PART_NAME" "CAP_0805-100UF,4V,20%,X5R,6024A"
					( Origin gPackager )
				)
				( attribute "SIDE_SKU" "1S"
					( Origin gFrontEnd )
				)
				( objectStatus "C5G117" )
				( pin "a"
					( attribute "PN" "1"
						( Origin gPackager )
					)
					( objectStatus "C5G117.1" )
				)
				( pin "b"
					( attribute "PN" "2"
						( Origin gPackager )
					)
					( objectStatus "C5G117.2" )
				)
			)
			( gate "@baseboard_fab2_lib.baseboard_fab2(sch_1):page243_i13"
				( attribute "BOM_COST" "MEM_VRD_PVDDQ_CD"
					( Origin gFrontEnd )
				)
				( attribute "CDS_LIB" "mstr_discrete"
					( Origin gPackager )
				)
				( attribute "CDS_LOCATION" "C5G118"
					( Origin gPackager )
				)
				( attribute "CDS_SEC" "1"
					( Origin gPackager )
				)
				( attribute "LOCATION" "C5G118"
					( Origin gFrontEnd )
				)
				( attribute "MATERIAL" "X5R"
					( Origin gFrontEnd )
				)
				( attribute "PACK_TYPE" "0805"
					( Origin gFrontEnd )
				)
				( attribute "PART_NUMBER" "602433-112"
					( Origin gFrontEnd )
				)
				( attribute "PHYS_PAGE" "243"
					( Origin gFrontEnd )
				)
				( attribute "ROOM" "VDDQ_KLM_PWR_VR"
					( Origin gFrontEnd )
				)
				( attribute "ROT" "0"
					( Origin gFrontEnd )
				)
				( attribute "SEC" "1"
					( Origin gPackager )
				)
				( attribute "TOLERANCE" "20%"
					( Origin gFrontEnd )
				)
				( attribute "VALUE" "100UF"
					( Origin gFrontEnd )
				)
				( attribute "VER" "1"
					( Origin gFrontEnd )
				)
				( attribute "VOLTAGE" "4V"
					( Units "uVoltage" "V" 1.000000)
					( Origin gFrontEnd )
				)
				( attribute "XY" "(-6700,3650)"
					( Origin gFrontEnd )
				)
				( attribute "CHIPS_PART_NAME" "CAP"
					( Origin gPackager )
				)
				( attribute "CDS_PART_NAME" "CAP_0805-100UF,4V,20%,X5R,6024A"
					( Origin gPackager )
				)
				( attribute "SIDE_SKU" "1S"
					( Origin gFrontEnd )
				)
				( objectStatus "C5G118" )
				( pin "a"
					( attribute "PN" "1"
						( Origin gPackager )
					)
					( objectStatus "C5G118.1" )
				)
				( pin "b"
					( attribute "PN" "2"
						( Origin gPackager )
					)
					( objectStatus "C5G118.2" )
				)
			)
			( gate "@baseboard_fab2_lib.baseboard_fab2(sch_1):page243_i39"
				( attribute "BOM_COST" "MEM_VRD_PVDDQ_CD"
					( Origin gFrontEnd )
				)
				( attribute "CDS_LIB" "mstr_discrete"
					( Origin gPackager )
				)
				( attribute "CDS_LOCATION" "C5G115"
					( Origin gPackager )
				)
				( attribute "CDS_SEC" "1"
					( Origin gPackager )
				)
				( attribute "LOCATION" "C5G115"
					( Origin gFrontEnd )
				)
				( attribute "MATERIAL" "X5R"
					( Origin gFrontEnd )
				)
				( attribute "PACK_TYPE" "0805"
					( Origin gFrontEnd )
				)
				( attribute "PART_NUMBER" "602433-112"
					( Origin gFrontEnd )
				)
				( attribute "PHYS_PAGE" "243"
					( Origin gFrontEnd )
				)
				( attribute "ROOM" "VDDQ_KLM_PWR_VR"
					( Origin gFrontEnd )
				)
				( attribute "ROT" "0"
					( Origin gFrontEnd )
				)
				( attribute "SEC" "1"
					( Origin gPackager )
				)
				( attribute "TOLERANCE" "20%"
					( Origin gFrontEnd )
				)
				( attribute "VALUE" "100UF"
					( Origin gFrontEnd )
				)
				( attribute "VER" "1"
					( Origin gFrontEnd )
				)
				( attribute "VOLTAGE" "4V"
					( Units "uVoltage" "V" 1.000000)
					( Origin gFrontEnd )
				)
				( attribute "XY" "(-3600,3925)"
					( Origin gFrontEnd )
				)
				( attribute "CHIPS_PART_NAME" "CAP"
					( Origin gPackager )
				)
				( attribute "CDS_PART_NAME" "CAP_0805-100UF,4V,20%,X5R,6024A"
					( Origin gPackager )
				)
				( attribute "SIDE_SKU" "1S"
					( Origin gFrontEnd )
				)
				( objectStatus "C5G115" )
				( pin "a"
					( attribute "PN" "1"
						( Origin gPackager )
					)
					( objectStatus "C5G115.1" )
				)
				( pin "b"
					( attribute "PN" "2"
						( Origin gPackager )
					)
					( objectStatus "C5G115.2" )
				)
			)
			( gate "@baseboard_fab2_lib.baseboard_fab2(sch_1):page243_i43"
				( attribute "BOM_COST" "MEM_VRD_PVDDQ_CD"
					( Origin gFrontEnd )
				)
				( attribute "CDS_LIB" "mstr_discrete"
					( Origin gPackager )
				)
				( attribute "CDS_LOCATION" "C5G116"
					( Origin gPackager )
				)
				( attribute "CDS_SEC" "1"
					( Origin gPackager )
				)
				( attribute "LOCATION" "C5G116"
					( Origin gFrontEnd )
				)
				( attribute "MATERIAL" "X5R"
					( Origin gFrontEnd )
				)
				( attribute "PACK_TYPE" "0805"
					( Origin gFrontEnd )
				)
				( attribute "PART_NUMBER" "602433-112"
					( Origin gFrontEnd )
				)
				( attribute "PHYS_PAGE" "243"
					( Origin gFrontEnd )
				)
				( attribute "ROOM" "VDDQ_KLM_PWR_VR"
					( Origin gFrontEnd )
				)
				( attribute "ROT" "0"
					( Origin gFrontEnd )
				)
				( attribute "SEC" "1"
					( Origin gPackager )
				)
				( attribute "TOLERANCE" "20%"
					( Origin gFrontEnd )
				)
				( attribute "VALUE" "100UF"
					( Origin gFrontEnd )
				)
				( attribute "VER" "1"
					( Origin gFrontEnd )
				)
				( attribute "VOLTAGE" "4V"
					( Units "uVoltage" "V" 1.000000)
					( Origin gFrontEnd )
				)
				( attribute "XY" "(-3200,3925)"
					( Origin gFrontEnd )
				)
				( attribute "CHIPS_PART_NAME" "CAP"
					( Origin gPackager )
				)
				( attribute "CDS_PART_NAME" "CAP_0805-100UF,4V,20%,X5R,6024A"
					( Origin gPackager )
				)
				( attribute "SIDE_SKU" "1S"
					( Origin gFrontEnd )
				)
				( objectStatus "C5G116" )
				( pin "a"
					( attribute "PN" "1"
						( Origin gPackager )
					)
					( objectStatus "C5G116.1" )
				)
				( pin "b"
					( attribute "PN" "2"
						( Origin gPackager )
					)
					( objectStatus "C5G116.2" )
				)
			)
			( gate "@baseboard_fab2_lib.baseboard_fab2(sch_1):page242_i53"
				( attribute "CDS_LIB" "dev_discrete"
					( Origin gPackager )
				)
				( attribute "LOCATION" "C5G41"
					( Origin gFrontEnd )
				)
				( attribute "MATERIAL" "X6S"
					( Origin gFrontEnd )
				)
				( attribute "PACK_TYPE" "0603V"
					( Origin gFrontEnd )
				)
				( attribute "PART_NUMBER" "E15431-004"
					( Origin gFrontEnd )
				)
				( attribute "PHYS_PAGE" "242"
					( Origin gFrontEnd )
				)
				( attribute "ROOM" "PVDDQ_KLM"
					( Origin gFrontEnd )
				)
				( attribute "ROT" "0"
					( Origin gFrontEnd )
				)
				( attribute "TOLERANCE" "20%"
					( Origin gFrontEnd )
				)
				( attribute "VALUE" "22.0UF"
					( Origin gFrontEnd )
				)
				( attribute "VER" "1"
					( Origin gFrontEnd )
				)
				( attribute "VOLTAGE" "4V"
					( Units "uVoltage" "V" 1.000000)
					( Origin gFrontEnd )
				)
				( attribute "XY" "(-7400,2775)"
					( Origin gFrontEnd )
				)
				( attribute "CHIPS_PART_NAME" "CAP_A"
					( Origin gPackager )
				)
				( attribute "CDS_PART_NAME" "CAP_A_0603V-22.0UF,4V,20%,X6S,A"
					( Origin gPackager )
				)
				( attribute "CDS_LOCATION" "C5G41"
					( Origin gPackager )
				)
				( attribute "CDS_SEC" "1"
					( Origin gPackager )
				)
				( attribute "SEC" "1"
					( Origin gPackager )
				)
				( attribute "SIDE_SKU" "1S"
					( Origin gFrontEnd )
				)
				( objectStatus "C5G41" )
				( pin "a"
					( attribute "PN" "1"
						( Origin gPackager )
					)
					( objectStatus "C5G41.1" )
				)
				( pin "b"
					( attribute "PN" "2"
						( Origin gPackager )
					)
					( objectStatus "C5G41.2" )
				)
			)
			( gate "@baseboard_fab2_lib.baseboard_fab2(sch_1):page242_i54"
				( attribute "CDS_LIB" "dev_discrete"
					( Origin gPackager )
				)
				( attribute "LOCATION" "C5G42"
					( Origin gFrontEnd )
				)
				( attribute "MATERIAL" "X6S"
					( Origin gFrontEnd )
				)
				( attribute "PACK_TYPE" "0603V"
					( Origin gFrontEnd )
				)
				( attribute "PART_NUMBER" "E15431-004"
					( Origin gFrontEnd )
				)
				( attribute "PHYS_PAGE" "242"
					( Origin gFrontEnd )
				)
				( attribute "ROOM" "PVDDQ_KLM"
					( Origin gFrontEnd )
				)
				( attribute "ROT" "0"
					( Origin gFrontEnd )
				)
				( attribute "TOLERANCE" "20%"
					( Origin gFrontEnd )
				)
				( attribute "VALUE" "22.0UF"
					( Origin gFrontEnd )
				)
				( attribute "VER" "1"
					( Origin gFrontEnd )
				)
				( attribute "VOLTAGE" "4V"
					( Units "uVoltage" "V" 1.000000)
					( Origin gFrontEnd )
				)
				( attribute "XY" "(-7100,2775)"
					( Origin gFrontEnd )
				)
				( attribute "CHIPS_PART_NAME" "CAP_A"
					( Origin gPackager )
				)
				( attribute "CDS_PART_NAME" "CAP_A_0603V-22.0UF,4V,20%,X6S,A"
					( Origin gPackager )
				)
				( attribute "CDS_LOCATION" "C5G42"
					( Origin gPackager )
				)
				( attribute "CDS_SEC" "1"
					( Origin gPackager )
				)
				( attribute "SEC" "1"
					( Origin gPackager )
				)
				( attribute "SIDE_SKU" "1S"
					( Origin gFrontEnd )
				)
				( objectStatus "C5G42" )
				( pin "a"
					( attribute "PN" "1"
						( Origin gPackager )
					)
					( objectStatus "C5G42.1" )
				)
				( pin "b"
					( attribute "PN" "2"
						( Origin gPackager )
					)
					( objectStatus "C5G42.2" )
				)
			)
			( gate "@baseboard_fab2_lib.baseboard_fab2(sch_1):page242_i55"
				( attribute "CDS_LIB" "dev_discrete"
					( Origin gPackager )
				)
				( attribute "LOCATION" "C5G44"
					( Origin gFrontEnd )
				)
				( attribute "MATERIAL" "X6S"
					( Origin gFrontEnd )
				)
				( attribute "PACK_TYPE" "0603V"
					( Origin gFrontEnd )
				)
				( attribute "PART_NUMBER" "E15431-004"
					( Origin gFrontEnd )
				)
				( attribute "PHYS_PAGE" "242"
					( Origin gFrontEnd )
				)
				( attribute "ROOM" "PVDDQ_KLM"
					( Origin gFrontEnd )
				)
				( attribute "ROT" "0"
					( Origin gFrontEnd )
				)
				( attribute "TOLERANCE" "20%"
					( Origin gFrontEnd )
				)
				( attribute "VALUE" "22.0UF"
					( Origin gFrontEnd )
				)
				( attribute "VER" "1"
					( Origin gFrontEnd )
				)
				( attribute "VOLTAGE" "4V"
					( Units "uVoltage" "V" 1.000000)
					( Origin gFrontEnd )
				)
				( attribute "XY" "(-6450,2775)"
					( Origin gFrontEnd )
				)
				( attribute "CHIPS_PART_NAME" "CAP_A"
					( Origin gPackager )
				)
				( attribute "CDS_PART_NAME" "CAP_A_0603V-22.0UF,4V,20%,X6S,A"
					( Origin gPackager )
				)
				( attribute "CDS_LOCATION" "C5G44"
					( Origin gPackager )
				)
				( attribute "CDS_SEC" "1"
					( Origin gPackager )
				)
				( attribute "SEC" "1"
					( Origin gPackager )
				)
				( attribute "SIDE_SKU" "1S"
					( Origin gFrontEnd )
				)
				( objectStatus "C5G44" )
				( pin "a"
					( attribute "PN" "1"
						( Origin gPackager )
					)
					( objectStatus "C5G44.1" )
				)
				( pin "b"
					( attribute "PN" "2"
						( Origin gPackager )
					)
					( objectStatus "C5G44.2" )
				)
			)
			( gate "@baseboard_fab2_lib.baseboard_fab2(sch_1):page242_i56"
				( attribute "CDS_LIB" "dev_discrete"
					( Origin gPackager )
				)
				( attribute "LOCATION" "C5G43"
					( Origin gFrontEnd )
				)
				( attribute "MATERIAL" "X6S"
					( Origin gFrontEnd )
				)
				( attribute "PACK_TYPE" "0603V"
					( Origin gFrontEnd )
				)
				( attribute "PART_NUMBER" "E15431-004"
					( Origin gFrontEnd )
				)
				( attribute "PHYS_PAGE" "242"
					( Origin gFrontEnd )
				)
				( attribute "ROOM" "PVDDQ_KLM"
					( Origin gFrontEnd )
				)
				( attribute "ROT" "0"
					( Origin gFrontEnd )
				)
				( attribute "TOLERANCE" "20%"
					( Origin gFrontEnd )
				)
				( attribute "VALUE" "22.0UF"
					( Origin gFrontEnd )
				)
				( attribute "VER" "1"
					( Origin gFrontEnd )
				)
				( attribute "VOLTAGE" "4V"
					( Units "uVoltage" "V" 1.000000)
					( Origin gFrontEnd )
				)
				( attribute "XY" "(-6800,2775)"
					( Origin gFrontEnd )
				)
				( attribute "CHIPS_PART_NAME" "CAP_A"
					( Origin gPackager )
				)
				( attribute "CDS_PART_NAME" "CAP_A_0603V-22.0UF,4V,20%,X6S,A"
					( Origin gPackager )
				)
				( attribute "CDS_LOCATION" "C5G43"
					( Origin gPackager )
				)
				( attribute "CDS_SEC" "1"
					( Origin gPackager )
				)
				( attribute "SEC" "1"
					( Origin gPackager )
				)
				( attribute "SIDE_SKU" "1S"
					( Origin gFrontEnd )
				)
				( objectStatus "C5G43" )
				( pin "a"
					( attribute "PN" "1"
						( Origin gPackager )
					)
					( objectStatus "C5G43.1" )
				)
				( pin "b"
					( attribute "PN" "2"
						( Origin gPackager )
					)
					( objectStatus "C5G43.2" )
				)
			)
			( gate "@baseboard_fab2_lib.baseboard_fab2(sch_1):page242_i57"
				( attribute "CDS_LIB" "dev_discrete"
					( Origin gPackager )
				)
				( attribute "LOCATION" "C5G48"
					( Origin gFrontEnd )
				)
				( attribute "MATERIAL" "X6S"
					( Origin gFrontEnd )
				)
				( attribute "PACK_TYPE" "0603V"
					( Origin gFrontEnd )
				)
				( attribute "PART_NUMBER" "E15431-004"
					( Origin gFrontEnd )
				)
				( attribute "PHYS_PAGE" "242"
					( Origin gFrontEnd )
				)
				( attribute "ROOM" "PVDDQ_KLM"
					( Origin gFrontEnd )
				)
				( attribute "ROT" "0"
					( Origin gFrontEnd )
				)
				( attribute "TOLERANCE" "20%"
					( Origin gFrontEnd )
				)
				( attribute "VALUE" "22.0UF"
					( Origin gFrontEnd )
				)
				( attribute "VER" "1"
					( Origin gFrontEnd )
				)
				( attribute "VOLTAGE" "4V"
					( Units "uVoltage" "V" 1.000000)
					( Origin gFrontEnd )
				)
				( attribute "XY" "(-5250,2775)"
					( Origin gFrontEnd )
				)
				( attribute "CHIPS_PART_NAME" "CAP_A"
					( Origin gPackager )
				)
				( attribute "CDS_PART_NAME" "CAP_A_0603V-22.0UF,4V,20%,X6S,A"
					( Origin gPackager )
				)
				( attribute "CDS_LOCATION" "C5G48"
					( Origin gPackager )
				)
				( attribute "CDS_SEC" "1"
					( Origin gPackager )
				)
				( attribute "SEC" "1"
					( Origin gPackager )
				)
				( attribute "SIDE_SKU" "1S"
					( Origin gFrontEnd )
				)
				( objectStatus "C5G48" )
				( pin "a"
					( attribute "PN" "1"
						( Origin gPackager )
					)
					( objectStatus "C5G48.1" )
				)
				( pin "b"
					( attribute "PN" "2"
						( Origin gPackager )
					)
					( objectStatus "C5G48.2" )
				)
			)
			( gate "@baseboard_fab2_lib.baseboard_fab2(sch_1):page242_i58"
				( attribute "CDS_LIB" "dev_discrete"
					( Origin gPackager )
				)
				( attribute "LOCATION" "C5G47"
					( Origin gFrontEnd )
				)
				( attribute "MATERIAL" "X6S"
					( Origin gFrontEnd )
				)
				( attribute "PACK_TYPE" "0603V"
					( Origin gFrontEnd )
				)
				( attribute "PART_NUMBER" "E15431-004"
					( Origin gFrontEnd )
				)
				( attribute "PHYS_PAGE" "242"
					( Origin gFrontEnd )
				)
				( attribute "ROOM" "PVDDQ_KLM"
					( Origin gFrontEnd )
				)
				( attribute "ROT" "0"
					( Origin gFrontEnd )
				)
				( attribute "TOLERANCE" "20%"
					( Origin gFrontEnd )
				)
				( attribute "VALUE" "22.0UF"
					( Origin gFrontEnd )
				)
				( attribute "VER" "1"
					( Origin gFrontEnd )
				)
				( attribute "VOLTAGE" "4V"
					( Units "uVoltage" "V" 1.000000)
					( Origin gFrontEnd )
				)
				( attribute "XY" "(-5550,2775)"
					( Origin gFrontEnd )
				)
				( attribute "CHIPS_PART_NAME" "CAP_A"
					( Origin gPackager )
				)
				( attribute "CDS_PART_NAME" "CAP_A_0603V-22.0UF,4V,20%,X6S,A"
					( Origin gPackager )
				)
				( attribute "CDS_LOCATION" "C5G47"
					( Origin gPackager )
				)
				( attribute "CDS_SEC" "1"
					( Origin gPackager )
				)
				( attribute "SEC" "1"
					( Origin gPackager )
				)
				( attribute "SIDE_SKU" "1S"
					( Origin gFrontEnd )
				)
				( objectStatus "C5G47" )
				( pin "a"
					( attribute "PN" "1"
						( Origin gPackager )
					)
					( objectStatus "C5G47.1" )
				)
				( pin "b"
					( attribute "PN" "2"
						( Origin gPackager )
					)
					( objectStatus "C5G47.2" )
				)
			)
			( gate "@baseboard_fab2_lib.baseboard_fab2(sch_1):page242_i59"
				( attribute "CDS_LIB" "dev_discrete"
					( Origin gPackager )
				)
				( attribute "LOCATION" "C5G46"
					( Origin gFrontEnd )
				)
				( attribute "MATERIAL" "X6S"
					( Origin gFrontEnd )
				)
				( attribute "PACK_TYPE" "0603V"
					( Origin gFrontEnd )
				)
				( attribute "PART_NUMBER" "E15431-004"
					( Origin gFrontEnd )
				)
				( attribute "PHYS_PAGE" "242"
					( Origin gFrontEnd )
				)
				( attribute "ROOM" "PVDDQ_KLM"
					( Origin gFrontEnd )
				)
				( attribute "ROT" "0"
					( Origin gFrontEnd )
				)
				( attribute "TOLERANCE" "20%"
					( Origin gFrontEnd )
				)
				( attribute "VALUE" "22.0UF"
					( Origin gFrontEnd )
				)
				( attribute "VER" "1"
					( Origin gFrontEnd )
				)
				( attribute "VOLTAGE" "4V"
					( Units "uVoltage" "V" 1.000000)
					( Origin gFrontEnd )
				)
				( attribute "XY" "(-5850,2775)"
					( Origin gFrontEnd )
				)
				( attribute "CHIPS_PART_NAME" "CAP_A"
					( Origin gPackager )
				)
				( attribute "CDS_PART_NAME" "CAP_A_0603V-22.0UF,4V,20%,X6S,A"
					( Origin gPackager )
				)
				( attribute "CDS_LOCATION" "C5G46"
					( Origin gPackager )
				)
				( attribute "CDS_SEC" "1"
					( Origin gPackager )
				)
				( attribute "SEC" "1"
					( Origin gPackager )
				)
				( attribute "SIDE_SKU" "1S"
					( Origin gFrontEnd )
				)
				( objectStatus "C5G46" )
				( pin "a"
					( attribute "PN" "1"
						( Origin gPackager )
					)
					( objectStatus "C5G46.1" )
				)
				( pin "b"
					( attribute "PN" "2"
						( Origin gPackager )
					)
					( objectStatus "C5G46.2" )
				)
			)
			( gate "@baseboard_fab2_lib.baseboard_fab2(sch_1):page242_i60"
				( attribute "CDS_LIB" "dev_discrete"
					( Origin gPackager )
				)
				( attribute "LOCATION" "C5G45"
					( Origin gFrontEnd )
				)
				( attribute "MATERIAL" "X6S"
					( Origin gFrontEnd )
				)
				( attribute "PACK_TYPE" "0603V"
					( Origin gFrontEnd )
				)
				( attribute "PART_NUMBER" "E15431-004"
					( Origin gFrontEnd )
				)
				( attribute "PHYS_PAGE" "242"
					( Origin gFrontEnd )
				)
				( attribute "ROOM" "PVDDQ_KLM"
					( Origin gFrontEnd )
				)
				( attribute "ROT" "0"
					( Origin gFrontEnd )
				)
				( attribute "TOLERANCE" "20%"
					( Origin gFrontEnd )
				)
				( attribute "VALUE" "22.0UF"
					( Origin gFrontEnd )
				)
				( attribute "VER" "1"
					( Origin gFrontEnd )
				)
				( attribute "VOLTAGE" "4V"
					( Units "uVoltage" "V" 1.000000)
					( Origin gFrontEnd )
				)
				( attribute "XY" "(-6150,2775)"
					( Origin gFrontEnd )
				)
				( attribute "CHIPS_PART_NAME" "CAP_A"
					( Origin gPackager )
				)
				( attribute "CDS_PART_NAME" "CAP_A_0603V-22.0UF,4V,20%,X6S,A"
					( Origin gPackager )
				)
				( attribute "CDS_LOCATION" "C5G45"
					( Origin gPackager )
				)
				( attribute "CDS_SEC" "1"
					( Origin gPackager )
				)
				( attribute "SEC" "1"
					( Origin gPackager )
				)
				( attribute "SIDE_SKU" "1S"
					( Origin gFrontEnd )
				)
				( objectStatus "C5G45" )
				( pin "a"
					( attribute "PN" "1"
						( Origin gPackager )
					)
					( objectStatus "C5G45.1" )
				)
				( pin "b"
					( attribute "PN" "2"
						( Origin gPackager )
					)
					( objectStatus "C5G45.2" )
				)
			)
			( gate "@baseboard_fab2_lib.baseboard_fab2(sch_1):page242_i61"
				( attribute "CDS_LIB" "dev_discrete"
					( Origin gPackager )
				)
				( attribute "LOCATION" "C5G49"
					( Origin gFrontEnd )
				)
				( attribute "MATERIAL" "X6S"
					( Origin gFrontEnd )
				)
				( attribute "PACK_TYPE" "0603V"
					( Origin gFrontEnd )
				)
				( attribute "PART_NUMBER" "E15431-004"
					( Origin gFrontEnd )
				)
				( attribute "PHYS_PAGE" "242"
					( Origin gFrontEnd )
				)
				( attribute "ROOM" "PVDDQ_KLM"
					( Origin gFrontEnd )
				)
				( attribute "ROT" "0"
					( Origin gFrontEnd )
				)
				( attribute "TOLERANCE" "20%"
					( Origin gFrontEnd )
				)
				( attribute "VALUE" "22.0UF"
					( Origin gFrontEnd )
				)
				( attribute "VER" "1"
					( Origin gFrontEnd )
				)
				( attribute "VOLTAGE" "4V"
					( Units "uVoltage" "V" 1.000000)
					( Origin gFrontEnd )
				)
				( attribute "XY" "(-4950,2775)"
					( Origin gFrontEnd )
				)
				( attribute "CHIPS_PART_NAME" "CAP_A"
					( Origin gPackager )
				)
				( attribute "CDS_PART_NAME" "CAP_A_0603V-22.0UF,4V,20%,X6S,A"
					( Origin gPackager )
				)
				( attribute "CDS_LOCATION" "C5G49"
					( Origin gPackager )
				)
				( attribute "CDS_SEC" "1"
					( Origin gPackager )
				)
				( attribute "SEC" "1"
					( Origin gPackager )
				)
				( attribute "SIDE_SKU" "1S"
					( Origin gFrontEnd )
				)
				( objectStatus "C5G49" )
				( pin "a"
					( attribute "PN" "1"
						( Origin gPackager )
					)
					( objectStatus "C5G49.1" )
				)
				( pin "b"
					( attribute "PN" "2"
						( Origin gPackager )
					)
					( objectStatus "C5G49.2" )
				)
			)
			( gate "@baseboard_fab2_lib.baseboard_fab2(sch_1):page242_i62"
				( attribute "CDS_LIB" "dev_discrete"
					( Origin gPackager )
				)
				( attribute "LOCATION" "C5G54"
					( Origin gFrontEnd )
				)
				( attribute "MATERIAL" "X6S"
					( Origin gFrontEnd )
				)
				( attribute "PACK_TYPE" "0603V"
					( Origin gFrontEnd )
				)
				( attribute "PART_NUMBER" "E15431-004"
					( Origin gFrontEnd )
				)
				( attribute "PHYS_PAGE" "242"
					( Origin gFrontEnd )
				)
				( attribute "ROOM" "PVDDQ_KLM"
					( Origin gFrontEnd )
				)
				( attribute "ROT" "0"
					( Origin gFrontEnd )
				)
				( attribute "TOLERANCE" "20%"
					( Origin gFrontEnd )
				)
				( attribute "VALUE" "22.0UF"
					( Origin gFrontEnd )
				)
				( attribute "VER" "1"
					( Origin gFrontEnd )
				)
				( attribute "VOLTAGE" "4V"
					( Units "uVoltage" "V" 1.000000)
					( Origin gFrontEnd )
				)
				( attribute "XY" "(-6150,1600)"
					( Origin gFrontEnd )
				)
				( attribute "CHIPS_PART_NAME" "CAP_A"
					( Origin gPackager )
				)
				( attribute "CDS_PART_NAME" "CAP_A_0603V-22.0UF,4V,20%,X6S,A"
					( Origin gPackager )
				)
				( attribute "CDS_LOCATION" "C5G54"
					( Origin gPackager )
				)
				( attribute "CDS_SEC" "1"
					( Origin gPackager )
				)
				( attribute "SEC" "1"
					( Origin gPackager )
				)
				( attribute "SIDE_SKU" "1S"
					( Origin gFrontEnd )
				)
				( objectStatus "C5G54" )
				( pin "a"
					( attribute "PN" "1"
						( Origin gPackager )
					)
					( objectStatus "C5G54.1" )
				)
				( pin "b"
					( attribute "PN" "2"
						( Origin gPackager )
					)
					( objectStatus "C5G54.2" )
				)
			)
			( gate "@baseboard_fab2_lib.baseboard_fab2(sch_1):page242_i63"
				( attribute "CDS_LIB" "dev_discrete"
					( Origin gPackager )
				)
				( attribute "LOCATION" "C5G58"
					( Origin gFrontEnd )
				)
				( attribute "MATERIAL" "X6S"
					( Origin gFrontEnd )
				)
				( attribute "PACK_TYPE" "0603V"
					( Origin gFrontEnd )
				)
				( attribute "PART_NUMBER" "E15431-004"
					( Origin gFrontEnd )
				)
				( attribute "PHYS_PAGE" "242"
					( Origin gFrontEnd )
				)
				( attribute "ROOM" "PVDDQ_KLM"
					( Origin gFrontEnd )
				)
				( attribute "ROT" "0"
					( Origin gFrontEnd )
				)
				( attribute "TOLERANCE" "20%"
					( Origin gFrontEnd )
				)
				( attribute "VALUE" "22.0UF"
					( Origin gFrontEnd )
				)
				( attribute "VER" "1"
					( Origin gFrontEnd )
				)
				( attribute "VOLTAGE" "4V"
					( Units "uVoltage" "V" 1.000000)
					( Origin gFrontEnd )
				)
				( attribute "XY" "(-4950,1600)"
					( Origin gFrontEnd )
				)
				( attribute "CHIPS_PART_NAME" "CAP_A"
					( Origin gPackager )
				)
				( attribute "CDS_PART_NAME" "CAP_A_0603V-22.0UF,4V,20%,X6S,A"
					( Origin gPackager )
				)
				( attribute "CDS_LOCATION" "C5G58"
					( Origin gPackager )
				)
				( attribute "CDS_SEC" "1"
					( Origin gPackager )
				)
				( attribute "SEC" "1"
					( Origin gPackager )
				)
				( attribute "SIDE_SKU" "1S"
					( Origin gFrontEnd )
				)
				( objectStatus "C5G58" )
				( pin "a"
					( attribute "PN" "1"
						( Origin gPackager )
					)
					( objectStatus "C5G58.1" )
				)
				( pin "b"
					( attribute "PN" "2"
						( Origin gPackager )
					)
					( objectStatus "C5G58.2" )
				)
			)
			( gate "@baseboard_fab2_lib.baseboard_fab2(sch_1):page242_i64"
				( attribute "CDS_LIB" "dev_discrete"
					( Origin gPackager )
				)
				( attribute "LOCATION" "C5G57"
					( Origin gFrontEnd )
				)
				( attribute "MATERIAL" "X6S"
					( Origin gFrontEnd )
				)
				( attribute "PACK_TYPE" "0603V"
					( Origin gFrontEnd )
				)
				( attribute "PART_NUMBER" "E15431-004"
					( Origin gFrontEnd )
				)
				( attribute "PHYS_PAGE" "242"
					( Origin gFrontEnd )
				)
				( attribute "ROOM" "PVDDQ_KLM"
					( Origin gFrontEnd )
				)
				( attribute "ROT" "0"
					( Origin gFrontEnd )
				)
				( attribute "TOLERANCE" "20%"
					( Origin gFrontEnd )
				)
				( attribute "VALUE" "22.0UF"
					( Origin gFrontEnd )
				)
				( attribute "VER" "1"
					( Origin gFrontEnd )
				)
				( attribute "VOLTAGE" "4V"
					( Units "uVoltage" "V" 1.000000)
					( Origin gFrontEnd )
				)
				( attribute "XY" "(-5250,1600)"
					( Origin gFrontEnd )
				)
				( attribute "CHIPS_PART_NAME" "CAP_A"
					( Origin gPackager )
				)
				( attribute "CDS_PART_NAME" "CAP_A_0603V-22.0UF,4V,20%,X6S,A"
					( Origin gPackager )
				)
				( attribute "CDS_LOCATION" "C5G57"
					( Origin gPackager )
				)
				( attribute "CDS_SEC" "1"
					( Origin gPackager )
				)
				( attribute "SEC" "1"
					( Origin gPackager )
				)
				( attribute "SIDE_SKU" "1S"
					( Origin gFrontEnd )
				)
				( objectStatus "C5G57" )
				( pin "a"
					( attribute "PN" "1"
						( Origin gPackager )
					)
					( objectStatus "C5G57.1" )
				)
				( pin "b"
					( attribute "PN" "2"
						( Origin gPackager )
					)
					( objectStatus "C5G57.2" )
				)
			)
			( gate "@baseboard_fab2_lib.baseboard_fab2(sch_1):page242_i65"
				( attribute "CDS_LIB" "dev_discrete"
					( Origin gPackager )
				)
				( attribute "LOCATION" "C5G56"
					( Origin gFrontEnd )
				)
				( attribute "MATERIAL" "X6S"
					( Origin gFrontEnd )
				)
				( attribute "PACK_TYPE" "0603V"
					( Origin gFrontEnd )
				)
				( attribute "PART_NUMBER" "E15431-004"
					( Origin gFrontEnd )
				)
				( attribute "PHYS_PAGE" "242"
					( Origin gFrontEnd )
				)
				( attribute "ROOM" "PVDDQ_KLM"
					( Origin gFrontEnd )
				)
				( attribute "ROT" "0"
					( Origin gFrontEnd )
				)
				( attribute "TOLERANCE" "20%"
					( Origin gFrontEnd )
				)
				( attribute "VALUE" "22.0UF"
					( Origin gFrontEnd )
				)
				( attribute "VER" "1"
					( Origin gFrontEnd )
				)
				( attribute "VOLTAGE" "4V"
					( Units "uVoltage" "V" 1.000000)
					( Origin gFrontEnd )
				)
				( attribute "XY" "(-5550,1600)"
					( Origin gFrontEnd )
				)
				( attribute "CHIPS_PART_NAME" "CAP_A"
					( Origin gPackager )
				)
				( attribute "CDS_PART_NAME" "CAP_A_0603V-22.0UF,4V,20%,X6S,A"
					( Origin gPackager )
				)
				( attribute "CDS_LOCATION" "C5G56"
					( Origin gPackager )
				)
				( attribute "CDS_SEC" "1"
					( Origin gPackager )
				)
				( attribute "SEC" "1"
					( Origin gPackager )
				)
				( attribute "SIDE_SKU" "1S"
					( Origin gFrontEnd )
				)
				( objectStatus "C5G56" )
				( pin "a"
					( attribute "PN" "1"
						( Origin gPackager )
					)
					( objectStatus "C5G56.1" )
				)
				( pin "b"
					( attribute "PN" "2"
						( Origin gPackager )
					)
					( objectStatus "C5G56.2" )
				)
			)
			( gate "@baseboard_fab2_lib.baseboard_fab2(sch_1):page242_i66"
				( attribute "CDS_LIB" "dev_discrete"
					( Origin gPackager )
				)
				( attribute "LOCATION" "C5G55"
					( Origin gFrontEnd )
				)
				( attribute "MATERIAL" "X6S"
					( Origin gFrontEnd )
				)
				( attribute "PACK_TYPE" "0603V"
					( Origin gFrontEnd )
				)
				( attribute "PART_NUMBER" "E15431-004"
					( Origin gFrontEnd )
				)
				( attribute "PHYS_PAGE" "242"
					( Origin gFrontEnd )
				)
				( attribute "ROOM" "PVDDQ_KLM"
					( Origin gFrontEnd )
				)
				( attribute "ROT" "0"
					( Origin gFrontEnd )
				)
				( attribute "TOLERANCE" "20%"
					( Origin gFrontEnd )
				)
				( attribute "VALUE" "22.0UF"
					( Origin gFrontEnd )
				)
				( attribute "VER" "1"
					( Origin gFrontEnd )
				)
				( attribute "VOLTAGE" "4V"
					( Units "uVoltage" "V" 1.000000)
					( Origin gFrontEnd )
				)
				( attribute "XY" "(-5850,1600)"
					( Origin gFrontEnd )
				)
				( attribute "CHIPS_PART_NAME" "CAP_A"
					( Origin gPackager )
				)
				( attribute "CDS_PART_NAME" "CAP_A_0603V-22.0UF,4V,20%,X6S,A"
					( Origin gPackager )
				)
				( attribute "CDS_LOCATION" "C5G55"
					( Origin gPackager )
				)
				( attribute "CDS_SEC" "1"
					( Origin gPackager )
				)
				( attribute "SEC" "1"
					( Origin gPackager )
				)
				( attribute "SIDE_SKU" "1S"
					( Origin gFrontEnd )
				)
				( objectStatus "C5G55" )
				( pin "a"
					( attribute "PN" "1"
						( Origin gPackager )
					)
					( objectStatus "C5G55.1" )
				)
				( pin "b"
					( attribute "PN" "2"
						( Origin gPackager )
					)
					( objectStatus "C5G55.2" )
				)
			)
			( gate "@baseboard_fab2_lib.baseboard_fab2(sch_1):page242_i67"
				( attribute "CDS_LIB" "dev_discrete"
					( Origin gPackager )
				)
				( attribute "LOCATION" "C5G53"
					( Origin gFrontEnd )
				)
				( attribute "MATERIAL" "X6S"
					( Origin gFrontEnd )
				)
				( attribute "PACK_TYPE" "0603V"
					( Origin gFrontEnd )
				)
				( attribute "PART_NUMBER" "E15431-004"
					( Origin gFrontEnd )
				)
				( attribute "PHYS_PAGE" "242"
					( Origin gFrontEnd )
				)
				( attribute "ROOM" "PVDDQ_KLM"
					( Origin gFrontEnd )
				)
				( attribute "ROT" "0"
					( Origin gFrontEnd )
				)
				( attribute "TOLERANCE" "20%"
					( Origin gFrontEnd )
				)
				( attribute "VALUE" "22.0UF"
					( Origin gFrontEnd )
				)
				( attribute "VER" "1"
					( Origin gFrontEnd )
				)
				( attribute "VOLTAGE" "4V"
					( Units "uVoltage" "V" 1.000000)
					( Origin gFrontEnd )
				)
				( attribute "XY" "(-6450,1600)"
					( Origin gFrontEnd )
				)
				( attribute "CHIPS_PART_NAME" "CAP_A"
					( Origin gPackager )
				)
				( attribute "CDS_PART_NAME" "CAP_A_0603V-22.0UF,4V,20%,X6S,A"
					( Origin gPackager )
				)
				( attribute "CDS_LOCATION" "C5G53"
					( Origin gPackager )
				)
				( attribute "CDS_SEC" "1"
					( Origin gPackager )
				)
				( attribute "SEC" "1"
					( Origin gPackager )
				)
				( attribute "SIDE_SKU" "1S"
					( Origin gFrontEnd )
				)
				( objectStatus "C5G53" )
				( pin "a"
					( attribute "PN" "1"
						( Origin gPackager )
					)
					( objectStatus "C5G53.1" )
				)
				( pin "b"
					( attribute "PN" "2"
						( Origin gPackager )
					)
					( objectStatus "C5G53.2" )
				)
			)
			( gate "@baseboard_fab2_lib.baseboard_fab2(sch_1):page242_i68"
				( attribute "CDS_LIB" "dev_discrete"
					( Origin gPackager )
				)
				( attribute "LOCATION" "C5G52"
					( Origin gFrontEnd )
				)
				( attribute "MATERIAL" "X6S"
					( Origin gFrontEnd )
				)
				( attribute "PACK_TYPE" "0603V"
					( Origin gFrontEnd )
				)
				( attribute "PART_NUMBER" "E15431-004"
					( Origin gFrontEnd )
				)
				( attribute "PHYS_PAGE" "242"
					( Origin gFrontEnd )
				)
				( attribute "ROOM" "PVDDQ_KLM"
					( Origin gFrontEnd )
				)
				( attribute "ROT" "0"
					( Origin gFrontEnd )
				)
				( attribute "TOLERANCE" "20%"
					( Origin gFrontEnd )
				)
				( attribute "VALUE" "22.0UF"
					( Origin gFrontEnd )
				)
				( attribute "VER" "1"
					( Origin gFrontEnd )
				)
				( attribute "VOLTAGE" "4V"
					( Units "uVoltage" "V" 1.000000)
					( Origin gFrontEnd )
				)
				( attribute "XY" "(-6800,1600)"
					( Origin gFrontEnd )
				)
				( attribute "CHIPS_PART_NAME" "CAP_A"
					( Origin gPackager )
				)
				( attribute "CDS_PART_NAME" "CAP_A_0603V-22.0UF,4V,20%,X6S,A"
					( Origin gPackager )
				)
				( attribute "CDS_LOCATION" "C5G52"
					( Origin gPackager )
				)
				( attribute "CDS_SEC" "1"
					( Origin gPackager )
				)
				( attribute "SEC" "1"
					( Origin gPackager )
				)
				( attribute "SIDE_SKU" "1S"
					( Origin gFrontEnd )
				)
				( objectStatus "C5G52" )
				( pin "a"
					( attribute "PN" "1"
						( Origin gPackager )
					)
					( objectStatus "C5G52.1" )
				)
				( pin "b"
					( attribute "PN" "2"
						( Origin gPackager )
					)
					( objectStatus "C5G52.2" )
				)
			)
			( gate "@baseboard_fab2_lib.baseboard_fab2(sch_1):page242_i69"
				( attribute "CDS_LIB" "dev_discrete"
					( Origin gPackager )
				)
				( attribute "LOCATION" "C5G51"
					( Origin gFrontEnd )
				)
				( attribute "MATERIAL" "X6S"
					( Origin gFrontEnd )
				)
				( attribute "PACK_TYPE" "0603V"
					( Origin gFrontEnd )
				)
				( attribute "PART_NUMBER" "E15431-004"
					( Origin gFrontEnd )
				)
				( attribute "PHYS_PAGE" "242"
					( Origin gFrontEnd )
				)
				( attribute "ROOM" "PVDDQ_KLM"
					( Origin gFrontEnd )
				)
				( attribute "ROT" "0"
					( Origin gFrontEnd )
				)
				( attribute "TOLERANCE" "20%"
					( Origin gFrontEnd )
				)
				( attribute "VALUE" "22.0UF"
					( Origin gFrontEnd )
				)
				( attribute "VER" "1"
					( Origin gFrontEnd )
				)
				( attribute "VOLTAGE" "4V"
					( Units "uVoltage" "V" 1.000000)
					( Origin gFrontEnd )
				)
				( attribute "XY" "(-7100,1600)"
					( Origin gFrontEnd )
				)
				( attribute "CHIPS_PART_NAME" "CAP_A"
					( Origin gPackager )
				)
				( attribute "CDS_PART_NAME" "CAP_A_0603V-22.0UF,4V,20%,X6S,A"
					( Origin gPackager )
				)
				( attribute "CDS_LOCATION" "C5G51"
					( Origin gPackager )
				)
				( attribute "CDS_SEC" "1"
					( Origin gPackager )
				)
				( attribute "SEC" "1"
					( Origin gPackager )
				)
				( attribute "SIDE_SKU" "1S"
					( Origin gFrontEnd )
				)
				( objectStatus "C5G51" )
				( pin "a"
					( attribute "PN" "1"
						( Origin gPackager )
					)
					( objectStatus "C5G51.1" )
				)
				( pin "b"
					( attribute "PN" "2"
						( Origin gPackager )
					)
					( objectStatus "C5G51.2" )
				)
			)
			( gate "@baseboard_fab2_lib.baseboard_fab2(sch_1):page242_i70"
				( attribute "CDS_LIB" "dev_discrete"
					( Origin gPackager )
				)
				( attribute "LOCATION" "C5G50"
					( Origin gFrontEnd )
				)
				( attribute "MATERIAL" "X6S"
					( Origin gFrontEnd )
				)
				( attribute "PACK_TYPE" "0603V"
					( Origin gFrontEnd )
				)
				( attribute "PART_NUMBER" "E15431-004"
					( Origin gFrontEnd )
				)
				( attribute "PHYS_PAGE" "242"
					( Origin gFrontEnd )
				)
				( attribute "ROOM" "PVDDQ_KLM"
					( Origin gFrontEnd )
				)
				( attribute "ROT" "0"
					( Origin gFrontEnd )
				)
				( attribute "TOLERANCE" "20%"
					( Origin gFrontEnd )
				)
				( attribute "VALUE" "22.0UF"
					( Origin gFrontEnd )
				)
				( attribute "VER" "1"
					( Origin gFrontEnd )
				)
				( attribute "VOLTAGE" "4V"
					( Units "uVoltage" "V" 1.000000)
					( Origin gFrontEnd )
				)
				( attribute "XY" "(-7400,1600)"
					( Origin gFrontEnd )
				)
				( attribute "CHIPS_PART_NAME" "CAP_A"
					( Origin gPackager )
				)
				( attribute "CDS_PART_NAME" "CAP_A_0603V-22.0UF,4V,20%,X6S,A"
					( Origin gPackager )
				)
				( attribute "CDS_LOCATION" "C5G50"
					( Origin gPackager )
				)
				( attribute "CDS_SEC" "1"
					( Origin gPackager )
				)
				( attribute "SEC" "1"
					( Origin gPackager )
				)
				( attribute "SIDE_SKU" "1S"
					( Origin gFrontEnd )
				)
				( objectStatus "C5G50" )
				( pin "a"
					( attribute "PN" "1"
						( Origin gPackager )
					)
					( objectStatus "C5G50.1" )
				)
				( pin "b"
					( attribute "PN" "2"
						( Origin gPackager )
					)
					( objectStatus "C5G50.2" )
				)
			)
			( gate "@baseboard_fab2_lib.baseboard_fab2(sch_1):page242_i71"
				( attribute "CDS_LIB" "dev_discrete"
					( Origin gPackager )
				)
				( attribute "LOCATION" "C5G67"
					( Origin gFrontEnd )
				)
				( attribute "MATERIAL" "X6S"
					( Origin gFrontEnd )
				)
				( attribute "PACK_TYPE" "0603V"
					( Origin gFrontEnd )
				)
				( attribute "PART_NUMBER" "E15431-004"
					( Origin gFrontEnd )
				)
				( attribute "PHYS_PAGE" "242"
					( Origin gFrontEnd )
				)
				( attribute "ROOM" "PVDDQ_KLM"
					( Origin gFrontEnd )
				)
				( attribute "ROT" "0"
					( Origin gFrontEnd )
				)
				( attribute "TOLERANCE" "20%"
					( Origin gFrontEnd )
				)
				( attribute "VALUE" "22.0UF"
					( Origin gFrontEnd )
				)
				( attribute "VER" "1"
					( Origin gFrontEnd )
				)
				( attribute "VOLTAGE" "4V"
					( Units "uVoltage" "V" 1.000000)
					( Origin gFrontEnd )
				)
				( attribute "XY" "(-700,2850)"
					( Origin gFrontEnd )
				)
				( attribute "CHIPS_PART_NAME" "CAP_A"
					( Origin gPackager )
				)
				( attribute "CDS_PART_NAME" "CAP_A_0603V-22.0UF,4V,20%,X6S,A"
					( Origin gPackager )
				)
				( attribute "CDS_LOCATION" "C5G67"
					( Origin gPackager )
				)
				( attribute "CDS_SEC" "1"
					( Origin gPackager )
				)
				( attribute "SEC" "1"
					( Origin gPackager )
				)
				( attribute "SIDE_SKU" "1S"
					( Origin gFrontEnd )
				)
				( objectStatus "C5G67" )
				( pin "a"
					( attribute "PN" "1"
						( Origin gPackager )
					)
					( objectStatus "C5G67.1" )
				)
				( pin "b"
					( attribute "PN" "2"
						( Origin gPackager )
					)
					( objectStatus "C5G67.2" )
				)
			)
			( gate "@baseboard_fab2_lib.baseboard_fab2(sch_1):page242_i72"
				( attribute "CDS_LIB" "dev_discrete"
					( Origin gPackager )
				)
				( attribute "LOCATION" "C5G66"
					( Origin gFrontEnd )
				)
				( attribute "MATERIAL" "X6S"
					( Origin gFrontEnd )
				)
				( attribute "PACK_TYPE" "0603V"
					( Origin gFrontEnd )
				)
				( attribute "PART_NUMBER" "E15431-004"
					( Origin gFrontEnd )
				)
				( attribute "PHYS_PAGE" "242"
					( Origin gFrontEnd )
				)
				( attribute "ROOM" "PVDDQ_KLM"
					( Origin gFrontEnd )
				)
				( attribute "ROT" "0"
					( Origin gFrontEnd )
				)
				( attribute "TOLERANCE" "20%"
					( Origin gFrontEnd )
				)
				( attribute "VALUE" "22.0UF"
					( Origin gFrontEnd )
				)
				( attribute "VER" "1"
					( Origin gFrontEnd )
				)
				( attribute "VOLTAGE" "4V"
					( Units "uVoltage" "V" 1.000000)
					( Origin gFrontEnd )
				)
				( attribute "XY" "(-1000,2850)"
					( Origin gFrontEnd )
				)
				( attribute "CHIPS_PART_NAME" "CAP_A"
					( Origin gPackager )
				)
				( attribute "CDS_PART_NAME" "CAP_A_0603V-22.0UF,4V,20%,X6S,A"
					( Origin gPackager )
				)
				( attribute "CDS_LOCATION" "C5G66"
					( Origin gPackager )
				)
				( attribute "CDS_SEC" "1"
					( Origin gPackager )
				)
				( attribute "SEC" "1"
					( Origin gPackager )
				)
				( attribute "SIDE_SKU" "1S"
					( Origin gFrontEnd )
				)
				( objectStatus "C5G66" )
				( pin "a"
					( attribute "PN" "1"
						( Origin gPackager )
					)
					( objectStatus "C5G66.1" )
				)
				( pin "b"
					( attribute "PN" "2"
						( Origin gPackager )
					)
					( objectStatus "C5G66.2" )
				)
			)
			( gate "@baseboard_fab2_lib.baseboard_fab2(sch_1):page242_i73"
				( attribute "CDS_LIB" "dev_discrete"
					( Origin gPackager )
				)
				( attribute "LOCATION" "C5G65"
					( Origin gFrontEnd )
				)
				( attribute "MATERIAL" "X6S"
					( Origin gFrontEnd )
				)
				( attribute "PACK_TYPE" "0603V"
					( Origin gFrontEnd )
				)
				( attribute "PART_NUMBER" "E15431-004"
					( Origin gFrontEnd )
				)
				( attribute "PHYS_PAGE" "242"
					( Origin gFrontEnd )
				)
				( attribute "ROOM" "PVDDQ_KLM"
					( Origin gFrontEnd )
				)
				( attribute "ROT" "0"
					( Origin gFrontEnd )
				)
				( attribute "TOLERANCE" "20%"
					( Origin gFrontEnd )
				)
				( attribute "VALUE" "22.0UF"
					( Origin gFrontEnd )
				)
				( attribute "VER" "1"
					( Origin gFrontEnd )
				)
				( attribute "VOLTAGE" "4V"
					( Units "uVoltage" "V" 1.000000)
					( Origin gFrontEnd )
				)
				( attribute "XY" "(-1300,2850)"
					( Origin gFrontEnd )
				)
				( attribute "CHIPS_PART_NAME" "CAP_A"
					( Origin gPackager )
				)
				( attribute "CDS_PART_NAME" "CAP_A_0603V-22.0UF,4V,20%,X6S,A"
					( Origin gPackager )
				)
				( attribute "CDS_LOCATION" "C5G65"
					( Origin gPackager )
				)
				( attribute "CDS_SEC" "1"
					( Origin gPackager )
				)
				( attribute "SEC" "1"
					( Origin gPackager )
				)
				( attribute "SIDE_SKU" "1S"
					( Origin gFrontEnd )
				)
				( objectStatus "C5G65" )
				( pin "a"
					( attribute "PN" "1"
						( Origin gPackager )
					)
					( objectStatus "C5G65.1" )
				)
				( pin "b"
					( attribute "PN" "2"
						( Origin gPackager )
					)
					( objectStatus "C5G65.2" )
				)
			)
			( gate "@baseboard_fab2_lib.baseboard_fab2(sch_1):page242_i74"
				( attribute "CDS_LIB" "dev_discrete"
					( Origin gPackager )
				)
				( attribute "LOCATION" "C5G64"
					( Origin gFrontEnd )
				)
				( attribute "MATERIAL" "X6S"
					( Origin gFrontEnd )
				)
				( attribute "PACK_TYPE" "0603V"
					( Origin gFrontEnd )
				)
				( attribute "PART_NUMBER" "E15431-004"
					( Origin gFrontEnd )
				)
				( attribute "PHYS_PAGE" "242"
					( Origin gFrontEnd )
				)
				( attribute "ROOM" "PVDDQ_KLM"
					( Origin gFrontEnd )
				)
				( attribute "ROT" "0"
					( Origin gFrontEnd )
				)
				( attribute "TOLERANCE" "20%"
					( Origin gFrontEnd )
				)
				( attribute "VALUE" "22.0UF"
					( Origin gFrontEnd )
				)
				( attribute "VER" "1"
					( Origin gFrontEnd )
				)
				( attribute "VOLTAGE" "4V"
					( Units "uVoltage" "V" 1.000000)
					( Origin gFrontEnd )
				)
				( attribute "XY" "(-1600,2850)"
					( Origin gFrontEnd )
				)
				( attribute "CHIPS_PART_NAME" "CAP_A"
					( Origin gPackager )
				)
				( attribute "CDS_PART_NAME" "CAP_A_0603V-22.0UF,4V,20%,X6S,A"
					( Origin gPackager )
				)
				( attribute "CDS_LOCATION" "C5G64"
					( Origin gPackager )
				)
				( attribute "CDS_SEC" "1"
					( Origin gPackager )
				)
				( attribute "SEC" "1"
					( Origin gPackager )
				)
				( attribute "SIDE_SKU" "1S"
					( Origin gFrontEnd )
				)
				( objectStatus "C5G64" )
				( pin "a"
					( attribute "PN" "1"
						( Origin gPackager )
					)
					( objectStatus "C5G64.1" )
				)
				( pin "b"
					( attribute "PN" "2"
						( Origin gPackager )
					)
					( objectStatus "C5G64.2" )
				)
			)
			( gate "@baseboard_fab2_lib.baseboard_fab2(sch_1):page242_i75"
				( attribute "CDS_LIB" "dev_discrete"
					( Origin gPackager )
				)
				( attribute "LOCATION" "C5G63"
					( Origin gFrontEnd )
				)
				( attribute "MATERIAL" "X6S"
					( Origin gFrontEnd )
				)
				( attribute "PACK_TYPE" "0603V"
					( Origin gFrontEnd )
				)
				( attribute "PART_NUMBER" "E15431-004"
					( Origin gFrontEnd )
				)
				( attribute "PHYS_PAGE" "242"
					( Origin gFrontEnd )
				)
				( attribute "ROOM" "PVDDQ_KLM"
					( Origin gFrontEnd )
				)
				( attribute "ROT" "0"
					( Origin gFrontEnd )
				)
				( attribute "TOLERANCE" "20%"
					( Origin gFrontEnd )
				)
				( attribute "VALUE" "22.0UF"
					( Origin gFrontEnd )
				)
				( attribute "VER" "1"
					( Origin gFrontEnd )
				)
				( attribute "VOLTAGE" "4V"
					( Units "uVoltage" "V" 1.000000)
					( Origin gFrontEnd )
				)
				( attribute "XY" "(-1900,2850)"
					( Origin gFrontEnd )
				)
				( attribute "CHIPS_PART_NAME" "CAP_A"
					( Origin gPackager )
				)
				( attribute "CDS_PART_NAME" "CAP_A_0603V-22.0UF,4V,20%,X6S,A"
					( Origin gPackager )
				)
				( attribute "CDS_LOCATION" "C5G63"
					( Origin gPackager )
				)
				( attribute "CDS_SEC" "1"
					( Origin gPackager )
				)
				( attribute "SEC" "1"
					( Origin gPackager )
				)
				( attribute "SIDE_SKU" "1S"
					( Origin gFrontEnd )
				)
				( objectStatus "C5G63" )
				( pin "a"
					( attribute "PN" "1"
						( Origin gPackager )
					)
					( objectStatus "C5G63.1" )
				)
				( pin "b"
					( attribute "PN" "2"
						( Origin gPackager )
					)
					( objectStatus "C5G63.2" )
				)
			)
			( gate "@baseboard_fab2_lib.baseboard_fab2(sch_1):page242_i76"
				( attribute "CDS_LIB" "dev_discrete"
					( Origin gPackager )
				)
				( attribute "LOCATION" "C5G62"
					( Origin gFrontEnd )
				)
				( attribute "MATERIAL" "X6S"
					( Origin gFrontEnd )
				)
				( attribute "PACK_TYPE" "0603V"
					( Origin gFrontEnd )
				)
				( attribute "PART_NUMBER" "E15431-004"
					( Origin gFrontEnd )
				)
				( attribute "PHYS_PAGE" "242"
					( Origin gFrontEnd )
				)
				( attribute "ROOM" "PVDDQ_KLM"
					( Origin gFrontEnd )
				)
				( attribute "ROT" "0"
					( Origin gFrontEnd )
				)
				( attribute "TOLERANCE" "20%"
					( Origin gFrontEnd )
				)
				( attribute "VALUE" "22.0UF"
					( Origin gFrontEnd )
				)
				( attribute "VER" "1"
					( Origin gFrontEnd )
				)
				( attribute "VOLTAGE" "4V"
					( Units "uVoltage" "V" 1.000000)
					( Origin gFrontEnd )
				)
				( attribute "XY" "(-2200,2850)"
					( Origin gFrontEnd )
				)
				( attribute "CHIPS_PART_NAME" "CAP_A"
					( Origin gPackager )
				)
				( attribute "CDS_PART_NAME" "CAP_A_0603V-22.0UF,4V,20%,X6S,A"
					( Origin gPackager )
				)
				( attribute "CDS_LOCATION" "C5G62"
					( Origin gPackager )
				)
				( attribute "CDS_SEC" "1"
					( Origin gPackager )
				)
				( attribute "SEC" "1"
					( Origin gPackager )
				)
				( attribute "SIDE_SKU" "1S"
					( Origin gFrontEnd )
				)
				( objectStatus "C5G62" )
				( pin "a"
					( attribute "PN" "1"
						( Origin gPackager )
					)
					( objectStatus "C5G62.1" )
				)
				( pin "b"
					( attribute "PN" "2"
						( Origin gPackager )
					)
					( objectStatus "C5G62.2" )
				)
			)
			( gate "@baseboard_fab2_lib.baseboard_fab2(sch_1):page242_i77"
				( attribute "CDS_LIB" "dev_discrete"
					( Origin gPackager )
				)
				( attribute "LOCATION" "C5G61"
					( Origin gFrontEnd )
				)
				( attribute "MATERIAL" "X6S"
					( Origin gFrontEnd )
				)
				( attribute "PACK_TYPE" "0603V"
					( Origin gFrontEnd )
				)
				( attribute "PART_NUMBER" "E15431-004"
					( Origin gFrontEnd )
				)
				( attribute "PHYS_PAGE" "242"
					( Origin gFrontEnd )
				)
				( attribute "ROOM" "PVDDQ_KLM"
					( Origin gFrontEnd )
				)
				( attribute "ROT" "0"
					( Origin gFrontEnd )
				)
				( attribute "TOLERANCE" "20%"
					( Origin gFrontEnd )
				)
				( attribute "VALUE" "22.0UF"
					( Origin gFrontEnd )
				)
				( attribute "VER" "1"
					( Origin gFrontEnd )
				)
				( attribute "VOLTAGE" "4V"
					( Units "uVoltage" "V" 1.000000)
					( Origin gFrontEnd )
				)
				( attribute "XY" "(-2550,2850)"
					( Origin gFrontEnd )
				)
				( attribute "CHIPS_PART_NAME" "CAP_A"
					( Origin gPackager )
				)
				( attribute "CDS_PART_NAME" "CAP_A_0603V-22.0UF,4V,20%,X6S,A"
					( Origin gPackager )
				)
				( attribute "CDS_LOCATION" "C5G61"
					( Origin gPackager )
				)
				( attribute "CDS_SEC" "1"
					( Origin gPackager )
				)
				( attribute "SEC" "1"
					( Origin gPackager )
				)
				( attribute "SIDE_SKU" "1S"
					( Origin gFrontEnd )
				)
				( objectStatus "C5G61" )
				( pin "a"
					( attribute "PN" "1"
						( Origin gPackager )
					)
					( objectStatus "C5G61.1" )
				)
				( pin "b"
					( attribute "PN" "2"
						( Origin gPackager )
					)
					( objectStatus "C5G61.2" )
				)
			)
			( gate "@baseboard_fab2_lib.baseboard_fab2(sch_1):page242_i78"
				( attribute "CDS_LIB" "dev_discrete"
					( Origin gPackager )
				)
				( attribute "LOCATION" "C5G60"
					( Origin gFrontEnd )
				)
				( attribute "MATERIAL" "X6S"
					( Origin gFrontEnd )
				)
				( attribute "PACK_TYPE" "0603V"
					( Origin gFrontEnd )
				)
				( attribute "PART_NUMBER" "E15431-004"
					( Origin gFrontEnd )
				)
				( attribute "PHYS_PAGE" "242"
					( Origin gFrontEnd )
				)
				( attribute "ROOM" "PVDDQ_KLM"
					( Origin gFrontEnd )
				)
				( attribute "ROT" "0"
					( Origin gFrontEnd )
				)
				( attribute "TOLERANCE" "20%"
					( Origin gFrontEnd )
				)
				( attribute "VALUE" "22.0UF"
					( Origin gFrontEnd )
				)
				( attribute "VER" "1"
					( Origin gFrontEnd )
				)
				( attribute "VOLTAGE" "4V"
					( Units "uVoltage" "V" 1.000000)
					( Origin gFrontEnd )
				)
				( attribute "XY" "(-2850,2850)"
					( Origin gFrontEnd )
				)
				( attribute "CHIPS_PART_NAME" "CAP_A"
					( Origin gPackager )
				)
				( attribute "CDS_PART_NAME" "CAP_A_0603V-22.0UF,4V,20%,X6S,A"
					( Origin gPackager )
				)
				( attribute "CDS_LOCATION" "C5G60"
					( Origin gPackager )
				)
				( attribute "CDS_SEC" "1"
					( Origin gPackager )
				)
				( attribute "SEC" "1"
					( Origin gPackager )
				)
				( attribute "SIDE_SKU" "1S"
					( Origin gFrontEnd )
				)
				( objectStatus "C5G60" )
				( pin "a"
					( attribute "PN" "1"
						( Origin gPackager )
					)
					( objectStatus "C5G60.1" )
				)
				( pin "b"
					( attribute "PN" "2"
						( Origin gPackager )
					)
					( objectStatus "C5G60.2" )
				)
			)
			( gate "@baseboard_fab2_lib.baseboard_fab2(sch_1):page242_i79"
				( attribute "CDS_LIB" "dev_discrete"
					( Origin gPackager )
				)
				( attribute "LOCATION" "C5G59"
					( Origin gFrontEnd )
				)
				( attribute "MATERIAL" "X6S"
					( Origin gFrontEnd )
				)
				( attribute "PACK_TYPE" "0603V"
					( Origin gFrontEnd )
				)
				( attribute "PART_NUMBER" "E15431-004"
					( Origin gFrontEnd )
				)
				( attribute "PHYS_PAGE" "242"
					( Origin gFrontEnd )
				)
				( attribute "ROOM" "PVDDQ_KLM"
					( Origin gFrontEnd )
				)
				( attribute "ROT" "0"
					( Origin gFrontEnd )
				)
				( attribute "TOLERANCE" "20%"
					( Origin gFrontEnd )
				)
				( attribute "VALUE" "22.0UF"
					( Origin gFrontEnd )
				)
				( attribute "VER" "1"
					( Origin gFrontEnd )
				)
				( attribute "VOLTAGE" "4V"
					( Units "uVoltage" "V" 1.000000)
					( Origin gFrontEnd )
				)
				( attribute "XY" "(-3150,2850)"
					( Origin gFrontEnd )
				)
				( attribute "CHIPS_PART_NAME" "CAP_A"
					( Origin gPackager )
				)
				( attribute "CDS_PART_NAME" "CAP_A_0603V-22.0UF,4V,20%,X6S,A"
					( Origin gPackager )
				)
				( attribute "CDS_LOCATION" "C5G59"
					( Origin gPackager )
				)
				( attribute "CDS_SEC" "1"
					( Origin gPackager )
				)
				( attribute "SEC" "1"
					( Origin gPackager )
				)
				( attribute "SIDE_SKU" "1S"
					( Origin gFrontEnd )
				)
				( objectStatus "C5G59" )
				( pin "a"
					( attribute "PN" "1"
						( Origin gPackager )
					)
					( objectStatus "C5G59.1" )
				)
				( pin "b"
					( attribute "PN" "2"
						( Origin gPackager )
					)
					( objectStatus "C5G59.2" )
				)
			)
			( gate "@baseboard_fab2_lib.baseboard_fab2(sch_1):page242_i80"
				( attribute "CDS_LIB" "dev_discrete"
					( Origin gPackager )
				)
				( attribute "LOCATION" "C5G76"
					( Origin gFrontEnd )
				)
				( attribute "MATERIAL" "X6S"
					( Origin gFrontEnd )
				)
				( attribute "PACK_TYPE" "0603V"
					( Origin gFrontEnd )
				)
				( attribute "PART_NUMBER" "E15431-004"
					( Origin gFrontEnd )
				)
				( attribute "PHYS_PAGE" "242"
					( Origin gFrontEnd )
				)
				( attribute "ROOM" "PVDDQ_KLM"
					( Origin gFrontEnd )
				)
				( attribute "ROT" "0"
					( Origin gFrontEnd )
				)
				( attribute "TOLERANCE" "20%"
					( Origin gFrontEnd )
				)
				( attribute "VALUE" "22.0UF"
					( Origin gFrontEnd )
				)
				( attribute "VER" "1"
					( Origin gFrontEnd )
				)
				( attribute "VOLTAGE" "4V"
					( Units "uVoltage" "V" 1.000000)
					( Origin gFrontEnd )
				)
				( attribute "XY" "(-700,1650)"
					( Origin gFrontEnd )
				)
				( attribute "CHIPS_PART_NAME" "CAP_A"
					( Origin gPackager )
				)
				( attribute "CDS_PART_NAME" "CAP_A_0603V-22.0UF,4V,20%,X6S,A"
					( Origin gPackager )
				)
				( attribute "CDS_LOCATION" "C5G76"
					( Origin gPackager )
				)
				( attribute "CDS_SEC" "1"
					( Origin gPackager )
				)
				( attribute "SEC" "1"
					( Origin gPackager )
				)
				( attribute "SIDE_SKU" "1S"
					( Origin gFrontEnd )
				)
				( objectStatus "C5G76" )
				( pin "a"
					( attribute "PN" "1"
						( Origin gPackager )
					)
					( objectStatus "C5G76.1" )
				)
				( pin "b"
					( attribute "PN" "2"
						( Origin gPackager )
					)
					( objectStatus "C5G76.2" )
				)
			)
			( gate "@baseboard_fab2_lib.baseboard_fab2(sch_1):page242_i81"
				( attribute "CDS_LIB" "dev_discrete"
					( Origin gPackager )
				)
				( attribute "LOCATION" "C5G75"
					( Origin gFrontEnd )
				)
				( attribute "MATERIAL" "X6S"
					( Origin gFrontEnd )
				)
				( attribute "PACK_TYPE" "0603V"
					( Origin gFrontEnd )
				)
				( attribute "PART_NUMBER" "E15431-004"
					( Origin gFrontEnd )
				)
				( attribute "PHYS_PAGE" "242"
					( Origin gFrontEnd )
				)
				( attribute "ROOM" "PVDDQ_KLM"
					( Origin gFrontEnd )
				)
				( attribute "ROT" "0"
					( Origin gFrontEnd )
				)
				( attribute "TOLERANCE" "20%"
					( Origin gFrontEnd )
				)
				( attribute "VALUE" "22.0UF"
					( Origin gFrontEnd )
				)
				( attribute "VER" "1"
					( Origin gFrontEnd )
				)
				( attribute "VOLTAGE" "4V"
					( Units "uVoltage" "V" 1.000000)
					( Origin gFrontEnd )
				)
				( attribute "XY" "(-1000,1650)"
					( Origin gFrontEnd )
				)
				( attribute "CHIPS_PART_NAME" "CAP_A"
					( Origin gPackager )
				)
				( attribute "CDS_PART_NAME" "CAP_A_0603V-22.0UF,4V,20%,X6S,A"
					( Origin gPackager )
				)
				( attribute "CDS_LOCATION" "C5G75"
					( Origin gPackager )
				)
				( attribute "CDS_SEC" "1"
					( Origin gPackager )
				)
				( attribute "SEC" "1"
					( Origin gPackager )
				)
				( attribute "SIDE_SKU" "1S"
					( Origin gFrontEnd )
				)
				( objectStatus "C5G75" )
				( pin "a"
					( attribute "PN" "1"
						( Origin gPackager )
					)
					( objectStatus "C5G75.1" )
				)
				( pin "b"
					( attribute "PN" "2"
						( Origin gPackager )
					)
					( objectStatus "C5G75.2" )
				)
			)
			( gate "@baseboard_fab2_lib.baseboard_fab2(sch_1):page242_i82"
				( attribute "CDS_LIB" "dev_discrete"
					( Origin gPackager )
				)
				( attribute "LOCATION" "C5G74"
					( Origin gFrontEnd )
				)
				( attribute "MATERIAL" "X6S"
					( Origin gFrontEnd )
				)
				( attribute "PACK_TYPE" "0603V"
					( Origin gFrontEnd )
				)
				( attribute "PART_NUMBER" "E15431-004"
					( Origin gFrontEnd )
				)
				( attribute "PHYS_PAGE" "242"
					( Origin gFrontEnd )
				)
				( attribute "ROOM" "PVDDQ_KLM"
					( Origin gFrontEnd )
				)
				( attribute "ROT" "0"
					( Origin gFrontEnd )
				)
				( attribute "TOLERANCE" "20%"
					( Origin gFrontEnd )
				)
				( attribute "VALUE" "22.0UF"
					( Origin gFrontEnd )
				)
				( attribute "VER" "1"
					( Origin gFrontEnd )
				)
				( attribute "VOLTAGE" "4V"
					( Units "uVoltage" "V" 1.000000)
					( Origin gFrontEnd )
				)
				( attribute "XY" "(-1300,1650)"
					( Origin gFrontEnd )
				)
				( attribute "CHIPS_PART_NAME" "CAP_A"
					( Origin gPackager )
				)
				( attribute "CDS_PART_NAME" "CAP_A_0603V-22.0UF,4V,20%,X6S,A"
					( Origin gPackager )
				)
				( attribute "CDS_LOCATION" "C5G74"
					( Origin gPackager )
				)
				( attribute "CDS_SEC" "1"
					( Origin gPackager )
				)
				( attribute "SEC" "1"
					( Origin gPackager )
				)
				( attribute "SIDE_SKU" "1S"
					( Origin gFrontEnd )
				)
				( objectStatus "C5G74" )
				( pin "a"
					( attribute "PN" "1"
						( Origin gPackager )
					)
					( objectStatus "C5G74.1" )
				)
				( pin "b"
					( attribute "PN" "2"
						( Origin gPackager )
					)
					( objectStatus "C5G74.2" )
				)
			)
			( gate "@baseboard_fab2_lib.baseboard_fab2(sch_1):page242_i83"
				( attribute "CDS_LIB" "dev_discrete"
					( Origin gPackager )
				)
				( attribute "LOCATION" "C5G73"
					( Origin gFrontEnd )
				)
				( attribute "MATERIAL" "X6S"
					( Origin gFrontEnd )
				)
				( attribute "PACK_TYPE" "0603V"
					( Origin gFrontEnd )
				)
				( attribute "PART_NUMBER" "E15431-004"
					( Origin gFrontEnd )
				)
				( attribute "PHYS_PAGE" "242"
					( Origin gFrontEnd )
				)
				( attribute "ROOM" "PVDDQ_KLM"
					( Origin gFrontEnd )
				)
				( attribute "ROT" "0"
					( Origin gFrontEnd )
				)
				( attribute "TOLERANCE" "20%"
					( Origin gFrontEnd )
				)
				( attribute "VALUE" "22.0UF"
					( Origin gFrontEnd )
				)
				( attribute "VER" "1"
					( Origin gFrontEnd )
				)
				( attribute "VOLTAGE" "4V"
					( Units "uVoltage" "V" 1.000000)
					( Origin gFrontEnd )
				)
				( attribute "XY" "(-1600,1650)"
					( Origin gFrontEnd )
				)
				( attribute "CHIPS_PART_NAME" "CAP_A"
					( Origin gPackager )
				)
				( attribute "CDS_PART_NAME" "CAP_A_0603V-22.0UF,4V,20%,X6S,A"
					( Origin gPackager )
				)
				( attribute "CDS_LOCATION" "C5G73"
					( Origin gPackager )
				)
				( attribute "CDS_SEC" "1"
					( Origin gPackager )
				)
				( attribute "SEC" "1"
					( Origin gPackager )
				)
				( attribute "SIDE_SKU" "1S"
					( Origin gFrontEnd )
				)
				( objectStatus "C5G73" )
				( pin "a"
					( attribute "PN" "1"
						( Origin gPackager )
					)
					( objectStatus "C5G73.1" )
				)
				( pin "b"
					( attribute "PN" "2"
						( Origin gPackager )
					)
					( objectStatus "C5G73.2" )
				)
			)
			( gate "@baseboard_fab2_lib.baseboard_fab2(sch_1):page242_i84"
				( attribute "CDS_LIB" "dev_discrete"
					( Origin gPackager )
				)
				( attribute "LOCATION" "C5G72"
					( Origin gFrontEnd )
				)
				( attribute "MATERIAL" "X6S"
					( Origin gFrontEnd )
				)
				( attribute "PACK_TYPE" "0603V"
					( Origin gFrontEnd )
				)
				( attribute "PART_NUMBER" "E15431-004"
					( Origin gFrontEnd )
				)
				( attribute "PHYS_PAGE" "242"
					( Origin gFrontEnd )
				)
				( attribute "ROOM" "PVDDQ_KLM"
					( Origin gFrontEnd )
				)
				( attribute "ROT" "0"
					( Origin gFrontEnd )
				)
				( attribute "TOLERANCE" "20%"
					( Origin gFrontEnd )
				)
				( attribute "VALUE" "22.0UF"
					( Origin gFrontEnd )
				)
				( attribute "VER" "1"
					( Origin gFrontEnd )
				)
				( attribute "VOLTAGE" "4V"
					( Units "uVoltage" "V" 1.000000)
					( Origin gFrontEnd )
				)
				( attribute "XY" "(-1900,1650)"
					( Origin gFrontEnd )
				)
				( attribute "CHIPS_PART_NAME" "CAP_A"
					( Origin gPackager )
				)
				( attribute "CDS_PART_NAME" "CAP_A_0603V-22.0UF,4V,20%,X6S,A"
					( Origin gPackager )
				)
				( attribute "CDS_LOCATION" "C5G72"
					( Origin gPackager )
				)
				( attribute "CDS_SEC" "1"
					( Origin gPackager )
				)
				( attribute "SEC" "1"
					( Origin gPackager )
				)
				( attribute "SIDE_SKU" "1S"
					( Origin gFrontEnd )
				)
				( objectStatus "C5G72" )
				( pin "a"
					( attribute "PN" "1"
						( Origin gPackager )
					)
					( objectStatus "C5G72.1" )
				)
				( pin "b"
					( attribute "PN" "2"
						( Origin gPackager )
					)
					( objectStatus "C5G72.2" )
				)
			)
			( gate "@baseboard_fab2_lib.baseboard_fab2(sch_1):page242_i85"
				( attribute "CDS_LIB" "dev_discrete"
					( Origin gPackager )
				)
				( attribute "LOCATION" "C5G71"
					( Origin gFrontEnd )
				)
				( attribute "MATERIAL" "X6S"
					( Origin gFrontEnd )
				)
				( attribute "PACK_TYPE" "0603V"
					( Origin gFrontEnd )
				)
				( attribute "PART_NUMBER" "E15431-004"
					( Origin gFrontEnd )
				)
				( attribute "PHYS_PAGE" "242"
					( Origin gFrontEnd )
				)
				( attribute "ROOM" "PVDDQ_KLM"
					( Origin gFrontEnd )
				)
				( attribute "ROT" "0"
					( Origin gFrontEnd )
				)
				( attribute "TOLERANCE" "20%"
					( Origin gFrontEnd )
				)
				( attribute "VALUE" "22.0UF"
					( Origin gFrontEnd )
				)
				( attribute "VER" "1"
					( Origin gFrontEnd )
				)
				( attribute "VOLTAGE" "4V"
					( Units "uVoltage" "V" 1.000000)
					( Origin gFrontEnd )
				)
				( attribute "XY" "(-2200,1650)"
					( Origin gFrontEnd )
				)
				( attribute "CHIPS_PART_NAME" "CAP_A"
					( Origin gPackager )
				)
				( attribute "CDS_PART_NAME" "CAP_A_0603V-22.0UF,4V,20%,X6S,A"
					( Origin gPackager )
				)
				( attribute "CDS_LOCATION" "C5G71"
					( Origin gPackager )
				)
				( attribute "CDS_SEC" "1"
					( Origin gPackager )
				)
				( attribute "SEC" "1"
					( Origin gPackager )
				)
				( attribute "SIDE_SKU" "1S"
					( Origin gFrontEnd )
				)
				( objectStatus "C5G71" )
				( pin "a"
					( attribute "PN" "1"
						( Origin gPackager )
					)
					( objectStatus "C5G71.1" )
				)
				( pin "b"
					( attribute "PN" "2"
						( Origin gPackager )
					)
					( objectStatus "C5G71.2" )
				)
			)
			( gate "@baseboard_fab2_lib.baseboard_fab2(sch_1):page242_i86"
				( attribute "CDS_LIB" "dev_discrete"
					( Origin gPackager )
				)
				( attribute "LOCATION" "C5G70"
					( Origin gFrontEnd )
				)
				( attribute "MATERIAL" "X6S"
					( Origin gFrontEnd )
				)
				( attribute "PACK_TYPE" "0603V"
					( Origin gFrontEnd )
				)
				( attribute "PART_NUMBER" "E15431-004"
					( Origin gFrontEnd )
				)
				( attribute "PHYS_PAGE" "242"
					( Origin gFrontEnd )
				)
				( attribute "ROOM" "PVDDQ_KLM"
					( Origin gFrontEnd )
				)
				( attribute "ROT" "0"
					( Origin gFrontEnd )
				)
				( attribute "TOLERANCE" "20%"
					( Origin gFrontEnd )
				)
				( attribute "VALUE" "22.0UF"
					( Origin gFrontEnd )
				)
				( attribute "VER" "1"
					( Origin gFrontEnd )
				)
				( attribute "VOLTAGE" "4V"
					( Units "uVoltage" "V" 1.000000)
					( Origin gFrontEnd )
				)
				( attribute "XY" "(-2550,1650)"
					( Origin gFrontEnd )
				)
				( attribute "CHIPS_PART_NAME" "CAP_A"
					( Origin gPackager )
				)
				( attribute "CDS_PART_NAME" "CAP_A_0603V-22.0UF,4V,20%,X6S,A"
					( Origin gPackager )
				)
				( attribute "CDS_LOCATION" "C5G70"
					( Origin gPackager )
				)
				( attribute "CDS_SEC" "1"
					( Origin gPackager )
				)
				( attribute "SEC" "1"
					( Origin gPackager )
				)
				( attribute "SIDE_SKU" "1S"
					( Origin gFrontEnd )
				)
				( objectStatus "C5G70" )
				( pin "a"
					( attribute "PN" "1"
						( Origin gPackager )
					)
					( objectStatus "C5G70.1" )
				)
				( pin "b"
					( attribute "PN" "2"
						( Origin gPackager )
					)
					( objectStatus "C5G70.2" )
				)
			)
			( gate "@baseboard_fab2_lib.baseboard_fab2(sch_1):page242_i87"
				( attribute "CDS_LIB" "dev_discrete"
					( Origin gPackager )
				)
				( attribute "LOCATION" "C5G69"
					( Origin gFrontEnd )
				)
				( attribute "MATERIAL" "X6S"
					( Origin gFrontEnd )
				)
				( attribute "PACK_TYPE" "0603V"
					( Origin gFrontEnd )
				)
				( attribute "PART_NUMBER" "E15431-004"
					( Origin gFrontEnd )
				)
				( attribute "PHYS_PAGE" "242"
					( Origin gFrontEnd )
				)
				( attribute "ROOM" "PVDDQ_KLM"
					( Origin gFrontEnd )
				)
				( attribute "ROT" "0"
					( Origin gFrontEnd )
				)
				( attribute "TOLERANCE" "20%"
					( Origin gFrontEnd )
				)
				( attribute "VALUE" "22.0UF"
					( Origin gFrontEnd )
				)
				( attribute "VER" "1"
					( Origin gFrontEnd )
				)
				( attribute "VOLTAGE" "4V"
					( Units "uVoltage" "V" 1.000000)
					( Origin gFrontEnd )
				)
				( attribute "XY" "(-2850,1650)"
					( Origin gFrontEnd )
				)
				( attribute "CHIPS_PART_NAME" "CAP_A"
					( Origin gPackager )
				)
				( attribute "CDS_PART_NAME" "CAP_A_0603V-22.0UF,4V,20%,X6S,A"
					( Origin gPackager )
				)
				( attribute "CDS_LOCATION" "C5G69"
					( Origin gPackager )
				)
				( attribute "CDS_SEC" "1"
					( Origin gPackager )
				)
				( attribute "SEC" "1"
					( Origin gPackager )
				)
				( attribute "SIDE_SKU" "1S"
					( Origin gFrontEnd )
				)
				( objectStatus "C5G69" )
				( pin "a"
					( attribute "PN" "1"
						( Origin gPackager )
					)
					( objectStatus "C5G69.1" )
				)
				( pin "b"
					( attribute "PN" "2"
						( Origin gPackager )
					)
					( objectStatus "C5G69.2" )
				)
			)
			( gate "@baseboard_fab2_lib.baseboard_fab2(sch_1):page242_i88"
				( attribute "CDS_LIB" "dev_discrete"
					( Origin gPackager )
				)
				( attribute "LOCATION" "C5G68"
					( Origin gFrontEnd )
				)
				( attribute "MATERIAL" "X6S"
					( Origin gFrontEnd )
				)
				( attribute "PACK_TYPE" "0603V"
					( Origin gFrontEnd )
				)
				( attribute "PART_NUMBER" "E15431-004"
					( Origin gFrontEnd )
				)
				( attribute "PHYS_PAGE" "242"
					( Origin gFrontEnd )
				)
				( attribute "ROOM" "PVDDQ_KLM"
					( Origin gFrontEnd )
				)
				( attribute "ROT" "0"
					( Origin gFrontEnd )
				)
				( attribute "TOLERANCE" "20%"
					( Origin gFrontEnd )
				)
				( attribute "VALUE" "22.0UF"
					( Origin gFrontEnd )
				)
				( attribute "VER" "1"
					( Origin gFrontEnd )
				)
				( attribute "VOLTAGE" "4V"
					( Units "uVoltage" "V" 1.000000)
					( Origin gFrontEnd )
				)
				( attribute "XY" "(-3150,1650)"
					( Origin gFrontEnd )
				)
				( attribute "CHIPS_PART_NAME" "CAP_A"
					( Origin gPackager )
				)
				( attribute "CDS_PART_NAME" "CAP_A_0603V-22.0UF,4V,20%,X6S,A"
					( Origin gPackager )
				)
				( attribute "CDS_LOCATION" "C5G68"
					( Origin gPackager )
				)
				( attribute "CDS_SEC" "1"
					( Origin gPackager )
				)
				( attribute "SEC" "1"
					( Origin gPackager )
				)
				( attribute "SIDE_SKU" "1S"
					( Origin gFrontEnd )
				)
				( objectStatus "C5G68" )
				( pin "a"
					( attribute "PN" "1"
						( Origin gPackager )
					)
					( objectStatus "C5G68.1" )
				)
				( pin "b"
					( attribute "PN" "2"
						( Origin gPackager )
					)
					( objectStatus "C5G68.2" )
				)
			)
			( gate "@baseboard_fab2_lib.baseboard_fab2(sch_1):page202_i89"
				( attribute "BOM_COST" "DEBUG"
					( Origin gFrontEnd )
				)
				( attribute "CDS_LIB" "mstr_discrete"
					( Origin gPackager )
				)
				( attribute "LOCATION" "RT3"
					( Origin gFrontEnd )
				)
				( attribute "MATERIAL" "CHIP"
					( Origin gFrontEnd )
				)
				( attribute "PACK_TYPE" "0402"
					( Origin gFrontEnd )
				)
				( attribute "PART_NUMBER" "G21497-005"
					( Origin gFrontEnd )
				)
				( attribute "PHYS_PAGE" "202"
					( Origin gFrontEnd )
				)
				( attribute "ROOM" "BMC_DEBUG_HEADER"
					( Origin gFrontEnd )
				)
				( attribute "ROT" "0"
					( Origin gFrontEnd )
				)
				( attribute "TOLERANCE" "5%"
					( Origin gFrontEnd )
				)
				( attribute "VALUE" "0.0"
					( Origin gFrontEnd )
				)
				( attribute "VER" "1"
					( Origin gFrontEnd )
				)
				( attribute "WATTAGE" "1/16W"
					( Origin gFrontEnd )
				)
				( attribute "XY" "(-4975,950)"
					( Origin gFrontEnd )
				)
				( attribute "CHIPS_PART_NAME" "RES"
					( Origin gPackager )
				)
				( attribute "CDS_PART_NAME" "RES_0402-0.0,5%,1/16W,CHIP,G21A"
					( Origin gPackager )
				)
				( attribute "CDS_LOCATION" "RT3"
					( Origin gPackager )
				)
				( attribute "CDS_SEC" "1"
					( Origin gPackager )
				)
				( attribute "SEC" "1"
					( Origin gPackager )
				)
				( objectStatus "RT3" )
				( pin "a"
					( attribute "PN" "1"
						( Origin gPackager )
					)
					( objectStatus "RT3.1" )
				)
				( pin "b"
					( attribute "PN" "2"
						( Origin gPackager )
					)
					( objectStatus "RT3.2" )
				)
			)
			( gate "@baseboard_fab2_lib.baseboard_fab2(sch_1):page202_i70"
				( attribute "CDS_LIB" "dev_discrete"
					( Origin gPackager )
				)
				( attribute "LOCATION" "CT1"
					( Origin gFrontEnd )
				)
				( attribute "MATERIAL" "X7R"
					( Origin gFrontEnd )
				)
				( attribute "PACK_TYPE" "0402V"
					( Origin gFrontEnd )
				)
				( attribute "PART_NUMBER" "A36096-030"
					( Origin gFrontEnd )
				)
				( attribute "PHYS_PAGE" "202"
					( Origin gFrontEnd )
				)
				( attribute "ROOM" "PVCCIN_CPU0_PWR_VR"
					( Origin gFrontEnd )
				)
				( attribute "ROT" "0"
					( Origin gFrontEnd )
				)
				( attribute "TOLERANCE" "10%"
					( Origin gFrontEnd )
				)
				( attribute "VALUE" "0.1UF"
					( Origin gFrontEnd )
				)
				( attribute "VER" "1"
					( Origin gFrontEnd )
				)
				( attribute "VOLTAGE" "16V"
					( Units "uVoltage" "V" 1.000000)
					( Origin gFrontEnd )
				)
				( attribute "XY" "(-4125,3300)"
					( Origin gFrontEnd )
				)
				( attribute "CHIPS_PART_NAME" "CAP_A"
					( Origin gPackager )
				)
				( attribute "CDS_PART_NAME" "CAP_A_0402V-0.1UF,16V,10%,X7R,A"
					( Origin gPackager )
				)
				( attribute "CDS_LOCATION" "CT1"
					( Origin gPackager )
				)
				( attribute "CDS_SEC" "1"
					( Origin gPackager )
				)
				( attribute "SEC" "1"
					( Origin gPackager )
				)
				( attribute "STATUS" "NOPOP"
					( Origin gFrontEnd )
				)
				( objectStatus "CT1" )
				( pin "a"
					( attribute "PN" "1"
						( Origin gPackager )
					)
					( objectStatus "CT1.1" )
				)
				( pin "b"
					( attribute "PN" "2"
						( Origin gPackager )
					)
					( objectStatus "CT1.2" )
				)
			)
			( gate "@baseboard_fab2_lib.baseboard_fab2(sch_1):page202_i75"
				( attribute "CDS_LIB" "w_hdl"
					( Origin gPackager )
				)
				( attribute "CDS_LMAN_SYM_OUTLINE" "-50,75,50,-75"
					( Origin gPackager )
				)
				( attribute "CDS_LOCATION" "RT2"
					( Origin gPackager )
				)
				( attribute "CDS_SEC" "1"
					( Origin gPackager )
				)
				( attribute "LOCATION" "RT2"
					( Origin gFrontEnd )
				)
				( attribute "PACK_TYPE" "SMD-RG5"
					( Origin gFrontEnd )
				)
				( attribute "PART_NUMBER" "64.3R015.16L"
					( Origin gFrontEnd )
				)
				( attribute "PHYS_PAGE" "202"
					( Origin gFrontEnd )
				)
				( attribute "ROT" "4"
					( Origin gFrontEnd )
				)
				( attribute "VALUE" "3D01R5F-GP"
					( Origin gFrontEnd )
				)
				( attribute "VER" "1"
					( Origin gFrontEnd )
				)
				( attribute "XY" "(-2550,3050)"
					( Origin gFrontEnd )
				)
				( attribute "CHIPS_PART_NAME" "3D01R5F-GP"
					( Origin gPackager )
				)
				( attribute "CDS_PART_NAME" "3D01R5F-GP_SMD-RG5-3D01R5F-GP,A"
					( Origin gPackager )
				)
				( attribute "SEC" "1"
					( Origin gPackager )
				)
				( attribute "STATUS" "NOPOP"
					( Origin gFrontEnd )
				)
				( objectStatus "RT2" )
				( pin "\1\"
					( attribute "PN" "1"
						( Origin gPackager )
					)
					( objectStatus "RT2.1" )
				)
				( pin "\2\"
					( attribute "PN" "2"
						( Origin gPackager )
					)
					( objectStatus "RT2.2" )
				)
			)
			( gate "@baseboard_fab2_lib.baseboard_fab2(sch_1):page202_i76"
				( attribute "CDS_LIB" "w_hdl"
					( Origin gPackager )
				)
				( attribute "CDS_LMAN_SYM_OUTLINE" "-50,25,50,-25"
					( Origin gPackager )
				)
				( attribute "LOCATION" "CT3"
					( Origin gFrontEnd )
				)
				( attribute "PACK_TYPE" "SMD-BCG6"
					( Origin gFrontEnd )
				)
				( attribute "PART_NUMBER" "78.22224.2BL"
					( Origin gFrontEnd )
				)
				( attribute "PHYS_PAGE" "202"
					( Origin gFrontEnd )
				)
				( attribute "ROT" "0"
					( Origin gFrontEnd )
				)
				( attribute "VALUE" "SC2K2P50V3KX-GP"
					( Origin gFrontEnd )
				)
				( attribute "VER" "1"
					( Origin gFrontEnd )
				)
				( attribute "XY" "(-2550,3350)"
					( Origin gFrontEnd )
				)
				( attribute "CHIPS_PART_NAME" "SC2K2P50V3KX-GP"
					( Origin gPackager )
				)
				( attribute "CDS_PART_NAME" "SC2K2P50V3KX-GP_SMD-BCG6-SC2K2A"
					( Origin gPackager )
				)
				( attribute "CDS_LOCATION" "CT3"
					( Origin gPackager )
				)
				( attribute "CDS_SEC" "1"
					( Origin gPackager )
				)
				( attribute "SEC" "1"
					( Origin gPackager )
				)
				( attribute "STATUS" "NOPOP"
					( Origin gFrontEnd )
				)
				( objectStatus "CT3" )
				( pin "\1\"
					( attribute "PN" "1"
						( Origin gPackager )
					)
					( objectStatus "CT3.1" )
				)
				( pin "\2\"
					( attribute "PN" "2"
						( Origin gPackager )
					)
					( objectStatus "CT3.2" )
				)
			)
			( gate "@baseboard_fab2_lib.baseboard_fab2(sch_1):page202_i78"
				( attribute "CDS_LIB" "mstr_discrete"
					( Origin gPackager )
				)
				( attribute "CDS_LOCATION" "CT2"
					( Origin gPackager )
				)
				( attribute "LOCATION" "CT2"
					( Origin gFrontEnd )
				)
				( attribute "MATERIAL" "X7R"
					( Origin gFrontEnd )
				)
				( attribute "PACK_TYPE" "0402LF"
					( Origin gFrontEnd )
				)
				( attribute "PART_NUMBER" "A36096-046"
					( Origin gFrontEnd )
				)
				( attribute "PHYS_PAGE" "202"
					( Origin gFrontEnd )
				)
				( attribute "ROOM" "VDDQ_KLM_PWR_VR"
					( Origin gFrontEnd )
				)
				( attribute "ROT" "0"
					( Origin gFrontEnd )
				)
				( attribute "SEC" "1"
					( Origin gFrontEnd )
				)
				( attribute "SEC_TYPE" "0402LF"
					( Origin gFrontEnd )
				)
				( attribute "TOLERANCE" "10%"
					( Origin gFrontEnd )
				)
				( attribute "VALUE" "1000PF"
					( Origin gFrontEnd )
				)
				( attribute "VER" "1"
					( Origin gFrontEnd )
				)
				( attribute "VOLTAGE" "50V"
					( Units "uVoltage" "V" 1.000000)
					( Origin gFrontEnd )
				)
				( attribute "XY" "(-2350,3875)"
					( Origin gFrontEnd )
				)
				( attribute "CHIPS_PART_NAME" "CAP"
					( Origin gPackager )
				)
				( attribute "CDS_PART_NAME" "CAP_0402LF-1000PF,50V,10%,X7R,A"
					( Origin gPackager )
				)
				( attribute "CDS_SEC" "1"
					( Origin gPackager )
				)
				( attribute "STATUS" "NOPOP"
					( Origin gFrontEnd )
				)
				( objectStatus "CT2" )
				( pin "a"
					( attribute "PN" "1"
						( Origin gPackager )
					)
					( objectStatus "CT2.1" )
				)
				( pin "b"
					( attribute "PN" "2"
						( Origin gPackager )
					)
					( objectStatus "CT2.2" )
				)
			)
			( gate "@baseboard_fab2_lib.baseboard_fab2(sch_1):page202_i81"
				( attribute "CDS_LIB" "dev_discrete"
					( Origin gPackager )
				)
				( attribute "LOCATION" "CT6"
					( Origin gFrontEnd )
				)
				( attribute "MATERIAL" "X7R"
					( Origin gFrontEnd )
				)
				( attribute "PACK_TYPE" "0402V"
					( Origin gFrontEnd )
				)
				( attribute "PART_NUMBER" "A36096-030"
					( Origin gFrontEnd )
				)
				( attribute "PHYS_PAGE" "202"
					( Origin gFrontEnd )
				)
				( attribute "ROOM" "PVCCIN_CPU0_PWR_VR"
					( Origin gFrontEnd )
				)
				( attribute "ROT" "0"
					( Origin gFrontEnd )
				)
				( attribute "TOLERANCE" "10%"
					( Origin gFrontEnd )
				)
				( attribute "VALUE" "0.1UF"
					( Origin gFrontEnd )
				)
				( attribute "VER" "1"
					( Origin gFrontEnd )
				)
				( attribute "VOLTAGE" "16V"
					( Units "uVoltage" "V" 1.000000)
					( Origin gFrontEnd )
				)
				( attribute "XY" "(-4175,675)"
					( Origin gFrontEnd )
				)
				( attribute "CHIPS_PART_NAME" "CAP_A"
					( Origin gPackager )
				)
				( attribute "CDS_PART_NAME" "CAP_A_0402V-0.1UF,16V,10%,X7R,A"
					( Origin gPackager )
				)
				( attribute "CDS_LOCATION" "CT6"
					( Origin gPackager )
				)
				( attribute "CDS_SEC" "1"
					( Origin gPackager )
				)
				( attribute "SEC" "1"
					( Origin gPackager )
				)
				( attribute "STATUS" "NOPOP"
					( Origin gFrontEnd )
				)
				( objectStatus "CT6" )
				( pin "a"
					( attribute "PN" "1"
						( Origin gPackager )
					)
					( objectStatus "CT6.1" )
				)
				( pin "b"
					( attribute "PN" "2"
						( Origin gPackager )
					)
					( objectStatus "CT6.2" )
				)
			)
			( gate "@baseboard_fab2_lib.baseboard_fab2(sch_1):page202_i82"
				( attribute "CDS_LIB" "w_hdl"
					( Origin gPackager )
				)
				( attribute "CDS_LMAN_SYM_OUTLINE" "-50,25,50,-25"
					( Origin gPackager )
				)
				( attribute "LOCATION" "CT5"
					( Origin gFrontEnd )
				)
				( attribute "PACK_TYPE" "SMD-BCG6"
					( Origin gFrontEnd )
				)
				( attribute "PART_NUMBER" "78.22224.2BL"
					( Origin gFrontEnd )
				)
				( attribute "PHYS_PAGE" "202"
					( Origin gFrontEnd )
				)
				( attribute "ROT" "0"
					( Origin gFrontEnd )
				)
				( attribute "VALUE" "SC2K2P50V3KX-GP"
					( Origin gFrontEnd )
				)
				( attribute "VER" "1"
					( Origin gFrontEnd )
				)
				( attribute "XY" "(-2450,800)"
					( Origin gFrontEnd )
				)
				( attribute "CHIPS_PART_NAME" "SC2K2P50V3KX-GP"
					( Origin gPackager )
				)
				( attribute "CDS_PART_NAME" "SC2K2P50V3KX-GP_SMD-BCG6-SC2K2A"
					( Origin gPackager )
				)
				( attribute "CDS_LOCATION" "CT5"
					( Origin gPackager )
				)
				( attribute "CDS_SEC" "1"
					( Origin gPackager )
				)
				( attribute "SEC" "1"
					( Origin gPackager )
				)
				( attribute "STATUS" "NOPOP"
					( Origin gFrontEnd )
				)
				( objectStatus "CT5" )
				( pin "\1\"
					( attribute "PN" "1"
						( Origin gPackager )
					)
					( objectStatus "CT5.1" )
				)
				( pin "\2\"
					( attribute "PN" "2"
						( Origin gPackager )
					)
					( objectStatus "CT5.2" )
				)
			)
			( gate "@baseboard_fab2_lib.baseboard_fab2(sch_1):page202_i83"
				( attribute "CDS_LIB" "w_hdl"
					( Origin gPackager )
				)
				( attribute "CDS_LMAN_SYM_OUTLINE" "-50,75,50,-75"
					( Origin gPackager )
				)
				( attribute "CDS_LOCATION" "RT4"
					( Origin gPackager )
				)
				( attribute "CDS_SEC" "1"
					( Origin gPackager )
				)
				( attribute "LOCATION" "RT4"
					( Origin gFrontEnd )
				)
				( attribute "PACK_TYPE" "SMD-RG5"
					( Origin gFrontEnd )
				)
				( attribute "PART_NUMBER" "64.3R015.16L"
					( Origin gFrontEnd )
				)
				( attribute "PHYS_PAGE" "202"
					( Origin gFrontEnd )
				)
				( attribute "ROT" "4"
					( Origin gFrontEnd )
				)
				( attribute "VALUE" "3D01R5F-GP"
					( Origin gFrontEnd )
				)
				( attribute "VER" "1"
					( Origin gFrontEnd )
				)
				( attribute "XY" "(-2450,575)"
					( Origin gFrontEnd )
				)
				( attribute "CHIPS_PART_NAME" "3D01R5F-GP"
					( Origin gPackager )
				)
				( attribute "CDS_PART_NAME" "3D01R5F-GP_SMD-RG5-3D01R5F-GP,A"
					( Origin gPackager )
				)
				( attribute "SEC" "1"
					( Origin gPackager )
				)
				( attribute "STATUS" "NOPOP"
					( Origin gFrontEnd )
				)
				( objectStatus "RT4" )
				( pin "\1\"
					( attribute "PN" "1"
						( Origin gPackager )
					)
					( objectStatus "RT4.1" )
				)
				( pin "\2\"
					( attribute "PN" "2"
						( Origin gPackager )
					)
					( objectStatus "RT4.2" )
				)
			)
			( gate "@baseboard_fab2_lib.baseboard_fab2(sch_1):page227_i109"
				( attribute "CDS_LIB" "dev_discrete"
					( Origin gPackager )
				)
				( attribute "LOCATION" "CT7"
					( Origin gFrontEnd )
				)
				( attribute "MATERIAL" "X7R"
					( Origin gFrontEnd )
				)
				( attribute "PACK_TYPE" "0402V"
					( Origin gFrontEnd )
				)
				( attribute "PART_NUMBER" "A36096-030"
					( Origin gFrontEnd )
				)
				( attribute "PHYS_PAGE" "227"
					( Origin gFrontEnd )
				)
				( attribute "ROOM" "PVCCIN_CPU0_PWR_VR"
					( Origin gFrontEnd )
				)
				( attribute "ROT" "0"
					( Origin gFrontEnd )
				)
				( attribute "TOLERANCE" "10%"
					( Origin gFrontEnd )
				)
				( attribute "VALUE" "0.1UF"
					( Origin gFrontEnd )
				)
				( attribute "VER" "1"
					( Origin gFrontEnd )
				)
				( attribute "VOLTAGE" "16V"
					( Units "uVoltage" "V" 1.000000)
					( Origin gFrontEnd )
				)
				( attribute "XY" "(825,1650)"
					( Origin gFrontEnd )
				)
				( attribute "CHIPS_PART_NAME" "CAP_A"
					( Origin gPackager )
				)
				( attribute "CDS_PART_NAME" "CAP_A_0402V-0.1UF,16V,10%,X7R,A"
					( Origin gPackager )
				)
				( attribute "CDS_LOCATION" "CT7"
					( Origin gPackager )
				)
				( attribute "CDS_SEC" "1"
					( Origin gPackager )
				)
				( attribute "SEC" "1"
					( Origin gPackager )
				)
				( attribute "STATUS" "NOPOP"
					( Origin gFrontEnd )
				)
				( objectStatus "CT7" )
				( pin "a"
					( attribute "PN" "1"
						( Origin gPackager )
					)
					( objectStatus "CT7.1" )
				)
				( pin "b"
					( attribute "PN" "2"
						( Origin gPackager )
					)
					( objectStatus "CT7.2" )
				)
			)
			( gate "@baseboard_fab2_lib.baseboard_fab2(sch_1):page227_i111"
				( attribute "CDS_LIB" "w_hdl"
					( Origin gPackager )
				)
				( attribute "CDS_LMAN_SYM_OUTLINE" "-50,25,50,-25"
					( Origin gPackager )
				)
				( attribute "LOCATION" "CT9"
					( Origin gFrontEnd )
				)
				( attribute "PACK_TYPE" "SMD-BCG6"
					( Origin gFrontEnd )
				)
				( attribute "PART_NUMBER" "78.22224.2BL"
					( Origin gFrontEnd )
				)
				( attribute "PHYS_PAGE" "227"
					( Origin gFrontEnd )
				)
				( attribute "ROT" "0"
					( Origin gFrontEnd )
				)
				( attribute "VALUE" "SC2K2P50V3KX-GP"
					( Origin gFrontEnd )
				)
				( attribute "VER" "1"
					( Origin gFrontEnd )
				)
				( attribute "XY" "(2600,1700)"
					( Origin gFrontEnd )
				)
				( attribute "CHIPS_PART_NAME" "SC2K2P50V3KX-GP"
					( Origin gPackager )
				)
				( attribute "CDS_PART_NAME" "SC2K2P50V3KX-GP_SMD-BCG6-SC2K2A"
					( Origin gPackager )
				)
				( attribute "CDS_LOCATION" "CT9"
					( Origin gPackager )
				)
				( attribute "CDS_SEC" "1"
					( Origin gPackager )
				)
				( attribute "SEC" "1"
					( Origin gPackager )
				)
				( attribute "STATUS" "NOPOP"
					( Origin gFrontEnd )
				)
				( objectStatus "CT9" )
				( pin "\1\"
					( attribute "PN" "1"
						( Origin gPackager )
					)
					( objectStatus "CT9.1" )
				)
				( pin "\2\"
					( attribute "PN" "2"
						( Origin gPackager )
					)
					( objectStatus "CT9.2" )
				)
			)
			( gate "@baseboard_fab2_lib.baseboard_fab2(sch_1):page227_i114"
				( attribute "CDS_LIB" "mstr_discrete"
					( Origin gPackager )
				)
				( attribute "LOCATION" "CT8"
					( Origin gFrontEnd )
				)
				( attribute "MATERIAL" "X7R"
					( Origin gFrontEnd )
				)
				( attribute "PACK_TYPE" "0402LF"
					( Origin gFrontEnd )
				)
				( attribute "PART_NUMBER" "A36096-046"
					( Origin gFrontEnd )
				)
				( attribute "PHYS_PAGE" "227"
					( Origin gFrontEnd )
				)
				( attribute "ROOM" "VDDQ_KLM_PWR_VR"
					( Origin gFrontEnd )
				)
				( attribute "ROT" "0"
					( Origin gFrontEnd )
				)
				( attribute "TOLERANCE" "10%"
					( Origin gFrontEnd )
				)
				( attribute "VALUE" "1000PF"
					( Origin gFrontEnd )
				)
				( attribute "VER" "1"
					( Origin gFrontEnd )
				)
				( attribute "VOLTAGE" "50V"
					( Units "uVoltage" "V" 1.000000)
					( Origin gFrontEnd )
				)
				( attribute "XY" "(2725,2125)"
					( Origin gFrontEnd )
				)
				( attribute "CHIPS_PART_NAME" "CAP"
					( Origin gPackager )
				)
				( attribute "CDS_PART_NAME" "CAP_0402LF-1000PF,50V,10%,X7R,A"
					( Origin gPackager )
				)
				( attribute "CDS_LOCATION" "CT8"
					( Origin gPackager )
				)
				( attribute "CDS_SEC" "1"
					( Origin gPackager )
				)
				( attribute "SEC" "1"
					( Origin gPackager )
				)
				( attribute "STATUS" "NOPOP"
					( Origin gFrontEnd )
				)
				( objectStatus "CT8" )
				( pin "a"
					( attribute "PN" "1"
						( Origin gPackager )
					)
					( objectStatus "CT8.1" )
				)
				( pin "b"
					( attribute "PN" "2"
						( Origin gPackager )
					)
					( objectStatus "CT8.2" )
				)
			)
			( gate "@baseboard_fab2_lib.baseboard_fab2(sch_1):page227_i116"
				( attribute "CDS_LIB" "w_hdl"
					( Origin gPackager )
				)
				( attribute "CDS_LMAN_SYM_OUTLINE" "-50,25,50,-25"
					( Origin gPackager )
				)
				( attribute "LOCATION" "CT11"
					( Origin gFrontEnd )
				)
				( attribute "PACK_TYPE" "SMD-BCG6"
					( Origin gFrontEnd )
				)
				( attribute "PART_NUMBER" "78.22224.2BL"
					( Origin gFrontEnd )
				)
				( attribute "PHYS_PAGE" "227"
					( Origin gFrontEnd )
				)
				( attribute "ROT" "0"
					( Origin gFrontEnd )
				)
				( attribute "VALUE" "SC2K2P50V3KX-GP"
					( Origin gFrontEnd )
				)
				( attribute "VER" "1"
					( Origin gFrontEnd )
				)
				( attribute "XY" "(2575,-425)"
					( Origin gFrontEnd )
				)
				( attribute "CHIPS_PART_NAME" "SC2K2P50V3KX-GP"
					( Origin gPackager )
				)
				( attribute "CDS_PART_NAME" "SC2K2P50V3KX-GP_SMD-BCG6-SC2K2A"
					( Origin gPackager )
				)
				( attribute "STATUS" "NOPOP"
					( Origin gFrontEnd )
				)
				( attribute "CDS_LOCATION" "CT11"
					( Origin gPackager )
				)
				( attribute "CDS_SEC" "1"
					( Origin gPackager )
				)
				( attribute "SEC" "1"
					( Origin gPackager )
				)
				( objectStatus "CT11" )
				( pin "\1\"
					( attribute "PN" "1"
						( Origin gPackager )
					)
					( objectStatus "CT11.1" )
				)
				( pin "\2\"
					( attribute "PN" "2"
						( Origin gPackager )
					)
					( objectStatus "CT11.2" )
				)
			)
			( gate "@baseboard_fab2_lib.baseboard_fab2(sch_1):page227_i125"
				( attribute "CDS_LIB" "w_hdl"
					( Origin gPackager )
				)
				( attribute "CDS_LMAN_SYM_OUTLINE" "-50,75,50,-75"
					( Origin gPackager )
				)
				( attribute "LOCATION" "RT6"
					( Origin gFrontEnd )
				)
				( attribute "PACK_TYPE" "SMD-RG5"
					( Origin gFrontEnd )
				)
				( attribute "PART_NUMBER" "64.3R015.16L"
					( Origin gFrontEnd )
				)
				( attribute "PHYS_PAGE" "227"
					( Origin gFrontEnd )
				)
				( attribute "ROT" "0"
					( Origin gFrontEnd )
				)
				( attribute "VALUE" "3D01R5F-GP"
					( Origin gFrontEnd )
				)
				( attribute "VER" "1"
					( Origin gFrontEnd )
				)
				( attribute "XY" "(2600,1400)"
					( Origin gFrontEnd )
				)
				( attribute "CHIPS_PART_NAME" "3D01R5F-GP"
					( Origin gPackager )
				)
				( attribute "CDS_PART_NAME" "3D01R5F-GP_SMD-RG5-3D01R5F-GP,A"
					( Origin gPackager )
				)
				( attribute "CDS_LOCATION" "RT6"
					( Origin gPackager )
				)
				( attribute "CDS_SEC" "1"
					( Origin gPackager )
				)
				( attribute "SEC" "1"
					( Origin gPackager )
				)
				( attribute "STATUS" "NOPOP"
					( Origin gFrontEnd )
				)
				( objectStatus "RT6" )
				( pin "\1\"
					( attribute "PN" "1"
						( Origin gPackager )
					)
					( objectStatus "RT6.1" )
				)
				( pin "\2\"
					( attribute "PN" "2"
						( Origin gPackager )
					)
					( objectStatus "RT6.2" )
				)
			)
			( gate "@baseboard_fab2_lib.baseboard_fab2(sch_1):page227_i119"
				( attribute "CDS_LIB" "mstr_discrete"
					( Origin gPackager )
				)
				( attribute "LOCATION" "CT10"
					( Origin gFrontEnd )
				)
				( attribute "MATERIAL" "X7R"
					( Origin gFrontEnd )
				)
				( attribute "PACK_TYPE" "0402LF"
					( Origin gFrontEnd )
				)
				( attribute "PART_NUMBER" "A36096-046"
					( Origin gFrontEnd )
				)
				( attribute "PHYS_PAGE" "227"
					( Origin gFrontEnd )
				)
				( attribute "ROOM" "VDDQ_KLM_PWR_VR"
					( Origin gFrontEnd )
				)
				( attribute "ROT" "0"
					( Origin gFrontEnd )
				)
				( attribute "TOLERANCE" "10%"
					( Origin gFrontEnd )
				)
				( attribute "VALUE" "1000PF"
					( Origin gFrontEnd )
				)
				( attribute "VER" "1"
					( Origin gFrontEnd )
				)
				( attribute "VOLTAGE" "50V"
					( Units "uVoltage" "V" 1.000000)
					( Origin gFrontEnd )
				)
				( attribute "XY" "(2600,50)"
					( Origin gFrontEnd )
				)
				( attribute "CHIPS_PART_NAME" "CAP"
					( Origin gPackager )
				)
				( attribute "CDS_PART_NAME" "CAP_0402LF-1000PF,50V,10%,X7R,A"
					( Origin gPackager )
				)
				( attribute "CDS_LOCATION" "CT10"
					( Origin gPackager )
				)
				( attribute "CDS_SEC" "1"
					( Origin gPackager )
				)
				( attribute "SEC" "1"
					( Origin gPackager )
				)
				( attribute "STATUS" "NOPOP"
					( Origin gFrontEnd )
				)
				( objectStatus "CT10" )
				( pin "a"
					( attribute "PN" "1"
						( Origin gPackager )
					)
					( objectStatus "CT10.1" )
				)
				( pin "b"
					( attribute "PN" "2"
						( Origin gPackager )
					)
					( objectStatus "CT10.2" )
				)
			)
			( gate "@baseboard_fab2_lib.baseboard_fab2(sch_1):page227_i122"
				( attribute "CDS_LIB" "dev_discrete"
					( Origin gPackager )
				)
				( attribute "LOCATION" "CT12"
					( Origin gFrontEnd )
				)
				( attribute "MATERIAL" "X7R"
					( Origin gFrontEnd )
				)
				( attribute "PACK_TYPE" "0402V"
					( Origin gFrontEnd )
				)
				( attribute "PART_NUMBER" "A36096-030"
					( Origin gFrontEnd )
				)
				( attribute "PHYS_PAGE" "227"
					( Origin gFrontEnd )
				)
				( attribute "ROOM" "PVCCIN_CPU0_PWR_VR"
					( Origin gFrontEnd )
				)
				( attribute "ROT" "0"
					( Origin gFrontEnd )
				)
				( attribute "TOLERANCE" "10%"
					( Origin gFrontEnd )
				)
				( attribute "VALUE" "0.1UF"
					( Origin gFrontEnd )
				)
				( attribute "VER" "1"
					( Origin gFrontEnd )
				)
				( attribute "VOLTAGE" "16V"
					( Units "uVoltage" "V" 1.000000)
					( Origin gFrontEnd )
				)
				( attribute "XY" "(800,-500)"
					( Origin gFrontEnd )
				)
				( attribute "CHIPS_PART_NAME" "CAP_A"
					( Origin gPackager )
				)
				( attribute "CDS_PART_NAME" "CAP_A_0402V-0.1UF,16V,10%,X7R,A"
					( Origin gPackager )
				)
				( attribute "CDS_LOCATION" "CT12"
					( Origin gPackager )
				)
				( attribute "CDS_SEC" "1"
					( Origin gPackager )
				)
				( attribute "SEC" "1"
					( Origin gPackager )
				)
				( attribute "STATUS" "NOPOP"
					( Origin gFrontEnd )
				)
				( objectStatus "CT12" )
				( pin "a"
					( attribute "PN" "1"
						( Origin gPackager )
					)
					( objectStatus "CT12.1" )
				)
				( pin "b"
					( attribute "PN" "2"
						( Origin gPackager )
					)
					( objectStatus "CT12.2" )
				)
			)
			( gate "@baseboard_fab2_lib.baseboard_fab2(sch_1):page208_i96"
				( attribute "BOM_COST" "DEBUG"
					( Origin gFrontEnd )
				)
				( attribute "CDS_LIB" "mstr_discrete"
					( Origin gPackager )
				)
				( attribute "LOCATION" "RT11"
					( Origin gFrontEnd )
				)
				( attribute "MATERIAL" "CHIP"
					( Origin gFrontEnd )
				)
				( attribute "PACK_TYPE" "0402"
					( Origin gFrontEnd )
				)
				( attribute "PART_NUMBER" "G21497-005"
					( Origin gFrontEnd )
				)
				( attribute "PHYS_PAGE" "208"
					( Origin gFrontEnd )
				)
				( attribute "ROOM" "BMC_DEBUG_HEADER"
					( Origin gFrontEnd )
				)
				( attribute "ROT" "0"
					( Origin gFrontEnd )
				)
				( attribute "TOLERANCE" "5%"
					( Origin gFrontEnd )
				)
				( attribute "VALUE" "0.0"
					( Origin gFrontEnd )
				)
				( attribute "VER" "1"
					( Origin gFrontEnd )
				)
				( attribute "WATTAGE" "1/16W"
					( Origin gFrontEnd )
				)
				( attribute "XY" "(-4975,3700)"
					( Origin gFrontEnd )
				)
				( attribute "CHIPS_PART_NAME" "RES"
					( Origin gPackager )
				)
				( attribute "CDS_PART_NAME" "RES_0402-0.0,5%,1/16W,CHIP,G21A"
					( Origin gPackager )
				)
				( attribute "CDS_LOCATION" "RT11"
					( Origin gPackager )
				)
				( attribute "CDS_SEC" "1"
					( Origin gPackager )
				)
				( attribute "SEC" "1"
					( Origin gPackager )
				)
				( objectStatus "RT11" )
				( pin "a"
					( attribute "PN" "1"
						( Origin gPackager )
					)
					( objectStatus "RT11.1" )
				)
				( pin "b"
					( attribute "PN" "2"
						( Origin gPackager )
					)
					( objectStatus "RT11.2" )
				)
			)
			( gate "@baseboard_fab2_lib.baseboard_fab2(sch_1):page209_i62"
				( attribute "CDS_LIB" "dev_discrete"
					( Origin gPackager )
				)
				( attribute "LOCATION" "CT13"
					( Origin gFrontEnd )
				)
				( attribute "MATERIAL" "X7R"
					( Origin gFrontEnd )
				)
				( attribute "PACK_TYPE" "0402V"
					( Origin gFrontEnd )
				)
				( attribute "PART_NUMBER" "A36096-030"
					( Origin gFrontEnd )
				)
				( attribute "PHYS_PAGE" "209"
					( Origin gFrontEnd )
				)
				( attribute "ROOM" "PVCCIN_CPU0_PWR_VR"
					( Origin gFrontEnd )
				)
				( attribute "ROT" "0"
					( Origin gFrontEnd )
				)
				( attribute "TOLERANCE" "10%"
					( Origin gFrontEnd )
				)
				( attribute "VALUE" "0.1UF"
					( Origin gFrontEnd )
				)
				( attribute "VER" "1"
					( Origin gFrontEnd )
				)
				( attribute "VOLTAGE" "16V"
					( Units "uVoltage" "V" 1.000000)
					( Origin gFrontEnd )
				)
				( attribute "XY" "(-3950,3275)"
					( Origin gFrontEnd )
				)
				( attribute "CHIPS_PART_NAME" "CAP_A"
					( Origin gPackager )
				)
				( attribute "CDS_PART_NAME" "CAP_A_0402V-0.1UF,16V,10%,X7R,A"
					( Origin gPackager )
				)
				( attribute "CDS_LOCATION" "CT13"
					( Origin gPackager )
				)
				( attribute "CDS_SEC" "1"
					( Origin gPackager )
				)
				( attribute "SEC" "1"
					( Origin gPackager )
				)
				( attribute "STATUS" "NOPOP"
					( Origin gFrontEnd )
				)
				( objectStatus "CT13" )
				( pin "a"
					( attribute "PN" "1"
						( Origin gPackager )
					)
					( objectStatus "CT13.1" )
				)
				( pin "b"
					( attribute "PN" "2"
						( Origin gPackager )
					)
					( objectStatus "CT13.2" )
				)
			)
			( gate "@baseboard_fab2_lib.baseboard_fab2(sch_1):page209_i64"
				( attribute "CDS_LIB" "w_hdl"
					( Origin gPackager )
				)
				( attribute "CDS_LMAN_SYM_OUTLINE" "-50,25,50,-25"
					( Origin gPackager )
				)
				( attribute "LOCATION" "CT14"
					( Origin gFrontEnd )
				)
				( attribute "PACK_TYPE" "SMD-BCG6"
					( Origin gFrontEnd )
				)
				( attribute "PART_NUMBER" "78.22224.2BL"
					( Origin gFrontEnd )
				)
				( attribute "PHYS_PAGE" "209"
					( Origin gFrontEnd )
				)
				( attribute "ROT" "0"
					( Origin gFrontEnd )
				)
				( attribute "VALUE" "SC2K2P50V3KX-GP"
					( Origin gFrontEnd )
				)
				( attribute "VER" "1"
					( Origin gFrontEnd )
				)
				( attribute "XY" "(-2400,3300)"
					( Origin gFrontEnd )
				)
				( attribute "CHIPS_PART_NAME" "SC2K2P50V3KX-GP"
					( Origin gPackager )
				)
				( attribute "CDS_PART_NAME" "SC2K2P50V3KX-GP_SMD-BCG6-SC2K2A"
					( Origin gPackager )
				)
				( attribute "STATUS" "NOPOP"
					( Origin gFrontEnd )
				)
				( attribute "CDS_LOCATION" "CT14"
					( Origin gPackager )
				)
				( attribute "CDS_SEC" "1"
					( Origin gPackager )
				)
				( attribute "SEC" "1"
					( Origin gPackager )
				)
				( objectStatus "CT14" )
				( pin "\1\"
					( attribute "PN" "1"
						( Origin gPackager )
					)
					( objectStatus "CT14.1" )
				)
				( pin "\2\"
					( attribute "PN" "2"
						( Origin gPackager )
					)
					( objectStatus "CT14.2" )
				)
			)
			( gate "@baseboard_fab2_lib.baseboard_fab2(sch_1):page209_i66"
				( attribute "CDS_LIB" "w_hdl"
					( Origin gPackager )
				)
				( attribute "CDS_LMAN_SYM_OUTLINE" "-50,75,50,-75"
					( Origin gPackager )
				)
				( attribute "LOCATION" "RT10"
					( Origin gFrontEnd )
				)
				( attribute "PACK_TYPE" "SMD-RG5"
					( Origin gFrontEnd )
				)
				( attribute "PART_NUMBER" "64.3R015.16L"
					( Origin gFrontEnd )
				)
				( attribute "PHYS_PAGE" "209"
					( Origin gFrontEnd )
				)
				( attribute "ROT" "4"
					( Origin gFrontEnd )
				)
				( attribute "VALUE" "3D01R5F-GP"
					( Origin gFrontEnd )
				)
				( attribute "VER" "1"
					( Origin gFrontEnd )
				)
				( attribute "XY" "(-2400,3025)"
					( Origin gFrontEnd )
				)
				( attribute "CHIPS_PART_NAME" "3D01R5F-GP"
					( Origin gPackager )
				)
				( attribute "CDS_PART_NAME" "3D01R5F-GP_SMD-RG5-3D01R5F-GP,A"
					( Origin gPackager )
				)
				( attribute "CDS_LOCATION" "RT10"
					( Origin gPackager )
				)
				( attribute "CDS_SEC" "1"
					( Origin gPackager )
				)
				( attribute "SEC" "1"
					( Origin gPackager )
				)
				( attribute "STATUS" "NOPOP"
					( Origin gFrontEnd )
				)
				( objectStatus "RT10" )
				( pin "\1\"
					( attribute "PN" "1"
						( Origin gPackager )
					)
					( objectStatus "RT10.1" )
				)
				( pin "\2\"
					( attribute "PN" "2"
						( Origin gPackager )
					)
					( objectStatus "RT10.2" )
				)
			)
			( gate "@baseboard_fab2_lib.baseboard_fab2(sch_1):page209_i67"
				( attribute "CDS_LIB" "mstr_discrete"
					( Origin gPackager )
				)
				( attribute "LOCATION" "CT15"
					( Origin gFrontEnd )
				)
				( attribute "MATERIAL" "X7R"
					( Origin gFrontEnd )
				)
				( attribute "PACK_TYPE" "0402LF"
					( Origin gFrontEnd )
				)
				( attribute "PART_NUMBER" "A36096-046"
					( Origin gFrontEnd )
				)
				( attribute "PHYS_PAGE" "209"
					( Origin gFrontEnd )
				)
				( attribute "ROOM" "VDDQ_KLM_PWR_VR"
					( Origin gFrontEnd )
				)
				( attribute "ROT" "0"
					( Origin gFrontEnd )
				)
				( attribute "TOLERANCE" "10%"
					( Origin gFrontEnd )
				)
				( attribute "VALUE" "1000PF"
					( Origin gFrontEnd )
				)
				( attribute "VER" "1"
					( Origin gFrontEnd )
				)
				( attribute "VOLTAGE" "50V"
					( Units "uVoltage" "V" 1.000000)
					( Origin gFrontEnd )
				)
				( attribute "XY" "(-1950,3825)"
					( Origin gFrontEnd )
				)
				( attribute "CHIPS_PART_NAME" "CAP"
					( Origin gPackager )
				)
				( attribute "CDS_PART_NAME" "CAP_0402LF-1000PF,50V,10%,X7R,A"
					( Origin gPackager )
				)
				( attribute "STATUS" "NOPOP"
					( Origin gFrontEnd )
				)
				( attribute "CDS_LOCATION" "CT15"
					( Origin gPackager )
				)
				( attribute "CDS_SEC" "1"
					( Origin gPackager )
				)
				( attribute "SEC" "1"
					( Origin gPackager )
				)
				( objectStatus "CT15" )
				( pin "a"
					( attribute "PN" "1"
						( Origin gPackager )
					)
					( objectStatus "CT15.1" )
				)
				( pin "b"
					( attribute "PN" "2"
						( Origin gPackager )
					)
					( objectStatus "CT15.2" )
				)
			)
			( gate "@baseboard_fab2_lib.baseboard_fab2(sch_1):page208_i80"
				( attribute "CDS_LIB" "dev_discrete"
					( Origin gPackager )
				)
				( attribute "LOCATION" "CT16"
					( Origin gFrontEnd )
				)
				( attribute "MATERIAL" "X7R"
					( Origin gFrontEnd )
				)
				( attribute "PACK_TYPE" "0402V"
					( Origin gFrontEnd )
				)
				( attribute "PART_NUMBER" "A36096-030"
					( Origin gFrontEnd )
				)
				( attribute "PHYS_PAGE" "208"
					( Origin gFrontEnd )
				)
				( attribute "ROOM" "PVCCIN_CPU0_PWR_VR"
					( Origin gFrontEnd )
				)
				( attribute "ROT" "0"
					( Origin gFrontEnd )
				)
				( attribute "TOLERANCE" "10%"
					( Origin gFrontEnd )
				)
				( attribute "VALUE" "0.1UF"
					( Origin gFrontEnd )
				)
				( attribute "VER" "1"
					( Origin gFrontEnd )
				)
				( attribute "VOLTAGE" "16V"
					( Units "uVoltage" "V" 1.000000)
					( Origin gFrontEnd )
				)
				( attribute "XY" "(-3975,3375)"
					( Origin gFrontEnd )
				)
				( attribute "CHIPS_PART_NAME" "CAP_A"
					( Origin gPackager )
				)
				( attribute "CDS_PART_NAME" "CAP_A_0402V-0.1UF,16V,10%,X7R,A"
					( Origin gPackager )
				)
				( attribute "CDS_LOCATION" "CT16"
					( Origin gPackager )
				)
				( attribute "CDS_SEC" "1"
					( Origin gPackager )
				)
				( attribute "SEC" "1"
					( Origin gPackager )
				)
				( attribute "STATUS" "NOPOP"
					( Origin gFrontEnd )
				)
				( objectStatus "CT16" )
				( pin "a"
					( attribute "PN" "1"
						( Origin gPackager )
					)
					( objectStatus "CT16.1" )
				)
				( pin "b"
					( attribute "PN" "2"
						( Origin gPackager )
					)
					( objectStatus "CT16.2" )
				)
			)
			( gate "@baseboard_fab2_lib.baseboard_fab2(sch_1):page208_i82"
				( attribute "CDS_LIB" "mstr_discrete"
					( Origin gPackager )
				)
				( attribute "LOCATION" "CTI7"
					( Origin gFrontEnd )
				)
				( attribute "MATERIAL" "X7R"
					( Origin gFrontEnd )
				)
				( attribute "PACK_TYPE" "0402LF"
					( Origin gFrontEnd )
				)
				( attribute "PART_NUMBER" "A36096-046"
					( Origin gFrontEnd )
				)
				( attribute "PHYS_PAGE" "208"
					( Origin gFrontEnd )
				)
				( attribute "ROOM" "VDDQ_KLM_PWR_VR"
					( Origin gFrontEnd )
				)
				( attribute "ROT" "0"
					( Origin gFrontEnd )
				)
				( attribute "TOLERANCE" "10%"
					( Origin gFrontEnd )
				)
				( attribute "VALUE" "1000PF"
					( Origin gFrontEnd )
				)
				( attribute "VER" "1"
					( Origin gFrontEnd )
				)
				( attribute "VOLTAGE" "50V"
					( Units "uVoltage" "V" 1.000000)
					( Origin gFrontEnd )
				)
				( attribute "XY" "(-2050,3900)"
					( Origin gFrontEnd )
				)
				( attribute "CHIPS_PART_NAME" "CAP"
					( Origin gPackager )
				)
				( attribute "CDS_PART_NAME" "CAP_0402LF-1000PF,50V,10%,X7R,A"
					( Origin gPackager )
				)
				( attribute "CDS_LOCATION" "CTI7"
					( Origin gPackager )
				)
				( attribute "CDS_SEC" "1"
					( Origin gPackager )
				)
				( attribute "SEC" "1"
					( Origin gPackager )
				)
				( attribute "STATUS" "NOPOP"
					( Origin gFrontEnd )
				)
				( objectStatus "CTI7" )
				( pin "a"
					( attribute "PN" "1"
						( Origin gPackager )
					)
					( objectStatus "CTI7.1" )
				)
				( pin "b"
					( attribute "PN" "2"
						( Origin gPackager )
					)
					( objectStatus "CTI7.2" )
				)
			)
			( gate "@baseboard_fab2_lib.baseboard_fab2(sch_1):page208_i84"
				( attribute "CDS_LIB" "w_hdl"
					( Origin gPackager )
				)
				( attribute "CDS_LMAN_SYM_OUTLINE" "-50,25,50,-25"
					( Origin gPackager )
				)
				( attribute "LOCATION" "CT18"
					( Origin gFrontEnd )
				)
				( attribute "PACK_TYPE" "SMD-BCG6"
					( Origin gFrontEnd )
				)
				( attribute "PART_NUMBER" "78.22224.2BL"
					( Origin gFrontEnd )
				)
				( attribute "PHYS_PAGE" "208"
					( Origin gFrontEnd )
				)
				( attribute "ROT" "0"
					( Origin gFrontEnd )
				)
				( attribute "VALUE" "SC2K2P50V3KX-GP"
					( Origin gFrontEnd )
				)
				( attribute "VER" "1"
					( Origin gFrontEnd )
				)
				( attribute "XY" "(-2000,3500)"
					( Origin gFrontEnd )
				)
				( attribute "CHIPS_PART_NAME" "SC2K2P50V3KX-GP"
					( Origin gPackager )
				)
				( attribute "CDS_PART_NAME" "SC2K2P50V3KX-GP_SMD-BCG6-SC2K2A"
					( Origin gPackager )
				)
				( attribute "CDS_LOCATION" "CT18"
					( Origin gPackager )
				)
				( attribute "CDS_SEC" "1"
					( Origin gPackager )
				)
				( attribute "SEC" "1"
					( Origin gPackager )
				)
				( attribute "STATUS" "NOPOP"
					( Origin gFrontEnd )
				)
				( objectStatus "CT18" )
				( pin "\1\"
					( attribute "PN" "1"
						( Origin gPackager )
					)
					( objectStatus "CT18.1" )
				)
				( pin "\2\"
					( attribute "PN" "2"
						( Origin gPackager )
					)
					( objectStatus "CT18.2" )
				)
			)
			( gate "@baseboard_fab2_lib.baseboard_fab2(sch_1):page208_i86"
				( attribute "CDS_LIB" "w_hdl"
					( Origin gPackager )
				)
				( attribute "CDS_LMAN_SYM_OUTLINE" "-50,75,50,-75"
					( Origin gPackager )
				)
				( attribute "CDS_LOCATION" "RT12"
					( Origin gPackager )
				)
				( attribute "CDS_SEC" "1"
					( Origin gPackager )
				)
				( attribute "LOCATION" "RT12"
					( Origin gFrontEnd )
				)
				( attribute "PACK_TYPE" "SMD-RG5"
					( Origin gFrontEnd )
				)
				( attribute "PART_NUMBER" "64.3R015.16L"
					( Origin gFrontEnd )
				)
				( attribute "PHYS_PAGE" "208"
					( Origin gFrontEnd )
				)
				( attribute "ROT" "4"
					( Origin gFrontEnd )
				)
				( attribute "VALUE" "3D01R5F-GP"
					( Origin gFrontEnd )
				)
				( attribute "VER" "1"
					( Origin gFrontEnd )
				)
				( attribute "XY" "(-2000,3200)"
					( Origin gFrontEnd )
				)
				( attribute "CHIPS_PART_NAME" "3D01R5F-GP"
					( Origin gPackager )
				)
				( attribute "CDS_PART_NAME" "3D01R5F-GP_SMD-RG5-3D01R5F-GP,A"
					( Origin gPackager )
				)
				( attribute "SEC" "1"
					( Origin gPackager )
				)
				( attribute "STATUS" "NOPOP"
					( Origin gFrontEnd )
				)
				( objectStatus "RT12" )
				( pin "\1\"
					( attribute "PN" "1"
						( Origin gPackager )
					)
					( objectStatus "RT12.1" )
				)
				( pin "\2\"
					( attribute "PN" "2"
						( Origin gPackager )
					)
					( objectStatus "RT12.2" )
				)
			)
			( gate "@baseboard_fab2_lib.baseboard_fab2(sch_1):page208_i87"
				( attribute "CDS_LIB" "dev_discrete"
					( Origin gPackager )
				)
				( attribute "LOCATION" "CT21"
					( Origin gFrontEnd )
				)
				( attribute "MATERIAL" "X7R"
					( Origin gFrontEnd )
				)
				( attribute "PACK_TYPE" "0402V"
					( Origin gFrontEnd )
				)
				( attribute "PART_NUMBER" "A36096-030"
					( Origin gFrontEnd )
				)
				( attribute "PHYS_PAGE" "208"
					( Origin gFrontEnd )
				)
				( attribute "ROOM" "PVCCIN_CPU0_PWR_VR"
					( Origin gFrontEnd )
				)
				( attribute "ROT" "0"
					( Origin gFrontEnd )
				)
				( attribute "TOLERANCE" "10%"
					( Origin gFrontEnd )
				)
				( attribute "VALUE" "0.1UF"
					( Origin gFrontEnd )
				)
				( attribute "VER" "1"
					( Origin gFrontEnd )
				)
				( attribute "VOLTAGE" "16V"
					( Units "uVoltage" "V" 1.000000)
					( Origin gFrontEnd )
				)
				( attribute "XY" "(-3850,775)"
					( Origin gFrontEnd )
				)
				( attribute "CHIPS_PART_NAME" "CAP_A"
					( Origin gPackager )
				)
				( attribute "CDS_PART_NAME" "CAP_A_0402V-0.1UF,16V,10%,X7R,A"
					( Origin gPackager )
				)
				( attribute "CDS_LOCATION" "CT21"
					( Origin gPackager )
				)
				( attribute "CDS_SEC" "1"
					( Origin gPackager )
				)
				( attribute "SEC" "1"
					( Origin gPackager )
				)
				( attribute "STATUS" "NOPOP"
					( Origin gFrontEnd )
				)
				( objectStatus "CT21" )
				( pin "a"
					( attribute "PN" "1"
						( Origin gPackager )
					)
					( objectStatus "CT21.1" )
				)
				( pin "b"
					( attribute "PN" "2"
						( Origin gPackager )
					)
					( objectStatus "CT21.2" )
				)
			)
			( gate "@baseboard_fab2_lib.baseboard_fab2(sch_1):page208_i90"
				( attribute "CDS_LIB" "mstr_discrete"
					( Origin gPackager )
				)
				( attribute "LOCATION" "CT19"
					( Origin gFrontEnd )
				)
				( attribute "MATERIAL" "X7R"
					( Origin gFrontEnd )
				)
				( attribute "PACK_TYPE" "0402LF"
					( Origin gFrontEnd )
				)
				( attribute "PART_NUMBER" "A36096-046"
					( Origin gFrontEnd )
				)
				( attribute "PHYS_PAGE" "208"
					( Origin gFrontEnd )
				)
				( attribute "ROOM" "VDDQ_KLM_PWR_VR"
					( Origin gFrontEnd )
				)
				( attribute "ROT" "0"
					( Origin gFrontEnd )
				)
				( attribute "TOLERANCE" "10%"
					( Origin gFrontEnd )
				)
				( attribute "VALUE" "1000PF"
					( Origin gFrontEnd )
				)
				( attribute "VER" "1"
					( Origin gFrontEnd )
				)
				( attribute "VOLTAGE" "50V"
					( Units "uVoltage" "V" 1.000000)
					( Origin gFrontEnd )
				)
				( attribute "XY" "(-2000,1300)"
					( Origin gFrontEnd )
				)
				( attribute "CHIPS_PART_NAME" "CAP"
					( Origin gPackager )
				)
				( attribute "CDS_PART_NAME" "CAP_0402LF-1000PF,50V,10%,X7R,A"
					( Origin gPackager )
				)
				( attribute "CDS_LOCATION" "CT19"
					( Origin gPackager )
				)
				( attribute "CDS_SEC" "1"
					( Origin gPackager )
				)
				( attribute "SEC" "1"
					( Origin gPackager )
				)
				( attribute "STATUS" "NOPOP"
					( Origin gFrontEnd )
				)
				( objectStatus "CT19" )
				( pin "a"
					( attribute "PN" "1"
						( Origin gPackager )
					)
					( objectStatus "CT19.1" )
				)
				( pin "b"
					( attribute "PN" "2"
						( Origin gPackager )
					)
					( objectStatus "CT19.2" )
				)
			)
			( gate "@baseboard_fab2_lib.baseboard_fab2(sch_1):page208_i92"
				( attribute "CDS_LIB" "w_hdl"
					( Origin gPackager )
				)
				( attribute "CDS_LMAN_SYM_OUTLINE" "-50,25,50,-25"
					( Origin gPackager )
				)
				( attribute "LOCATION" "CT20"
					( Origin gFrontEnd )
				)
				( attribute "PACK_TYPE" "SMD-BCG6"
					( Origin gFrontEnd )
				)
				( attribute "PART_NUMBER" "78.22224.2BL"
					( Origin gFrontEnd )
				)
				( attribute "PHYS_PAGE" "208"
					( Origin gFrontEnd )
				)
				( attribute "ROT" "0"
					( Origin gFrontEnd )
				)
				( attribute "VALUE" "SC2K2P50V3KX-GP"
					( Origin gFrontEnd )
				)
				( attribute "VER" "1"
					( Origin gFrontEnd )
				)
				( attribute "XY" "(-1900,875)"
					( Origin gFrontEnd )
				)
				( attribute "CHIPS_PART_NAME" "SC2K2P50V3KX-GP"
					( Origin gPackager )
				)
				( attribute "CDS_PART_NAME" "SC2K2P50V3KX-GP_SMD-BCG6-SC2K2A"
					( Origin gPackager )
				)
				( attribute "CDS_LOCATION" "CT20"
					( Origin gPackager )
				)
				( attribute "CDS_SEC" "1"
					( Origin gPackager )
				)
				( attribute "SEC" "1"
					( Origin gPackager )
				)
				( attribute "STATUS" "NOPOP"
					( Origin gFrontEnd )
				)
				( objectStatus "CT20" )
				( pin "\1\"
					( attribute "PN" "1"
						( Origin gPackager )
					)
					( objectStatus "CT20.1" )
				)
				( pin "\2\"
					( attribute "PN" "2"
						( Origin gPackager )
					)
					( objectStatus "CT20.2" )
				)
			)
			( gate "@baseboard_fab2_lib.baseboard_fab2(sch_1):page208_i94"
				( attribute "CDS_LIB" "w_hdl"
					( Origin gPackager )
				)
				( attribute "CDS_LMAN_SYM_OUTLINE" "-50,75,50,-75"
					( Origin gPackager )
				)
				( attribute "CDS_LOCATION" "RT13"
					( Origin gPackager )
				)
				( attribute "CDS_SEC" "1"
					( Origin gPackager )
				)
				( attribute "LOCATION" "RT13"
					( Origin gFrontEnd )
				)
				( attribute "PACK_TYPE" "SMD-RG5"
					( Origin gFrontEnd )
				)
				( attribute "PART_NUMBER" "64.3R015.16L"
					( Origin gFrontEnd )
				)
				( attribute "PHYS_PAGE" "208"
					( Origin gFrontEnd )
				)
				( attribute "ROT" "4"
					( Origin gFrontEnd )
				)
				( attribute "VALUE" "3D01R5F-GP"
					( Origin gFrontEnd )
				)
				( attribute "VER" "1"
					( Origin gFrontEnd )
				)
				( attribute "XY" "(-1900,650)"
					( Origin gFrontEnd )
				)
				( attribute "CHIPS_PART_NAME" "3D01R5F-GP"
					( Origin gPackager )
				)
				( attribute "CDS_PART_NAME" "3D01R5F-GP_SMD-RG5-3D01R5F-GP,A"
					( Origin gPackager )
				)
				( attribute "SEC" "1"
					( Origin gPackager )
				)
				( attribute "STATUS" "NOPOP"
					( Origin gFrontEnd )
				)
				( objectStatus "RT13" )
				( pin "\1\"
					( attribute "PN" "1"
						( Origin gPackager )
					)
					( objectStatus "RT13.1" )
				)
				( pin "\2\"
					( attribute "PN" "2"
						( Origin gPackager )
					)
					( objectStatus "RT13.2" )
				)
			)
			( gate "@baseboard_fab2_lib.baseboard_fab2(sch_1):page207_i71"
				( attribute "CDS_LIB" "dev_discrete"
					( Origin gPackager )
				)
				( attribute "LOCATION" "CT24"
					( Origin gFrontEnd )
				)
				( attribute "MATERIAL" "X7R"
					( Origin gFrontEnd )
				)
				( attribute "PACK_TYPE" "0402V"
					( Origin gFrontEnd )
				)
				( attribute "PART_NUMBER" "A36096-030"
					( Origin gFrontEnd )
				)
				( attribute "PHYS_PAGE" "207"
					( Origin gFrontEnd )
				)
				( attribute "ROOM" "PVCCIN_CPU0_PWR_VR"
					( Origin gFrontEnd )
				)
				( attribute "ROT" "0"
					( Origin gFrontEnd )
				)
				( attribute "TOLERANCE" "10%"
					( Origin gFrontEnd )
				)
				( attribute "VALUE" "0.1UF"
					( Origin gFrontEnd )
				)
				( attribute "VER" "1"
					( Origin gFrontEnd )
				)
				( attribute "VOLTAGE" "16V"
					( Units "uVoltage" "V" 1.000000)
					( Origin gFrontEnd )
				)
				( attribute "XY" "(-4175,3325)"
					( Origin gFrontEnd )
				)
				( attribute "CHIPS_PART_NAME" "CAP_A"
					( Origin gPackager )
				)
				( attribute "CDS_PART_NAME" "CAP_A_0402V-0.1UF,16V,10%,X7R,A"
					( Origin gPackager )
				)
				( attribute "CDS_LOCATION" "CT24"
					( Origin gPackager )
				)
				( attribute "CDS_SEC" "1"
					( Origin gPackager )
				)
				( attribute "SEC" "1"
					( Origin gPackager )
				)
				( attribute "STATUS" "NOPOP"
					( Origin gFrontEnd )
				)
				( objectStatus "CT24" )
				( pin "a"
					( attribute "PN" "1"
						( Origin gPackager )
					)
					( objectStatus "CT24.1" )
				)
				( pin "b"
					( attribute "PN" "2"
						( Origin gPackager )
					)
					( objectStatus "CT24.2" )
				)
			)
			( gate "@baseboard_fab2_lib.baseboard_fab2(sch_1):page207_i74"
				( attribute "CDS_LIB" "mstr_discrete"
					( Origin gPackager )
				)
				( attribute "LOCATION" "CT22"
					( Origin gFrontEnd )
				)
				( attribute "MATERIAL" "X7R"
					( Origin gFrontEnd )
				)
				( attribute "PACK_TYPE" "0402LF"
					( Origin gFrontEnd )
				)
				( attribute "PART_NUMBER" "A36096-046"
					( Origin gFrontEnd )
				)
				( attribute "PHYS_PAGE" "207"
					( Origin gFrontEnd )
				)
				( attribute "ROOM" "VDDQ_KLM_PWR_VR"
					( Origin gFrontEnd )
				)
				( attribute "ROT" "0"
					( Origin gFrontEnd )
				)
				( attribute "TOLERANCE" "10%"
					( Origin gFrontEnd )
				)
				( attribute "VALUE" "1000PF"
					( Origin gFrontEnd )
				)
				( attribute "VER" "1"
					( Origin gFrontEnd )
				)
				( attribute "VOLTAGE" "50V"
					( Units "uVoltage" "V" 1.000000)
					( Origin gFrontEnd )
				)
				( attribute "XY" "(-2450,3825)"
					( Origin gFrontEnd )
				)
				( attribute "CHIPS_PART_NAME" "CAP"
					( Origin gPackager )
				)
				( attribute "CDS_PART_NAME" "CAP_0402LF-1000PF,50V,10%,X7R,A"
					( Origin gPackager )
				)
				( attribute "CDS_LOCATION" "CT22"
					( Origin gPackager )
				)
				( attribute "CDS_SEC" "1"
					( Origin gPackager )
				)
				( attribute "SEC" "1"
					( Origin gPackager )
				)
				( attribute "STATUS" "NOPOP"
					( Origin gFrontEnd )
				)
				( objectStatus "CT22" )
				( pin "a"
					( attribute "PN" "1"
						( Origin gPackager )
					)
					( objectStatus "CT22.1" )
				)
				( pin "b"
					( attribute "PN" "2"
						( Origin gPackager )
					)
					( objectStatus "CT22.2" )
				)
			)
			( gate "@baseboard_fab2_lib.baseboard_fab2(sch_1):page207_i76"
				( attribute "CDS_LIB" "w_hdl"
					( Origin gPackager )
				)
				( attribute "CDS_LMAN_SYM_OUTLINE" "-50,75,50,-75"
					( Origin gPackager )
				)
				( attribute "CDS_LOCATION" "RT16"
					( Origin gPackager )
				)
				( attribute "CDS_SEC" "1"
					( Origin gPackager )
				)
				( attribute "LOCATION" "RT16"
					( Origin gFrontEnd )
				)
				( attribute "PACK_TYPE" "SMD-RG5"
					( Origin gFrontEnd )
				)
				( attribute "PART_NUMBER" "64.3R015.16L"
					( Origin gFrontEnd )
				)
				( attribute "PHYS_PAGE" "207"
					( Origin gFrontEnd )
				)
				( attribute "ROT" "4"
					( Origin gFrontEnd )
				)
				( attribute "VALUE" "3D01R5F-GP"
					( Origin gFrontEnd )
				)
				( attribute "VER" "1"
					( Origin gFrontEnd )
				)
				( attribute "XY" "(-2400,3075)"
					( Origin gFrontEnd )
				)
				( attribute "CHIPS_PART_NAME" "3D01R5F-GP"
					( Origin gPackager )
				)
				( attribute "CDS_PART_NAME" "3D01R5F-GP_SMD-RG5-3D01R5F-GP,A"
					( Origin gPackager )
				)
				( attribute "SEC" "1"
					( Origin gPackager )
				)
				( attribute "STATUS" "NOPOP"
					( Origin gFrontEnd )
				)
				( objectStatus "RT16" )
				( pin "\1\"
					( attribute "PN" "1"
						( Origin gPackager )
					)
					( objectStatus "RT16.1" )
				)
				( pin "\2\"
					( attribute "PN" "2"
						( Origin gPackager )
					)
					( objectStatus "RT16.2" )
				)
			)
			( gate "@baseboard_fab2_lib.baseboard_fab2(sch_1):page207_i77"
				( attribute "CDS_LIB" "w_hdl"
					( Origin gPackager )
				)
				( attribute "CDS_LMAN_SYM_OUTLINE" "-50,25,50,-25"
					( Origin gPackager )
				)
				( attribute "LOCATION" "CT23"
					( Origin gFrontEnd )
				)
				( attribute "PACK_TYPE" "SMD-BCG6"
					( Origin gFrontEnd )
				)
				( attribute "PART_NUMBER" "78.22224.2BL"
					( Origin gFrontEnd )
				)
				( attribute "PHYS_PAGE" "207"
					( Origin gFrontEnd )
				)
				( attribute "ROT" "0"
					( Origin gFrontEnd )
				)
				( attribute "VALUE" "SC2K2P50V3KX-GP"
					( Origin gFrontEnd )
				)
				( attribute "VER" "1"
					( Origin gFrontEnd )
				)
				( attribute "XY" "(-2400,3375)"
					( Origin gFrontEnd )
				)
				( attribute "CHIPS_PART_NAME" "SC2K2P50V3KX-GP"
					( Origin gPackager )
				)
				( attribute "CDS_PART_NAME" "SC2K2P50V3KX-GP_SMD-BCG6-SC2K2A"
					( Origin gPackager )
				)
				( attribute "CDS_LOCATION" "CT23"
					( Origin gPackager )
				)
				( attribute "CDS_SEC" "1"
					( Origin gPackager )
				)
				( attribute "SEC" "1"
					( Origin gPackager )
				)
				( attribute "STATUS" "NOPOP"
					( Origin gFrontEnd )
				)
				( objectStatus "CT23" )
				( pin "\1\"
					( attribute "PN" "1"
						( Origin gPackager )
					)
					( objectStatus "CT23.1" )
				)
				( pin "\2\"
					( attribute "PN" "2"
						( Origin gPackager )
					)
					( objectStatus "CT23.2" )
				)
			)
			( gate "@baseboard_fab2_lib.baseboard_fab2(sch_1):page224_i117"
				( attribute "CDS_LIB" "dev_discrete"
					( Origin gPackager )
				)
				( attribute "LOCATION" "CT30"
					( Origin gFrontEnd )
				)
				( attribute "MATERIAL" "X7R"
					( Origin gFrontEnd )
				)
				( attribute "PACK_TYPE" "0402V"
					( Origin gFrontEnd )
				)
				( attribute "PART_NUMBER" "A36096-030"
					( Origin gFrontEnd )
				)
				( attribute "PHYS_PAGE" "224"
					( Origin gFrontEnd )
				)
				( attribute "ROOM" "PVCCIN_CPU0_PWR_VR"
					( Origin gFrontEnd )
				)
				( attribute "ROT" "0"
					( Origin gFrontEnd )
				)
				( attribute "TOLERANCE" "10%"
					( Origin gFrontEnd )
				)
				( attribute "VALUE" "0.1UF"
					( Origin gFrontEnd )
				)
				( attribute "VER" "1"
					( Origin gFrontEnd )
				)
				( attribute "VOLTAGE" "16V"
					( Units "uVoltage" "V" 1.000000)
					( Origin gFrontEnd )
				)
				( attribute "XY" "(700,1725)"
					( Origin gFrontEnd )
				)
				( attribute "CHIPS_PART_NAME" "CAP_A"
					( Origin gPackager )
				)
				( attribute "CDS_PART_NAME" "CAP_A_0402V-0.1UF,16V,10%,X7R,A"
					( Origin gPackager )
				)
				( attribute "CDS_LOCATION" "CT30"
					( Origin gPackager )
				)
				( attribute "CDS_SEC" "1"
					( Origin gPackager )
				)
				( attribute "SEC" "1"
					( Origin gPackager )
				)
				( attribute "STATUS" "NOPOP"
					( Origin gFrontEnd )
				)
				( objectStatus "CT30" )
				( pin "a"
					( attribute "PN" "1"
						( Origin gPackager )
					)
					( objectStatus "CT30.1" )
				)
				( pin "b"
					( attribute "PN" "2"
						( Origin gPackager )
					)
					( objectStatus "CT30.2" )
				)
			)
			( gate "@baseboard_fab2_lib.baseboard_fab2(sch_1):page224_i119"
				( attribute "CDS_LIB" "w_hdl"
					( Origin gPackager )
				)
				( attribute "CDS_LMAN_SYM_OUTLINE" "-50,75,50,-75"
					( Origin gPackager )
				)
				( attribute "CDS_LOCATION" "RT20"
					( Origin gPackager )
				)
				( attribute "CDS_SEC" "1"
					( Origin gPackager )
				)
				( attribute "LOCATION" "RT20"
					( Origin gFrontEnd )
				)
				( attribute "PACK_TYPE" "SMD-RG5"
					( Origin gFrontEnd )
				)
				( attribute "PART_NUMBER" "64.3R015.16L"
					( Origin gFrontEnd )
				)
				( attribute "PHYS_PAGE" "224"
					( Origin gFrontEnd )
				)
				( attribute "ROT" "4"
					( Origin gFrontEnd )
				)
				( attribute "VALUE" "3D01R5F-GP"
					( Origin gFrontEnd )
				)
				( attribute "VER" "1"
					( Origin gFrontEnd )
				)
				( attribute "XY" "(2700,1500)"
					( Origin gFrontEnd )
				)
				( attribute "CHIPS_PART_NAME" "3D01R5F-GP"
					( Origin gPackager )
				)
				( attribute "CDS_PART_NAME" "3D01R5F-GP_SMD-RG5-3D01R5F-GP,A"
					( Origin gPackager )
				)
				( attribute "SEC" "1"
					( Origin gPackager )
				)
				( attribute "STATUS" "NOPOP"
					( Origin gFrontEnd )
				)
				( objectStatus "RT20" )
				( pin "\1\"
					( attribute "PN" "1"
						( Origin gPackager )
					)
					( objectStatus "RT20.1" )
				)
				( pin "\2\"
					( attribute "PN" "2"
						( Origin gPackager )
					)
					( objectStatus "RT20.2" )
				)
			)
			( gate "@baseboard_fab2_lib.baseboard_fab2(sch_1):page224_i121"
				( attribute "CDS_LIB" "w_hdl"
					( Origin gPackager )
				)
				( attribute "CDS_LMAN_SYM_OUTLINE" "-50,25,50,-25"
					( Origin gPackager )
				)
				( attribute "LOCATION" "CT29"
					( Origin gFrontEnd )
				)
				( attribute "PACK_TYPE" "SMD-BCG6"
					( Origin gFrontEnd )
				)
				( attribute "PART_NUMBER" "78.22224.2BL"
					( Origin gFrontEnd )
				)
				( attribute "PHYS_PAGE" "224"
					( Origin gFrontEnd )
				)
				( attribute "ROT" "0"
					( Origin gFrontEnd )
				)
				( attribute "VALUE" "SC2K2P50V3KX-GP"
					( Origin gFrontEnd )
				)
				( attribute "VER" "1"
					( Origin gFrontEnd )
				)
				( attribute "XY" "(2700,1800)"
					( Origin gFrontEnd )
				)
				( attribute "CHIPS_PART_NAME" "SC2K2P50V3KX-GP"
					( Origin gPackager )
				)
				( attribute "CDS_PART_NAME" "SC2K2P50V3KX-GP_SMD-BCG6-SC2K2A"
					( Origin gPackager )
				)
				( attribute "CDS_LOCATION" "CT29"
					( Origin gPackager )
				)
				( attribute "CDS_SEC" "1"
					( Origin gPackager )
				)
				( attribute "SEC" "1"
					( Origin gPackager )
				)
				( attribute "STATUS" "NOPOP"
					( Origin gFrontEnd )
				)
				( objectStatus "CT29" )
				( pin "\1\"
					( attribute "PN" "1"
						( Origin gPackager )
					)
					( objectStatus "CT29.1" )
				)
				( pin "\2\"
					( attribute "PN" "2"
						( Origin gPackager )
					)
					( objectStatus "CT29.2" )
				)
			)
			( gate "@baseboard_fab2_lib.baseboard_fab2(sch_1):page224_i122"
				( attribute "CDS_LIB" "mstr_discrete"
					( Origin gPackager )
				)
				( attribute "LOCATION" "CT28"
					( Origin gFrontEnd )
				)
				( attribute "MATERIAL" "X7R"
					( Origin gFrontEnd )
				)
				( attribute "PACK_TYPE" "0402LF"
					( Origin gFrontEnd )
				)
				( attribute "PART_NUMBER" "A36096-046"
					( Origin gFrontEnd )
				)
				( attribute "PHYS_PAGE" "224"
					( Origin gFrontEnd )
				)
				( attribute "ROOM" "VDDQ_KLM_PWR_VR"
					( Origin gFrontEnd )
				)
				( attribute "ROT" "0"
					( Origin gFrontEnd )
				)
				( attribute "TOLERANCE" "10%"
					( Origin gFrontEnd )
				)
				( attribute "VALUE" "1000PF"
					( Origin gFrontEnd )
				)
				( attribute "VER" "1"
					( Origin gFrontEnd )
				)
				( attribute "VOLTAGE" "50V"
					( Units "uVoltage" "V" 1.000000)
					( Origin gFrontEnd )
				)
				( attribute "XY" "(2600,2225)"
					( Origin gFrontEnd )
				)
				( attribute "CHIPS_PART_NAME" "CAP"
					( Origin gPackager )
				)
				( attribute "CDS_PART_NAME" "CAP_0402LF-1000PF,50V,10%,X7R,A"
					( Origin gPackager )
				)
				( attribute "CDS_LOCATION" "CT28"
					( Origin gPackager )
				)
				( attribute "CDS_SEC" "1"
					( Origin gPackager )
				)
				( attribute "SEC" "1"
					( Origin gPackager )
				)
				( attribute "STATUS" "NOPOP"
					( Origin gFrontEnd )
				)
				( objectStatus "CT28" )
				( pin "a"
					( attribute "PN" "1"
						( Origin gPackager )
					)
					( objectStatus "CT28.1" )
				)
				( pin "b"
					( attribute "PN" "2"
						( Origin gPackager )
					)
					( objectStatus "CT28.2" )
				)
			)
			( gate "@baseboard_fab2_lib.baseboard_fab2(sch_1):page224_i124"
				( attribute "CDS_LIB" "dev_discrete"
					( Origin gPackager )
				)
				( attribute "LOCATION" "CT31"
					( Origin gFrontEnd )
				)
				( attribute "MATERIAL" "X7R"
					( Origin gFrontEnd )
				)
				( attribute "PACK_TYPE" "0402V"
					( Origin gFrontEnd )
				)
				( attribute "PART_NUMBER" "A36096-030"
					( Origin gFrontEnd )
				)
				( attribute "PHYS_PAGE" "224"
					( Origin gFrontEnd )
				)
				( attribute "ROOM" "PVCCIN_CPU0_PWR_VR"
					( Origin gFrontEnd )
				)
				( attribute "ROT" "0"
					( Origin gFrontEnd )
				)
				( attribute "TOLERANCE" "10%"
					( Origin gFrontEnd )
				)
				( attribute "VALUE" "0.1UF"
					( Origin gFrontEnd )
				)
				( attribute "VER" "1"
					( Origin gFrontEnd )
				)
				( attribute "VOLTAGE" "16V"
					( Units "uVoltage" "V" 1.000000)
					( Origin gFrontEnd )
				)
				( attribute "XY" "(800,-625)"
					( Origin gFrontEnd )
				)
				( attribute "CHIPS_PART_NAME" "CAP_A"
					( Origin gPackager )
				)
				( attribute "CDS_PART_NAME" "CAP_A_0402V-0.1UF,16V,10%,X7R,A"
					( Origin gPackager )
				)
				( attribute "CDS_LOCATION" "CT31"
					( Origin gPackager )
				)
				( attribute "CDS_SEC" "1"
					( Origin gPackager )
				)
				( attribute "SEC" "1"
					( Origin gPackager )
				)
				( attribute "STATUS" "NOPOP"
					( Origin gFrontEnd )
				)
				( objectStatus "CT31" )
				( pin "a"
					( attribute "PN" "1"
						( Origin gPackager )
					)
					( objectStatus "CT31.1" )
				)
				( pin "b"
					( attribute "PN" "2"
						( Origin gPackager )
					)
					( objectStatus "CT31.2" )
				)
			)
			( gate "@baseboard_fab2_lib.baseboard_fab2(sch_1):page224_i127"
				( attribute "CDS_LIB" "w_hdl"
					( Origin gPackager )
				)
				( attribute "CDS_LMAN_SYM_OUTLINE" "-50,25,50,-25"
					( Origin gPackager )
				)
				( attribute "LOCATION" "CT33"
					( Origin gFrontEnd )
				)
				( attribute "PACK_TYPE" "SMD-BCG6"
					( Origin gFrontEnd )
				)
				( attribute "PART_NUMBER" "78.22224.2BL"
					( Origin gFrontEnd )
				)
				( attribute "PHYS_PAGE" "224"
					( Origin gFrontEnd )
				)
				( attribute "ROT" "0"
					( Origin gFrontEnd )
				)
				( attribute "VALUE" "SC2K2P50V3KX-GP"
					( Origin gFrontEnd )
				)
				( attribute "VER" "1"
					( Origin gFrontEnd )
				)
				( attribute "XY" "(2800,-575)"
					( Origin gFrontEnd )
				)
				( attribute "CHIPS_PART_NAME" "SC2K2P50V3KX-GP"
					( Origin gPackager )
				)
				( attribute "CDS_PART_NAME" "SC2K2P50V3KX-GP_SMD-BCG6-SC2K2A"
					( Origin gPackager )
				)
				( attribute "CDS_LOCATION" "CT33"
					( Origin gPackager )
				)
				( attribute "CDS_SEC" "1"
					( Origin gPackager )
				)
				( attribute "SEC" "1"
					( Origin gPackager )
				)
				( attribute "STATUS" "NOPOP"
					( Origin gFrontEnd )
				)
				( objectStatus "CT33" )
				( pin "\1\"
					( attribute "PN" "1"
						( Origin gPackager )
					)
					( objectStatus "CT33.1" )
				)
				( pin "\2\"
					( attribute "PN" "2"
						( Origin gPackager )
					)
					( objectStatus "CT33.2" )
				)
			)
			( gate "@baseboard_fab2_lib.baseboard_fab2(sch_1):page224_i129"
				( attribute "CDS_LIB" "w_hdl"
					( Origin gPackager )
				)
				( attribute "CDS_LMAN_SYM_OUTLINE" "-50,75,50,-75"
					( Origin gPackager )
				)
				( attribute "CDS_LOCATION" "RT22"
					( Origin gPackager )
				)
				( attribute "CDS_SEC" "1"
					( Origin gPackager )
				)
				( attribute "LOCATION" "RT22"
					( Origin gFrontEnd )
				)
				( attribute "PACK_TYPE" "SMD-RG5"
					( Origin gFrontEnd )
				)
				( attribute "PART_NUMBER" "64.3R015.16L"
					( Origin gFrontEnd )
				)
				( attribute "PHYS_PAGE" "224"
					( Origin gFrontEnd )
				)
				( attribute "ROT" "4"
					( Origin gFrontEnd )
				)
				( attribute "VALUE" "3D01R5F-GP"
					( Origin gFrontEnd )
				)
				( attribute "VER" "1"
					( Origin gFrontEnd )
				)
				( attribute "XY" "(2800,-875)"
					( Origin gFrontEnd )
				)
				( attribute "CHIPS_PART_NAME" "3D01R5F-GP"
					( Origin gPackager )
				)
				( attribute "CDS_PART_NAME" "3D01R5F-GP_SMD-RG5-3D01R5F-GP,A"
					( Origin gPackager )
				)
				( attribute "SEC" "1"
					( Origin gPackager )
				)
				( attribute "STATUS" "NOPOP"
					( Origin gFrontEnd )
				)
				( objectStatus "RT22" )
				( pin "\1\"
					( attribute "PN" "1"
						( Origin gPackager )
					)
					( objectStatus "RT22.1" )
				)
				( pin "\2\"
					( attribute "PN" "2"
						( Origin gPackager )
					)
					( objectStatus "RT22.2" )
				)
			)
			( gate "@baseboard_fab2_lib.baseboard_fab2(sch_1):page224_i130"
				( attribute "CDS_LIB" "mstr_discrete"
					( Origin gPackager )
				)
				( attribute "LOCATION" "CT32"
					( Origin gFrontEnd )
				)
				( attribute "MATERIAL" "X7R"
					( Origin gFrontEnd )
				)
				( attribute "PACK_TYPE" "0402LF"
					( Origin gFrontEnd )
				)
				( attribute "PART_NUMBER" "A36096-046"
					( Origin gFrontEnd )
				)
				( attribute "PHYS_PAGE" "224"
					( Origin gFrontEnd )
				)
				( attribute "ROOM" "VDDQ_KLM_PWR_VR"
					( Origin gFrontEnd )
				)
				( attribute "ROT" "0"
					( Origin gFrontEnd )
				)
				( attribute "TOLERANCE" "10%"
					( Origin gFrontEnd )
				)
				( attribute "VALUE" "1000PF"
					( Origin gFrontEnd )
				)
				( attribute "VER" "1"
					( Origin gFrontEnd )
				)
				( attribute "VOLTAGE" "50V"
					( Units "uVoltage" "V" 1.000000)
					( Origin gFrontEnd )
				)
				( attribute "XY" "(2700,-75)"
					( Origin gFrontEnd )
				)
				( attribute "CHIPS_PART_NAME" "CAP"
					( Origin gPackager )
				)
				( attribute "CDS_PART_NAME" "CAP_0402LF-1000PF,50V,10%,X7R,A"
					( Origin gPackager )
				)
				( attribute "CDS_LOCATION" "CT32"
					( Origin gPackager )
				)
				( attribute "CDS_SEC" "1"
					( Origin gPackager )
				)
				( attribute "SEC" "1"
					( Origin gPackager )
				)
				( attribute "STATUS" "NOPOP"
					( Origin gFrontEnd )
				)
				( objectStatus "CT32" )
				( pin "a"
					( attribute "PN" "1"
						( Origin gPackager )
					)
					( objectStatus "CT32.1" )
				)
				( pin "b"
					( attribute "PN" "2"
						( Origin gPackager )
					)
					( objectStatus "CT32.2" )
				)
			)
			( gate "@baseboard_fab2_lib.baseboard_fab2(sch_1):page204_i85"
				( attribute "CDS_LIB" "dev_discrete"
					( Origin gPackager )
				)
				( attribute "LOCATION" "CT36"
					( Origin gFrontEnd )
				)
				( attribute "MATERIAL" "X7R"
					( Origin gFrontEnd )
				)
				( attribute "PACK_TYPE" "0402V"
					( Origin gFrontEnd )
				)
				( attribute "PART_NUMBER" "A36096-030"
					( Origin gFrontEnd )
				)
				( attribute "PHYS_PAGE" "204"
					( Origin gFrontEnd )
				)
				( attribute "ROOM" "PVCCIN_CPU0_PWR_VR"
					( Origin gFrontEnd )
				)
				( attribute "ROT" "0"
					( Origin gFrontEnd )
				)
				( attribute "TOLERANCE" "10%"
					( Origin gFrontEnd )
				)
				( attribute "VALUE" "0.1UF"
					( Origin gFrontEnd )
				)
				( attribute "VER" "1"
					( Origin gFrontEnd )
				)
				( attribute "VOLTAGE" "16V"
					( Units "uVoltage" "V" 1.000000)
					( Origin gFrontEnd )
				)
				( attribute "XY" "(-4225,3200)"
					( Origin gFrontEnd )
				)
				( attribute "CHIPS_PART_NAME" "CAP_A"
					( Origin gPackager )
				)
				( attribute "CDS_PART_NAME" "CAP_A_0402V-0.1UF,16V,10%,X7R,A"
					( Origin gPackager )
				)
				( attribute "CDS_LOCATION" "CT36"
					( Origin gPackager )
				)
				( attribute "CDS_SEC" "1"
					( Origin gPackager )
				)
				( attribute "SEC" "1"
					( Origin gPackager )
				)
				( attribute "STATUS" "NOPOP"
					( Origin gFrontEnd )
				)
				( objectStatus "CT36" )
				( pin "a"
					( attribute "PN" "1"
						( Origin gPackager )
					)
					( objectStatus "CT36.1" )
				)
				( pin "b"
					( attribute "PN" "2"
						( Origin gPackager )
					)
					( objectStatus "CT36.2" )
				)
			)
			( gate "@baseboard_fab2_lib.baseboard_fab2(sch_1):page203_i110"
				( attribute "BOM_COST" "DEBUG"
					( Origin gFrontEnd )
				)
				( attribute "CDS_LIB" "mstr_discrete"
					( Origin gPackager )
				)
				( attribute "LOCATION" "RT25"
					( Origin gFrontEnd )
				)
				( attribute "MATERIAL" "CHIP"
					( Origin gFrontEnd )
				)
				( attribute "PACK_TYPE" "0402"
					( Origin gFrontEnd )
				)
				( attribute "PART_NUMBER" "G21497-005"
					( Origin gFrontEnd )
				)
				( attribute "PHYS_PAGE" "203"
					( Origin gFrontEnd )
				)
				( attribute "ROOM" "BMC_DEBUG_HEADER"
					( Origin gFrontEnd )
				)
				( attribute "ROT" "0"
					( Origin gFrontEnd )
				)
				( attribute "TOLERANCE" "5%"
					( Origin gFrontEnd )
				)
				( attribute "VALUE" "0.0"
					( Origin gFrontEnd )
				)
				( attribute "VER" "1"
					( Origin gFrontEnd )
				)
				( attribute "WATTAGE" "1/16W"
					( Origin gFrontEnd )
				)
				( attribute "XY" "(-4950,3700)"
					( Origin gFrontEnd )
				)
				( attribute "CHIPS_PART_NAME" "RES"
					( Origin gPackager )
				)
				( attribute "CDS_PART_NAME" "RES_0402-0.0,5%,1/16W,CHIP,G21A"
					( Origin gPackager )
				)
				( attribute "CDS_LOCATION" "RT25"
					( Origin gPackager )
				)
				( attribute "CDS_SEC" "1"
					( Origin gPackager )
				)
				( attribute "SEC" "1"
					( Origin gPackager )
				)
				( objectStatus "RT25" )
				( pin "a"
					( attribute "PN" "1"
						( Origin gPackager )
					)
					( objectStatus "RT25.1" )
				)
				( pin "b"
					( attribute "PN" "2"
						( Origin gPackager )
					)
					( objectStatus "RT25.2" )
				)
			)
			( gate "@baseboard_fab2_lib.baseboard_fab2(sch_1):page204_i88"
				( attribute "CDS_LIB" "mstr_discrete"
					( Origin gPackager )
				)
				( attribute "LOCATION" "CT34"
					( Origin gFrontEnd )
				)
				( attribute "MATERIAL" "X7R"
					( Origin gFrontEnd )
				)
				( attribute "PACK_TYPE" "0402LF"
					( Origin gFrontEnd )
				)
				( attribute "PART_NUMBER" "A36096-046"
					( Origin gFrontEnd )
				)
				( attribute "PHYS_PAGE" "204"
					( Origin gFrontEnd )
				)
				( attribute "ROOM" "VDDQ_KLM_PWR_VR"
					( Origin gFrontEnd )
				)
				( attribute "ROT" "0"
					( Origin gFrontEnd )
				)
				( attribute "TOLERANCE" "10%"
					( Origin gFrontEnd )
				)
				( attribute "VALUE" "1000PF"
					( Origin gFrontEnd )
				)
				( attribute "VER" "1"
					( Origin gFrontEnd )
				)
				( attribute "VOLTAGE" "50V"
					( Units "uVoltage" "V" 1.000000)
					( Origin gFrontEnd )
				)
				( attribute "XY" "(-2450,3725)"
					( Origin gFrontEnd )
				)
				( attribute "CHIPS_PART_NAME" "CAP"
					( Origin gPackager )
				)
				( attribute "CDS_PART_NAME" "CAP_0402LF-1000PF,50V,10%,X7R,A"
					( Origin gPackager )
				)
				( attribute "STATUS" "NOPOP"
					( Origin gFrontEnd )
				)
				( attribute "CDS_LOCATION" "CT34"
					( Origin gPackager )
				)
				( attribute "CDS_SEC" "1"
					( Origin gPackager )
				)
				( attribute "SEC" "1"
					( Origin gPackager )
				)
				( objectStatus "CT34" )
				( pin "a"
					( attribute "PN" "1"
						( Origin gPackager )
					)
					( objectStatus "CT34.1" )
				)
				( pin "b"
					( attribute "PN" "2"
						( Origin gPackager )
					)
					( objectStatus "CT34.2" )
				)
			)
			( gate "@baseboard_fab2_lib.baseboard_fab2(sch_1):page204_i90"
				( attribute "CDS_LIB" "w_hdl"
					( Origin gPackager )
				)
				( attribute "CDS_LMAN_SYM_OUTLINE" "-50,25,50,-25"
					( Origin gPackager )
				)
				( attribute "LOCATION" "CT35"
					( Origin gFrontEnd )
				)
				( attribute "PACK_TYPE" "SMD-BCG6"
					( Origin gFrontEnd )
				)
				( attribute "PART_NUMBER" "78.22224.2BL"
					( Origin gFrontEnd )
				)
				( attribute "PHYS_PAGE" "204"
					( Origin gFrontEnd )
				)
				( attribute "ROT" "0"
					( Origin gFrontEnd )
				)
				( attribute "VALUE" "SC2K2P50V3KX-GP"
					( Origin gFrontEnd )
				)
				( attribute "VER" "1"
					( Origin gFrontEnd )
				)
				( attribute "XY" "(-2350,3275)"
					( Origin gFrontEnd )
				)
				( attribute "CHIPS_PART_NAME" "SC2K2P50V3KX-GP"
					( Origin gPackager )
				)
				( attribute "CDS_PART_NAME" "SC2K2P50V3KX-GP_SMD-BCG6-SC2K2A"
					( Origin gPackager )
				)
				( attribute "CDS_LOCATION" "CT35"
					( Origin gPackager )
				)
				( attribute "CDS_SEC" "1"
					( Origin gPackager )
				)
				( attribute "SEC" "1"
					( Origin gPackager )
				)
				( attribute "STATUS" "NOPOP"
					( Origin gFrontEnd )
				)
				( objectStatus "CT35" )
				( pin "\1\"
					( attribute "PN" "1"
						( Origin gPackager )
					)
					( objectStatus "CT35.1" )
				)
				( pin "\2\"
					( attribute "PN" "2"
						( Origin gPackager )
					)
					( objectStatus "CT35.2" )
				)
			)
			( gate "@baseboard_fab2_lib.baseboard_fab2(sch_1):page204_i91"
				( attribute "CDS_LIB" "w_hdl"
					( Origin gPackager )
				)
				( attribute "CDS_LMAN_SYM_OUTLINE" "-50,75,50,-75"
					( Origin gPackager )
				)
				( attribute "CDS_LOCATION" "RT24"
					( Origin gPackager )
				)
				( attribute "CDS_SEC" "1"
					( Origin gPackager )
				)
				( attribute "LOCATION" "RT24"
					( Origin gFrontEnd )
				)
				( attribute "PACK_TYPE" "SMD-RG5"
					( Origin gFrontEnd )
				)
				( attribute "PART_NUMBER" "64.3R015.16L"
					( Origin gFrontEnd )
				)
				( attribute "PHYS_PAGE" "204"
					( Origin gFrontEnd )
				)
				( attribute "ROT" "4"
					( Origin gFrontEnd )
				)
				( attribute "VALUE" "3D01R5F-GP"
					( Origin gFrontEnd )
				)
				( attribute "VER" "1"
					( Origin gFrontEnd )
				)
				( attribute "XY" "(-2350,2975)"
					( Origin gFrontEnd )
				)
				( attribute "CHIPS_PART_NAME" "3D01R5F-GP"
					( Origin gPackager )
				)
				( attribute "CDS_PART_NAME" "3D01R5F-GP_SMD-RG5-3D01R5F-GP,A"
					( Origin gPackager )
				)
				( attribute "SEC" "1"
					( Origin gPackager )
				)
				( attribute "STATUS" "NOPOP"
					( Origin gFrontEnd )
				)
				( objectStatus "RT24" )
				( pin "\1\"
					( attribute "PN" "1"
						( Origin gPackager )
					)
					( objectStatus "RT24.1" )
				)
				( pin "\2\"
					( attribute "PN" "2"
						( Origin gPackager )
					)
					( objectStatus "RT24.2" )
				)
			)
			( gate "@baseboard_fab2_lib.baseboard_fab2(sch_1):page203_i93"
				( attribute "CDS_LIB" "dev_discrete"
					( Origin gPackager )
				)
				( attribute "LOCATION" "CT40"
					( Origin gFrontEnd )
				)
				( attribute "MATERIAL" "X7R"
					( Origin gFrontEnd )
				)
				( attribute "PACK_TYPE" "0402V"
					( Origin gFrontEnd )
				)
				( attribute "PART_NUMBER" "A36096-030"
					( Origin gFrontEnd )
				)
				( attribute "PHYS_PAGE" "203"
					( Origin gFrontEnd )
				)
				( attribute "ROOM" "PVCCIN_CPU0_PWR_VR"
					( Origin gFrontEnd )
				)
				( attribute "ROT" "0"
					( Origin gFrontEnd )
				)
				( attribute "TOLERANCE" "10%"
					( Origin gFrontEnd )
				)
				( attribute "VALUE" "0.1UF"
					( Origin gFrontEnd )
				)
				( attribute "VER" "1"
					( Origin gFrontEnd )
				)
				( attribute "VOLTAGE" "16V"
					( Units "uVoltage" "V" 1.000000)
					( Origin gFrontEnd )
				)
				( attribute "XY" "(-4125,675)"
					( Origin gFrontEnd )
				)
				( attribute "CHIPS_PART_NAME" "CAP_A"
					( Origin gPackager )
				)
				( attribute "CDS_PART_NAME" "CAP_A_0402V-0.1UF,16V,10%,X7R,A"
					( Origin gPackager )
				)
				( attribute "CDS_LOCATION" "CT40"
					( Origin gPackager )
				)
				( attribute "CDS_SEC" "1"
					( Origin gPackager )
				)
				( attribute "SEC" "1"
					( Origin gPackager )
				)
				( attribute "STATUS" "NOPOP"
					( Origin gFrontEnd )
				)
				( objectStatus "CT40" )
				( pin "a"
					( attribute "PN" "1"
						( Origin gPackager )
					)
					( objectStatus "CT40.1" )
				)
				( pin "b"
					( attribute "PN" "2"
						( Origin gPackager )
					)
					( objectStatus "CT40.2" )
				)
			)
			( gate "@baseboard_fab2_lib.baseboard_fab2(sch_1):page219_i130"
				( attribute "BOM_COST" "DEBUG"
					( Origin gFrontEnd )
				)
				( attribute "CDS_LIB" "mstr_discrete"
					( Origin gPackager )
				)
				( attribute "LOCATION" "RT31"
					( Origin gFrontEnd )
				)
				( attribute "MATERIAL" "CHIP"
					( Origin gFrontEnd )
				)
				( attribute "PACK_TYPE" "0402"
					( Origin gFrontEnd )
				)
				( attribute "PART_NUMBER" "G21497-005"
					( Origin gFrontEnd )
				)
				( attribute "PHYS_PAGE" "219"
					( Origin gFrontEnd )
				)
				( attribute "ROOM" "BMC_DEBUG_HEADER"
					( Origin gFrontEnd )
				)
				( attribute "ROT" "0"
					( Origin gFrontEnd )
				)
				( attribute "TOLERANCE" "5%"
					( Origin gFrontEnd )
				)
				( attribute "VALUE" "0.0"
					( Origin gFrontEnd )
				)
				( attribute "VER" "1"
					( Origin gFrontEnd )
				)
				( attribute "WATTAGE" "1/16W"
					( Origin gFrontEnd )
				)
				( attribute "XY" "(-100,-275)"
					( Origin gFrontEnd )
				)
				( attribute "CHIPS_PART_NAME" "RES"
					( Origin gPackager )
				)
				( attribute "CDS_PART_NAME" "RES_0402-0.0,5%,1/16W,CHIP,G21A"
					( Origin gPackager )
				)
				( attribute "CDS_LOCATION" "RT31"
					( Origin gPackager )
				)
				( attribute "CDS_SEC" "1"
					( Origin gPackager )
				)
				( attribute "SEC" "1"
					( Origin gPackager )
				)
				( objectStatus "RT31" )
				( pin "a"
					( attribute "PN" "1"
						( Origin gPackager )
					)
					( objectStatus "RT31.1" )
				)
				( pin "b"
					( attribute "PN" "2"
						( Origin gPackager )
					)
					( objectStatus "RT31.2" )
				)
			)
			( gate "@baseboard_fab2_lib.baseboard_fab2(sch_1):page203_i96"
				( attribute "CDS_LIB" "dev_discrete"
					( Origin gPackager )
				)
				( attribute "LOCATION" "CT39"
					( Origin gFrontEnd )
				)
				( attribute "MATERIAL" "X7R"
					( Origin gFrontEnd )
				)
				( attribute "PACK_TYPE" "0402V"
					( Origin gFrontEnd )
				)
				( attribute "PART_NUMBER" "A36096-030"
					( Origin gFrontEnd )
				)
				( attribute "PHYS_PAGE" "203"
					( Origin gFrontEnd )
				)
				( attribute "ROOM" "PVCCIN_CPU0_PWR_VR"
					( Origin gFrontEnd )
				)
				( attribute "ROT" "0"
					( Origin gFrontEnd )
				)
				( attribute "TOLERANCE" "10%"
					( Origin gFrontEnd )
				)
				( attribute "VALUE" "0.1UF"
					( Origin gFrontEnd )
				)
				( attribute "VER" "1"
					( Origin gFrontEnd )
				)
				( attribute "VOLTAGE" "16V"
					( Units "uVoltage" "V" 1.000000)
					( Origin gFrontEnd )
				)
				( attribute "XY" "(-4125,3375)"
					( Origin gFrontEnd )
				)
				( attribute "CHIPS_PART_NAME" "CAP_A"
					( Origin gPackager )
				)
				( attribute "CDS_PART_NAME" "CAP_A_0402V-0.1UF,16V,10%,X7R,A"
					( Origin gPackager )
				)
				( attribute "CDS_LOCATION" "CT39"
					( Origin gPackager )
				)
				( attribute "CDS_SEC" "1"
					( Origin gPackager )
				)
				( attribute "SEC" "1"
					( Origin gPackager )
				)
				( attribute "STATUS" "NOPOP"
					( Origin gFrontEnd )
				)
				( objectStatus "CT39" )
				( pin "a"
					( attribute "PN" "1"
						( Origin gPackager )
					)
					( objectStatus "CT39.1" )
				)
				( pin "b"
					( attribute "PN" "2"
						( Origin gPackager )
					)
					( objectStatus "CT39.2" )
				)
			)
			( gate "@baseboard_fab2_lib.baseboard_fab2(sch_1):page219_i129"
				( attribute "BOM_COST" "DEBUG"
					( Origin gFrontEnd )
				)
				( attribute "CDS_LIB" "mstr_discrete"
					( Origin gPackager )
				)
				( attribute "LOCATION" "RT30"
					( Origin gFrontEnd )
				)
				( attribute "MATERIAL" "CHIP"
					( Origin gFrontEnd )
				)
				( attribute "PACK_TYPE" "0402"
					( Origin gFrontEnd )
				)
				( attribute "PART_NUMBER" "G21497-005"
					( Origin gFrontEnd )
				)
				( attribute "PHYS_PAGE" "219"
					( Origin gFrontEnd )
				)
				( attribute "ROOM" "BMC_DEBUG_HEADER"
					( Origin gFrontEnd )
				)
				( attribute "ROT" "0"
					( Origin gFrontEnd )
				)
				( attribute "TOLERANCE" "5%"
					( Origin gFrontEnd )
				)
				( attribute "VALUE" "0.0"
					( Origin gFrontEnd )
				)
				( attribute "VER" "1"
					( Origin gFrontEnd )
				)
				( attribute "WATTAGE" "1/16W"
					( Origin gFrontEnd )
				)
				( attribute "XY" "(-350,1850)"
					( Origin gFrontEnd )
				)
				( attribute "CHIPS_PART_NAME" "RES"
					( Origin gPackager )
				)
				( attribute "CDS_PART_NAME" "RES_0402-0.0,5%,1/16W,CHIP,G21A"
					( Origin gPackager )
				)
				( attribute "CDS_LOCATION" "RT30"
					( Origin gPackager )
				)
				( attribute "CDS_SEC" "1"
					( Origin gPackager )
				)
				( attribute "SEC" "1"
					( Origin gPackager )
				)
				( objectStatus "RT30" )
				( pin "a"
					( attribute "PN" "1"
						( Origin gPackager )
					)
					( objectStatus "RT30.1" )
				)
				( pin "b"
					( attribute "PN" "2"
						( Origin gPackager )
					)
					( objectStatus "RT30.2" )
				)
			)
			( gate "@baseboard_fab2_lib.baseboard_fab2(sch_1):page203_i99"
				( attribute "CDS_LIB" "mstr_discrete"
					( Origin gPackager )
				)
				( attribute "LOCATION" "CT37"
					( Origin gFrontEnd )
				)
				( attribute "MATERIAL" "X7R"
					( Origin gFrontEnd )
				)
				( attribute "PACK_TYPE" "0402LF"
					( Origin gFrontEnd )
				)
				( attribute "PART_NUMBER" "A36096-046"
					( Origin gFrontEnd )
				)
				( attribute "PHYS_PAGE" "203"
					( Origin gFrontEnd )
				)
				( attribute "ROOM" "VDDQ_KLM_PWR_VR"
					( Origin gFrontEnd )
				)
				( attribute "ROT" "0"
					( Origin gFrontEnd )
				)
				( attribute "TOLERANCE" "10%"
					( Origin gFrontEnd )
				)
				( attribute "VALUE" "1000PF"
					( Origin gFrontEnd )
				)
				( attribute "VER" "1"
					( Origin gFrontEnd )
				)
				( attribute "VOLTAGE" "50V"
					( Units "uVoltage" "V" 1.000000)
					( Origin gFrontEnd )
				)
				( attribute "XY" "(-2200,3925)"
					( Origin gFrontEnd )
				)
				( attribute "CHIPS_PART_NAME" "CAP"
					( Origin gPackager )
				)
				( attribute "CDS_PART_NAME" "CAP_0402LF-1000PF,50V,10%,X7R,A"
					( Origin gPackager )
				)
				( attribute "CDS_LOCATION" "CT37"
					( Origin gPackager )
				)
				( attribute "CDS_SEC" "1"
					( Origin gPackager )
				)
				( attribute "SEC" "1"
					( Origin gPackager )
				)
				( attribute "STATUS" "NOPOP"
					( Origin gFrontEnd )
				)
				( objectStatus "CT37" )
				( pin "a"
					( attribute "PN" "1"
						( Origin gPackager )
					)
					( objectStatus "CT37.1" )
				)
				( pin "b"
					( attribute "PN" "2"
						( Origin gPackager )
					)
					( objectStatus "CT37.2" )
				)
			)
			( gate "@baseboard_fab2_lib.baseboard_fab2(sch_1):page203_i101"
				( attribute "CDS_LIB" "w_hdl"
					( Origin gPackager )
				)
				( attribute "CDS_LMAN_SYM_OUTLINE" "-50,25,50,-25"
					( Origin gPackager )
				)
				( attribute "LOCATION" "CT38"
					( Origin gFrontEnd )
				)
				( attribute "PACK_TYPE" "SMD-BCG6"
					( Origin gFrontEnd )
				)
				( attribute "PART_NUMBER" "78.22224.2BL"
					( Origin gFrontEnd )
				)
				( attribute "PHYS_PAGE" "203"
					( Origin gFrontEnd )
				)
				( attribute "ROT" "0"
					( Origin gFrontEnd )
				)
				( attribute "VALUE" "SC2K2P50V3KX-GP"
					( Origin gFrontEnd )
				)
				( attribute "VER" "1"
					( Origin gFrontEnd )
				)
				( attribute "XY" "(-2100,3475)"
					( Origin gFrontEnd )
				)
				( attribute "CHIPS_PART_NAME" "SC2K2P50V3KX-GP"
					( Origin gPackager )
				)
				( attribute "CDS_PART_NAME" "SC2K2P50V3KX-GP_SMD-BCG6-SC2K2A"
					( Origin gPackager )
				)
				( attribute "CDS_LOCATION" "CT38"
					( Origin gPackager )
				)
				( attribute "CDS_SEC" "1"
					( Origin gPackager )
				)
				( attribute "SEC" "1"
					( Origin gPackager )
				)
				( attribute "STATUS" "NOPOP"
					( Origin gFrontEnd )
				)
				( objectStatus "CT38" )
				( pin "\1\"
					( attribute "PN" "1"
						( Origin gPackager )
					)
					( objectStatus "CT38.1" )
				)
				( pin "\2\"
					( attribute "PN" "2"
						( Origin gPackager )
					)
					( objectStatus "CT38.2" )
				)
			)
			( gate "@baseboard_fab2_lib.baseboard_fab2(sch_1):page203_i102"
				( attribute "CDS_LIB" "w_hdl"
					( Origin gPackager )
				)
				( attribute "CDS_LMAN_SYM_OUTLINE" "-50,75,50,-75"
					( Origin gPackager )
				)
				( attribute "CDS_LOCATION" "RT26"
					( Origin gPackager )
				)
				( attribute "CDS_SEC" "1"
					( Origin gPackager )
				)
				( attribute "LOCATION" "RT26"
					( Origin gFrontEnd )
				)
				( attribute "PACK_TYPE" "SMD-RG5"
					( Origin gFrontEnd )
				)
				( attribute "PART_NUMBER" "64.3R015.16L"
					( Origin gFrontEnd )
				)
				( attribute "PHYS_PAGE" "203"
					( Origin gFrontEnd )
				)
				( attribute "ROT" "4"
					( Origin gFrontEnd )
				)
				( attribute "VALUE" "3D01R5F-GP"
					( Origin gFrontEnd )
				)
				( attribute "VER" "1"
					( Origin gFrontEnd )
				)
				( attribute "XY" "(-2100,3200)"
					( Origin gFrontEnd )
				)
				( attribute "CHIPS_PART_NAME" "3D01R5F-GP"
					( Origin gPackager )
				)
				( attribute "CDS_PART_NAME" "3D01R5F-GP_SMD-RG5-3D01R5F-GP,A"
					( Origin gPackager )
				)
				( attribute "SEC" "1"
					( Origin gPackager )
				)
				( attribute "STATUS" "NOPOP"
					( Origin gFrontEnd )
				)
				( objectStatus "RT26" )
				( pin "\1\"
					( attribute "PN" "1"
						( Origin gPackager )
					)
					( objectStatus "RT26.1" )
				)
				( pin "\2\"
					( attribute "PN" "2"
						( Origin gPackager )
					)
					( objectStatus "RT26.2" )
				)
			)
			( gate "@baseboard_fab2_lib.baseboard_fab2(sch_1):page203_i105"
				( attribute "CDS_LIB" "w_hdl"
					( Origin gPackager )
				)
				( attribute "CDS_LMAN_SYM_OUTLINE" "-50,75,50,-75"
					( Origin gPackager )
				)
				( attribute "CDS_LOCATION" "RT27"
					( Origin gPackager )
				)
				( attribute "CDS_SEC" "1"
					( Origin gPackager )
				)
				( attribute "LOCATION" "RT27"
					( Origin gFrontEnd )
				)
				( attribute "PACK_TYPE" "SMD-RG5"
					( Origin gFrontEnd )
				)
				( attribute "PART_NUMBER" "64.3R015.16L"
					( Origin gFrontEnd )
				)
				( attribute "PHYS_PAGE" "203"
					( Origin gFrontEnd )
				)
				( attribute "ROT" "4"
					( Origin gFrontEnd )
				)
				( attribute "VALUE" "3D01R5F-GP"
					( Origin gFrontEnd )
				)
				( attribute "VER" "1"
					( Origin gFrontEnd )
				)
				( attribute "XY" "(-2100,575)"
					( Origin gFrontEnd )
				)
				( attribute "CHIPS_PART_NAME" "3D01R5F-GP"
					( Origin gPackager )
				)
				( attribute "CDS_PART_NAME" "3D01R5F-GP_SMD-RG5-3D01R5F-GP,A"
					( Origin gPackager )
				)
				( attribute "SEC" "1"
					( Origin gPackager )
				)
				( attribute "STATUS" "NOPOP"
					( Origin gFrontEnd )
				)
				( objectStatus "RT27" )
				( pin "\1\"
					( attribute "PN" "1"
						( Origin gPackager )
					)
					( objectStatus "RT27.1" )
				)
				( pin "\2\"
					( attribute "PN" "2"
						( Origin gPackager )
					)
					( objectStatus "RT27.2" )
				)
			)
			( gate "@baseboard_fab2_lib.baseboard_fab2(sch_1):page203_i106"
				( attribute "CDS_LIB" "w_hdl"
					( Origin gPackager )
				)
				( attribute "CDS_LMAN_SYM_OUTLINE" "-50,25,50,-25"
					( Origin gPackager )
				)
				( attribute "LOCATION" "CT41"
					( Origin gFrontEnd )
				)
				( attribute "PACK_TYPE" "SMD-BCG6"
					( Origin gFrontEnd )
				)
				( attribute "PART_NUMBER" "78.22224.2BL"
					( Origin gFrontEnd )
				)
				( attribute "PHYS_PAGE" "203"
					( Origin gFrontEnd )
				)
				( attribute "ROT" "0"
					( Origin gFrontEnd )
				)
				( attribute "VALUE" "SC2K2P50V3KX-GP"
					( Origin gFrontEnd )
				)
				( attribute "VER" "1"
					( Origin gFrontEnd )
				)
				( attribute "XY" "(-2100,800)"
					( Origin gFrontEnd )
				)
				( attribute "CHIPS_PART_NAME" "SC2K2P50V3KX-GP"
					( Origin gPackager )
				)
				( attribute "CDS_PART_NAME" "SC2K2P50V3KX-GP_SMD-BCG6-SC2K2A"
					( Origin gPackager )
				)
				( attribute "STATUS" "NOPOP"
					( Origin gFrontEnd )
				)
				( attribute "CDS_LOCATION" "CT41"
					( Origin gPackager )
				)
				( attribute "CDS_SEC" "1"
					( Origin gPackager )
				)
				( attribute "SEC" "1"
					( Origin gPackager )
				)
				( objectStatus "CT41" )
				( pin "\1\"
					( attribute "PN" "1"
						( Origin gPackager )
					)
					( objectStatus "CT41.1" )
				)
				( pin "\2\"
					( attribute "PN" "2"
						( Origin gPackager )
					)
					( objectStatus "CT41.2" )
				)
			)
			( gate "@baseboard_fab2_lib.baseboard_fab2(sch_1):page203_i108"
				( attribute "CDS_LIB" "mstr_discrete"
					( Origin gPackager )
				)
				( attribute "LOCATION" "CT42"
					( Origin gFrontEnd )
				)
				( attribute "MATERIAL" "X7R"
					( Origin gFrontEnd )
				)
				( attribute "PACK_TYPE" "0402LF"
					( Origin gFrontEnd )
				)
				( attribute "PART_NUMBER" "A36096-046"
					( Origin gFrontEnd )
				)
				( attribute "PHYS_PAGE" "203"
					( Origin gFrontEnd )
				)
				( attribute "ROOM" "VDDQ_KLM_PWR_VR"
					( Origin gFrontEnd )
				)
				( attribute "ROT" "0"
					( Origin gFrontEnd )
				)
				( attribute "TOLERANCE" "10%"
					( Origin gFrontEnd )
				)
				( attribute "VALUE" "1000PF"
					( Origin gFrontEnd )
				)
				( attribute "VER" "1"
					( Origin gFrontEnd )
				)
				( attribute "VOLTAGE" "50V"
					( Units "uVoltage" "V" 1.000000)
					( Origin gFrontEnd )
				)
				( attribute "XY" "(-2150,1250)"
					( Origin gFrontEnd )
				)
				( attribute "CHIPS_PART_NAME" "CAP"
					( Origin gPackager )
				)
				( attribute "CDS_PART_NAME" "CAP_0402LF-1000PF,50V,10%,X7R,A"
					( Origin gPackager )
				)
				( attribute "CDS_LOCATION" "CT42"
					( Origin gPackager )
				)
				( attribute "CDS_SEC" "1"
					( Origin gPackager )
				)
				( attribute "SEC" "1"
					( Origin gPackager )
				)
				( attribute "STATUS" "NOPOP"
					( Origin gFrontEnd )
				)
				( objectStatus "CT42" )
				( pin "a"
					( attribute "PN" "1"
						( Origin gPackager )
					)
					( objectStatus "CT42.1" )
				)
				( pin "b"
					( attribute "PN" "2"
						( Origin gPackager )
					)
					( objectStatus "CT42.2" )
				)
			)
			( gate "@baseboard_fab2_lib.baseboard_fab2(sch_1):page219_i113"
				( attribute "CDS_LIB" "dev_discrete"
					( Origin gPackager )
				)
				( attribute "LOCATION" "CT46"
					( Origin gFrontEnd )
				)
				( attribute "MATERIAL" "X7R"
					( Origin gFrontEnd )
				)
				( attribute "PACK_TYPE" "0402V"
					( Origin gFrontEnd )
				)
				( attribute "PART_NUMBER" "A36096-030"
					( Origin gFrontEnd )
				)
				( attribute "PHYS_PAGE" "219"
					( Origin gFrontEnd )
				)
				( attribute "ROOM" "PVCCIN_CPU0_PWR_VR"
					( Origin gFrontEnd )
				)
				( attribute "ROT" "0"
					( Origin gFrontEnd )
				)
				( attribute "TOLERANCE" "10%"
					( Origin gFrontEnd )
				)
				( attribute "VALUE" "0.1UF"
					( Origin gFrontEnd )
				)
				( attribute "VER" "1"
					( Origin gFrontEnd )
				)
				( attribute "VOLTAGE" "16V"
					( Units "uVoltage" "V" 1.000000)
					( Origin gFrontEnd )
				)
				( attribute "XY" "(875,-550)"
					( Origin gFrontEnd )
				)
				( attribute "CHIPS_PART_NAME" "CAP_A"
					( Origin gPackager )
				)
				( attribute "CDS_PART_NAME" "CAP_A_0402V-0.1UF,16V,10%,X7R,A"
					( Origin gPackager )
				)
				( attribute "CDS_LOCATION" "CT46"
					( Origin gPackager )
				)
				( attribute "CDS_SEC" "1"
					( Origin gPackager )
				)
				( attribute "SEC" "1"
					( Origin gPackager )
				)
				( attribute "STATUS" "NOPOP"
					( Origin gFrontEnd )
				)
				( objectStatus "CT46" )
				( pin "a"
					( attribute "PN" "1"
						( Origin gPackager )
					)
					( objectStatus "CT46.1" )
				)
				( pin "b"
					( attribute "PN" "2"
						( Origin gPackager )
					)
					( objectStatus "CT46.2" )
				)
			)
			( gate "@baseboard_fab2_lib.baseboard_fab2(sch_1):page216_i127"
				( attribute "BOM_COST" "DEBUG"
					( Origin gFrontEnd )
				)
				( attribute "CDS_LIB" "mstr_discrete"
					( Origin gPackager )
				)
				( attribute "LOCATION" "RT36"
					( Origin gFrontEnd )
				)
				( attribute "MATERIAL" "CHIP"
					( Origin gFrontEnd )
				)
				( attribute "PACK_TYPE" "0402"
					( Origin gFrontEnd )
				)
				( attribute "PART_NUMBER" "G21497-005"
					( Origin gFrontEnd )
				)
				( attribute "PHYS_PAGE" "216"
					( Origin gFrontEnd )
				)
				( attribute "ROOM" "BMC_DEBUG_HEADER"
					( Origin gFrontEnd )
				)
				( attribute "ROT" "0"
					( Origin gFrontEnd )
				)
				( attribute "TOLERANCE" "5%"
					( Origin gFrontEnd )
				)
				( attribute "VALUE" "0.0"
					( Origin gFrontEnd )
				)
				( attribute "VER" "1"
					( Origin gFrontEnd )
				)
				( attribute "WATTAGE" "1/16W"
					( Origin gFrontEnd )
				)
				( attribute "XY" "(-225,-325)"
					( Origin gFrontEnd )
				)
				( attribute "CHIPS_PART_NAME" "RES"
					( Origin gPackager )
				)
				( attribute "CDS_PART_NAME" "RES_0402-0.0,5%,1/16W,CHIP,G21A"
					( Origin gPackager )
				)
				( attribute "CDS_LOCATION" "RT36"
					( Origin gPackager )
				)
				( attribute "CDS_SEC" "1"
					( Origin gPackager )
				)
				( attribute "SEC" "1"
					( Origin gPackager )
				)
				( objectStatus "RT36" )
				( pin "a"
					( attribute "PN" "1"
						( Origin gPackager )
					)
					( objectStatus "RT36.1" )
				)
				( pin "b"
					( attribute "PN" "2"
						( Origin gPackager )
					)
					( objectStatus "RT36.2" )
				)
			)
			( gate "@baseboard_fab2_lib.baseboard_fab2(sch_1):page219_i116"
				( attribute "CDS_LIB" "dev_discrete"
					( Origin gPackager )
				)
				( attribute "LOCATION" "CT45"
					( Origin gFrontEnd )
				)
				( attribute "MATERIAL" "X7R"
					( Origin gFrontEnd )
				)
				( attribute "PACK_TYPE" "0402V"
					( Origin gFrontEnd )
				)
				( attribute "PART_NUMBER" "A36096-030"
					( Origin gFrontEnd )
				)
				( attribute "PHYS_PAGE" "219"
					( Origin gFrontEnd )
				)
				( attribute "ROOM" "PVCCIN_CPU0_PWR_VR"
					( Origin gFrontEnd )
				)
				( attribute "ROT" "0"
					( Origin gFrontEnd )
				)
				( attribute "TOLERANCE" "10%"
					( Origin gFrontEnd )
				)
				( attribute "VALUE" "0.1UF"
					( Origin gFrontEnd )
				)
				( attribute "VER" "1"
					( Origin gFrontEnd )
				)
				( attribute "VOLTAGE" "16V"
					( Units "uVoltage" "V" 1.000000)
					( Origin gFrontEnd )
				)
				( attribute "XY" "(825,1575)"
					( Origin gFrontEnd )
				)
				( attribute "CHIPS_PART_NAME" "CAP_A"
					( Origin gPackager )
				)
				( attribute "CDS_PART_NAME" "CAP_A_0402V-0.1UF,16V,10%,X7R,A"
					( Origin gPackager )
				)
				( attribute "CDS_LOCATION" "CT45"
					( Origin gPackager )
				)
				( attribute "CDS_SEC" "1"
					( Origin gPackager )
				)
				( attribute "SEC" "1"
					( Origin gPackager )
				)
				( attribute "STATUS" "NOPOP"
					( Origin gFrontEnd )
				)
				( objectStatus "CT45" )
				( pin "a"
					( attribute "PN" "1"
						( Origin gPackager )
					)
					( objectStatus "CT45.1" )
				)
				( pin "b"
					( attribute "PN" "2"
						( Origin gPackager )
					)
					( objectStatus "CT45.2" )
				)
			)
			( gate "@baseboard_fab2_lib.baseboard_fab2(sch_1):page216_i126"
				( attribute "BOM_COST" "DEBUG"
					( Origin gFrontEnd )
				)
				( attribute "CDS_LIB" "mstr_discrete"
					( Origin gPackager )
				)
				( attribute "LOCATION" "RT33"
					( Origin gFrontEnd )
				)
				( attribute "MATERIAL" "CHIP"
					( Origin gFrontEnd )
				)
				( attribute "PACK_TYPE" "0402"
					( Origin gFrontEnd )
				)
				( attribute "PART_NUMBER" "G21497-005"
					( Origin gFrontEnd )
				)
				( attribute "PHYS_PAGE" "216"
					( Origin gFrontEnd )
				)
				( attribute "ROOM" "BMC_DEBUG_HEADER"
					( Origin gFrontEnd )
				)
				( attribute "ROT" "0"
					( Origin gFrontEnd )
				)
				( attribute "TOLERANCE" "5%"
					( Origin gFrontEnd )
				)
				( attribute "VALUE" "0.0"
					( Origin gFrontEnd )
				)
				( attribute "VER" "1"
					( Origin gFrontEnd )
				)
				( attribute "WATTAGE" "1/16W"
					( Origin gFrontEnd )
				)
				( attribute "XY" "(-275,2025)"
					( Origin gFrontEnd )
				)
				( attribute "CHIPS_PART_NAME" "RES"
					( Origin gPackager )
				)
				( attribute "CDS_PART_NAME" "RES_0402-0.0,5%,1/16W,CHIP,G21A"
					( Origin gPackager )
				)
				( attribute "CDS_LOCATION" "RT33"
					( Origin gPackager )
				)
				( attribute "CDS_SEC" "1"
					( Origin gPackager )
				)
				( attribute "SEC" "1"
					( Origin gPackager )
				)
				( objectStatus "RT33" )
				( pin "a"
					( attribute "PN" "1"
						( Origin gPackager )
					)
					( objectStatus "RT33.1" )
				)
				( pin "b"
					( attribute "PN" "2"
						( Origin gPackager )
					)
					( objectStatus "RT33.2" )
				)
			)
			( gate "@baseboard_fab2_lib.baseboard_fab2(sch_1):page219_i119"
				( attribute "CDS_LIB" "mstr_discrete"
					( Origin gPackager )
				)
				( attribute "LOCATION" "CT48"
					( Origin gFrontEnd )
				)
				( attribute "MATERIAL" "X7R"
					( Origin gFrontEnd )
				)
				( attribute "PACK_TYPE" "0402LF"
					( Origin gFrontEnd )
				)
				( attribute "PART_NUMBER" "A36096-046"
					( Origin gFrontEnd )
				)
				( attribute "PHYS_PAGE" "219"
					( Origin gFrontEnd )
				)
				( attribute "ROOM" "VDDQ_KLM_PWR_VR"
					( Origin gFrontEnd )
				)
				( attribute "ROT" "0"
					( Origin gFrontEnd )
				)
				( attribute "TOLERANCE" "10%"
					( Origin gFrontEnd )
				)
				( attribute "VALUE" "1000PF"
					( Origin gFrontEnd )
				)
				( attribute "VER" "1"
					( Origin gFrontEnd )
				)
				( attribute "VOLTAGE" "50V"
					( Units "uVoltage" "V" 1.000000)
					( Origin gFrontEnd )
				)
				( attribute "XY" "(2600,-25)"
					( Origin gFrontEnd )
				)
				( attribute "CHIPS_PART_NAME" "CAP"
					( Origin gPackager )
				)
				( attribute "CDS_PART_NAME" "CAP_0402LF-1000PF,50V,10%,X7R,A"
					( Origin gPackager )
				)
				( attribute "CDS_LOCATION" "CT48"
					( Origin gPackager )
				)
				( attribute "CDS_SEC" "1"
					( Origin gPackager )
				)
				( attribute "SEC" "1"
					( Origin gPackager )
				)
				( attribute "STATUS" "NOPOP"
					( Origin gFrontEnd )
				)
				( objectStatus "CT48" )
				( pin "a"
					( attribute "PN" "1"
						( Origin gPackager )
					)
					( objectStatus "CT48.1" )
				)
				( pin "b"
					( attribute "PN" "2"
						( Origin gPackager )
					)
					( objectStatus "CT48.2" )
				)
			)
			( gate "@baseboard_fab2_lib.baseboard_fab2(sch_1):page219_i121"
				( attribute "CDS_LIB" "w_hdl"
					( Origin gPackager )
				)
				( attribute "CDS_LMAN_SYM_OUTLINE" "-50,25,50,-25"
					( Origin gPackager )
				)
				( attribute "LOCATION" "CT47"
					( Origin gFrontEnd )
				)
				( attribute "PACK_TYPE" "SMD-BCG6"
					( Origin gFrontEnd )
				)
				( attribute "PART_NUMBER" "78.22224.2BL"
					( Origin gFrontEnd )
				)
				( attribute "PHYS_PAGE" "219"
					( Origin gFrontEnd )
				)
				( attribute "ROT" "0"
					( Origin gFrontEnd )
				)
				( attribute "VALUE" "SC2K2P50V3KX-GP"
					( Origin gFrontEnd )
				)
				( attribute "VER" "1"
					( Origin gFrontEnd )
				)
				( attribute "XY" "(2675,-525)"
					( Origin gFrontEnd )
				)
				( attribute "CHIPS_PART_NAME" "SC2K2P50V3KX-GP"
					( Origin gPackager )
				)
				( attribute "CDS_PART_NAME" "SC2K2P50V3KX-GP_SMD-BCG6-SC2K2A"
					( Origin gPackager )
				)
				( attribute "CDS_LOCATION" "CT47"
					( Origin gPackager )
				)
				( attribute "CDS_SEC" "1"
					( Origin gPackager )
				)
				( attribute "SEC" "1"
					( Origin gPackager )
				)
				( attribute "STATUS" "NOPOP"
					( Origin gFrontEnd )
				)
				( objectStatus "CT47" )
				( pin "\1\"
					( attribute "PN" "1"
						( Origin gPackager )
					)
					( objectStatus "CT47.1" )
				)
				( pin "\2\"
					( attribute "PN" "2"
						( Origin gPackager )
					)
					( objectStatus "CT47.2" )
				)
			)
			( gate "@baseboard_fab2_lib.baseboard_fab2(sch_1):page219_i123"
				( attribute "CDS_LIB" "w_hdl"
					( Origin gPackager )
				)
				( attribute "CDS_LMAN_SYM_OUTLINE" "-50,75,50,-75"
					( Origin gPackager )
				)
				( attribute "CDS_LOCATION" "RT32"
					( Origin gPackager )
				)
				( attribute "CDS_SEC" "1"
					( Origin gPackager )
				)
				( attribute "LOCATION" "RT32"
					( Origin gFrontEnd )
				)
				( attribute "PACK_TYPE" "SMD-RG5"
					( Origin gFrontEnd )
				)
				( attribute "PART_NUMBER" "64.3R015.16L"
					( Origin gFrontEnd )
				)
				( attribute "PHYS_PAGE" "219"
					( Origin gFrontEnd )
				)
				( attribute "ROT" "4"
					( Origin gFrontEnd )
				)
				( attribute "VALUE" "3D01R5F-GP"
					( Origin gFrontEnd )
				)
				( attribute "VER" "1"
					( Origin gFrontEnd )
				)
				( attribute "XY" "(2675,-850)"
					( Origin gFrontEnd )
				)
				( attribute "CHIPS_PART_NAME" "3D01R5F-GP"
					( Origin gPackager )
				)
				( attribute "CDS_PART_NAME" "3D01R5F-GP_SMD-RG5-3D01R5F-GP,A"
					( Origin gPackager )
				)
				( attribute "SEC" "1"
					( Origin gPackager )
				)
				( attribute "STATUS" "NOPOP"
					( Origin gFrontEnd )
				)
				( objectStatus "RT32" )
				( pin "\1\"
					( attribute "PN" "1"
						( Origin gPackager )
					)
					( objectStatus "RT32.1" )
				)
				( pin "\2\"
					( attribute "PN" "2"
						( Origin gPackager )
					)
					( objectStatus "RT32.2" )
				)
			)
			( gate "@baseboard_fab2_lib.baseboard_fab2(sch_1):page219_i124"
				( attribute "CDS_LIB" "mstr_discrete"
					( Origin gPackager )
				)
				( attribute "LOCATION" "CT43"
					( Origin gFrontEnd )
				)
				( attribute "MATERIAL" "X7R"
					( Origin gFrontEnd )
				)
				( attribute "PACK_TYPE" "0402LF"
					( Origin gFrontEnd )
				)
				( attribute "PART_NUMBER" "A36096-046"
					( Origin gFrontEnd )
				)
				( attribute "PHYS_PAGE" "219"
					( Origin gFrontEnd )
				)
				( attribute "ROOM" "VDDQ_KLM_PWR_VR"
					( Origin gFrontEnd )
				)
				( attribute "ROT" "0"
					( Origin gFrontEnd )
				)
				( attribute "TOLERANCE" "10%"
					( Origin gFrontEnd )
				)
				( attribute "VALUE" "1000PF"
					( Origin gFrontEnd )
				)
				( attribute "VER" "1"
					( Origin gFrontEnd )
				)
				( attribute "VOLTAGE" "50V"
					( Units "uVoltage" "V" 1.000000)
					( Origin gFrontEnd )
				)
				( attribute "XY" "(2700,2075)"
					( Origin gFrontEnd )
				)
				( attribute "CHIPS_PART_NAME" "CAP"
					( Origin gPackager )
				)
				( attribute "CDS_PART_NAME" "CAP_0402LF-1000PF,50V,10%,X7R,A"
					( Origin gPackager )
				)
				( attribute "CDS_LOCATION" "CT43"
					( Origin gPackager )
				)
				( attribute "CDS_SEC" "1"
					( Origin gPackager )
				)
				( attribute "SEC" "1"
					( Origin gPackager )
				)
				( attribute "STATUS" "NOPOP"
					( Origin gFrontEnd )
				)
				( objectStatus "CT43" )
				( pin "a"
					( attribute "PN" "1"
						( Origin gPackager )
					)
					( objectStatus "CT43.1" )
				)
				( pin "b"
					( attribute "PN" "2"
						( Origin gPackager )
					)
					( objectStatus "CT43.2" )
				)
			)
			( gate "@baseboard_fab2_lib.baseboard_fab2(sch_1):page219_i126"
				( attribute "CDS_LIB" "w_hdl"
					( Origin gPackager )
				)
				( attribute "CDS_LMAN_SYM_OUTLINE" "-50,75,50,-75"
					( Origin gPackager )
				)
				( attribute "CDS_LOCATION" "RT29"
					( Origin gPackager )
				)
				( attribute "CDS_SEC" "1"
					( Origin gPackager )
				)
				( attribute "LOCATION" "RT29"
					( Origin gFrontEnd )
				)
				( attribute "PACK_TYPE" "SMD-RG5"
					( Origin gFrontEnd )
				)
				( attribute "PART_NUMBER" "64.3R015.16L"
					( Origin gFrontEnd )
				)
				( attribute "PHYS_PAGE" "219"
					( Origin gFrontEnd )
				)
				( attribute "ROT" "4"
					( Origin gFrontEnd )
				)
				( attribute "VALUE" "3D01R5F-GP"
					( Origin gFrontEnd )
				)
				( attribute "VER" "1"
					( Origin gFrontEnd )
				)
				( attribute "XY" "(2800,1325)"
					( Origin gFrontEnd )
				)
				( attribute "CHIPS_PART_NAME" "3D01R5F-GP"
					( Origin gPackager )
				)
				( attribute "CDS_PART_NAME" "3D01R5F-GP_SMD-RG5-3D01R5F-GP,A"
					( Origin gPackager )
				)
				( attribute "SEC" "1"
					( Origin gPackager )
				)
				( attribute "STATUS" "NOPOP"
					( Origin gFrontEnd )
				)
				( objectStatus "RT29" )
				( pin "\1\"
					( attribute "PN" "1"
						( Origin gPackager )
					)
					( objectStatus "RT29.1" )
				)
				( pin "\2\"
					( attribute "PN" "2"
						( Origin gPackager )
					)
					( objectStatus "RT29.2" )
				)
			)
			( gate "@baseboard_fab2_lib.baseboard_fab2(sch_1):page219_i127"
				( attribute "CDS_LIB" "w_hdl"
					( Origin gPackager )
				)
				( attribute "CDS_LMAN_SYM_OUTLINE" "-50,25,50,-25"
					( Origin gPackager )
				)
				( attribute "LOCATION" "CT44"
					( Origin gFrontEnd )
				)
				( attribute "PACK_TYPE" "SMD-BCG6"
					( Origin gFrontEnd )
				)
				( attribute "PART_NUMBER" "78.22224.2BL"
					( Origin gFrontEnd )
				)
				( attribute "PHYS_PAGE" "219"
					( Origin gFrontEnd )
				)
				( attribute "ROT" "0"
					( Origin gFrontEnd )
				)
				( attribute "VALUE" "SC2K2P50V3KX-GP"
					( Origin gFrontEnd )
				)
				( attribute "VER" "1"
					( Origin gFrontEnd )
				)
				( attribute "XY" "(2800,1625)"
					( Origin gFrontEnd )
				)
				( attribute "CHIPS_PART_NAME" "SC2K2P50V3KX-GP"
					( Origin gPackager )
				)
				( attribute "CDS_PART_NAME" "SC2K2P50V3KX-GP_SMD-BCG6-SC2K2A"
					( Origin gPackager )
				)
				( attribute "CDS_LOCATION" "CT44"
					( Origin gPackager )
				)
				( attribute "CDS_SEC" "1"
					( Origin gPackager )
				)
				( attribute "SEC" "1"
					( Origin gPackager )
				)
				( attribute "STATUS" "NOPOP"
					( Origin gFrontEnd )
				)
				( objectStatus "CT44" )
				( pin "\1\"
					( attribute "PN" "1"
						( Origin gPackager )
					)
					( objectStatus "CT44.1" )
				)
				( pin "\2\"
					( attribute "PN" "2"
						( Origin gPackager )
					)
					( objectStatus "CT44.2" )
				)
			)
			( gate "@baseboard_fab2_lib.baseboard_fab2(sch_1):page216_i108"
				( attribute "CDS_LIB" "dev_discrete"
					( Origin gPackager )
				)
				( attribute "LOCATION" "CT51"
					( Origin gFrontEnd )
				)
				( attribute "MATERIAL" "X7R"
					( Origin gFrontEnd )
				)
				( attribute "PACK_TYPE" "0402V"
					( Origin gFrontEnd )
				)
				( attribute "PART_NUMBER" "A36096-030"
					( Origin gFrontEnd )
				)
				( attribute "PHYS_PAGE" "216"
					( Origin gFrontEnd )
				)
				( attribute "ROOM" "PVCCIN_CPU0_PWR_VR"
					( Origin gFrontEnd )
				)
				( attribute "ROT" "0"
					( Origin gFrontEnd )
				)
				( attribute "TOLERANCE" "10%"
					( Origin gFrontEnd )
				)
				( attribute "VALUE" "0.1UF"
					( Origin gFrontEnd )
				)
				( attribute "VER" "1"
					( Origin gFrontEnd )
				)
				( attribute "VOLTAGE" "16V"
					( Units "uVoltage" "V" 1.000000)
					( Origin gFrontEnd )
				)
				( attribute "XY" "(675,1750)"
					( Origin gFrontEnd )
				)
				( attribute "CHIPS_PART_NAME" "CAP_A"
					( Origin gPackager )
				)
				( attribute "CDS_PART_NAME" "CAP_A_0402V-0.1UF,16V,10%,X7R,A"
					( Origin gPackager )
				)
				( attribute "CDS_LOCATION" "CT51"
					( Origin gPackager )
				)
				( attribute "CDS_SEC" "1"
					( Origin gPackager )
				)
				( attribute "SEC" "1"
					( Origin gPackager )
				)
				( attribute "STATUS" "NOPOP"
					( Origin gFrontEnd )
				)
				( objectStatus "CT51" )
				( pin "a"
					( attribute "PN" "1"
						( Origin gPackager )
					)
					( objectStatus "CT51.1" )
				)
				( pin "b"
					( attribute "PN" "2"
						( Origin gPackager )
					)
					( objectStatus "CT51.2" )
				)
			)
			( gate "@baseboard_fab2_lib.baseboard_fab2(sch_1):page216_i128"
				( attribute "CDS_LIB" "mstr_discrete"
					( Origin gPackager )
				)
				( attribute "CDS_LOCATION" "C7G38"
					( Origin gPackager )
				)
				( attribute "CDS_SEC" "1"
					( Origin gPackager )
				)
				( attribute "LOCATION" "C7G38"
					( Origin gFrontEnd )
				)
				( attribute "MATERIAL" "X7R"
					( Origin gFrontEnd )
				)
				( attribute "PACK_TYPE" "0402"
					( Origin gFrontEnd )
				)
				( attribute "PART_NUMBER" "A36096-104"
					( Origin gFrontEnd )
				)
				( attribute "PHYS_PAGE" "216"
					( Origin gFrontEnd )
				)
				( attribute "ROOM" "VDDQ_ABC_PWR_VR"
					( Origin gFrontEnd )
				)
				( attribute "ROT" "2"
					( Origin gFrontEnd )
				)
				( attribute "SEC" "1"
					( Origin gFrontEnd )
				)
				( attribute "SEC_TYPE" "0402"
					( Origin gFrontEnd )
				)
				( attribute "SPOF" "TRUE"
					( Origin gFrontEnd )
				)
				( attribute "TOLERANCE" "10%"
					( Origin gFrontEnd )
				)
				( attribute "VALUE" "0.220UF"
					( Origin gFrontEnd )
				)
				( attribute "VER" "1"
					( Origin gFrontEnd )
				)
				( attribute "VOLTAGE" "16V"
					( Units "uVoltage" "V" 1.000000)
					( Origin gFrontEnd )
				)
				( attribute "XY" "(-1150,-475)"
					( Origin gFrontEnd )
				)
				( attribute "CHIPS_PART_NAME" "CAP"
					( Origin gPackager )
				)
				( attribute "CDS_PART_NAME" "CAP_0402-0.220UF,16V,10%,X7R,AA"
					( Origin gPackager )
				)
				( objectStatus "C7G38" )
				( pin "a"
					( attribute "PN" "1"
						( Origin gPackager )
					)
					( objectStatus "C7G38.1" )
				)
				( pin "b"
					( attribute "PN" "2"
						( Origin gPackager )
					)
					( objectStatus "C7G38.2" )
				)
			)
			( gate "@baseboard_fab2_lib.baseboard_fab2(sch_1):page216_i111"
				( attribute "CDS_LIB" "dev_discrete"
					( Origin gPackager )
				)
				( attribute "LOCATION" "CT52"
					( Origin gFrontEnd )
				)
				( attribute "MATERIAL" "X7R"
					( Origin gFrontEnd )
				)
				( attribute "PACK_TYPE" "0402V"
					( Origin gFrontEnd )
				)
				( attribute "PART_NUMBER" "A36096-030"
					( Origin gFrontEnd )
				)
				( attribute "PHYS_PAGE" "216"
					( Origin gFrontEnd )
				)
				( attribute "ROOM" "PVCCIN_CPU0_PWR_VR"
					( Origin gFrontEnd )
				)
				( attribute "ROT" "0"
					( Origin gFrontEnd )
				)
				( attribute "TOLERANCE" "10%"
					( Origin gFrontEnd )
				)
				( attribute "VALUE" "0.1UF"
					( Origin gFrontEnd )
				)
				( attribute "VER" "1"
					( Origin gFrontEnd )
				)
				( attribute "VOLTAGE" "16V"
					( Units "uVoltage" "V" 1.000000)
					( Origin gFrontEnd )
				)
				( attribute "XY" "(775,-625)"
					( Origin gFrontEnd )
				)
				( attribute "CHIPS_PART_NAME" "CAP_A"
					( Origin gPackager )
				)
				( attribute "CDS_PART_NAME" "CAP_A_0402V-0.1UF,16V,10%,X7R,A"
					( Origin gPackager )
				)
				( attribute "CDS_LOCATION" "CT52"
					( Origin gPackager )
				)
				( attribute "CDS_SEC" "1"
					( Origin gPackager )
				)
				( attribute "SEC" "1"
					( Origin gPackager )
				)
				( attribute "STATUS" "NOPOP"
					( Origin gFrontEnd )
				)
				( objectStatus "CT52" )
				( pin "a"
					( attribute "PN" "1"
						( Origin gPackager )
					)
					( objectStatus "CT52.1" )
				)
				( pin "b"
					( attribute "PN" "2"
						( Origin gPackager )
					)
					( objectStatus "CT52.2" )
				)
			)
			( gate "@baseboard_fab2_lib.baseboard_fab2(sch_1):page210_i62"
				( attribute "BOM_COST" "DEBUG"
					( Origin gFrontEnd )
				)
				( attribute "CDS_LIB" "mstr_discrete"
					( Origin gPackager )
				)
				( attribute "LOCATION" "RT37"
					( Origin gFrontEnd )
				)
				( attribute "MATERIAL" "CHIP"
					( Origin gFrontEnd )
				)
				( attribute "PACK_TYPE" "0402"
					( Origin gFrontEnd )
				)
				( attribute "PART_NUMBER" "G21497-005"
					( Origin gFrontEnd )
				)
				( attribute "PHYS_PAGE" "210"
					( Origin gFrontEnd )
				)
				( attribute "ROOM" "BMC_DEBUG_HEADER"
					( Origin gFrontEnd )
				)
				( attribute "ROT" "0"
					( Origin gFrontEnd )
				)
				( attribute "TOLERANCE" "5%"
					( Origin gFrontEnd )
				)
				( attribute "VALUE" "0.0"
					( Origin gFrontEnd )
				)
				( attribute "VER" "1"
					( Origin gFrontEnd )
				)
				( attribute "WATTAGE" "1/16W"
					( Origin gFrontEnd )
				)
				( attribute "XY" "(-5425,3375)"
					( Origin gFrontEnd )
				)
				( attribute "CHIPS_PART_NAME" "RES"
					( Origin gPackager )
				)
				( attribute "CDS_PART_NAME" "RES_0402-0.0,5%,1/16W,CHIP,G21A"
					( Origin gPackager )
				)
				( attribute "CDS_LOCATION" "RT37"
					( Origin gPackager )
				)
				( attribute "CDS_SEC" "1"
					( Origin gPackager )
				)
				( attribute "SEC" "1"
					( Origin gPackager )
				)
				( objectStatus "RT37" )
				( pin "a"
					( attribute "PN" "1"
						( Origin gPackager )
					)
					( objectStatus "RT37.1" )
				)
				( pin "b"
					( attribute "PN" "2"
						( Origin gPackager )
					)
					( objectStatus "RT37.2" )
				)
			)
			( gate "@baseboard_fab2_lib.baseboard_fab2(sch_1):page216_i114"
				( attribute "CDS_LIB" "w_hdl"
					( Origin gPackager )
				)
				( attribute "CDS_LMAN_SYM_OUTLINE" "-50,75,50,-75"
					( Origin gPackager )
				)
				( attribute "CDS_LOCATION" "RT34"
					( Origin gPackager )
				)
				( attribute "CDS_SEC" "1"
					( Origin gPackager )
				)
				( attribute "LOCATION" "RT34"
					( Origin gFrontEnd )
				)
				( attribute "PACK_TYPE" "SMD-RG5"
					( Origin gFrontEnd )
				)
				( attribute "PART_NUMBER" "64.3R015.16L"
					( Origin gFrontEnd )
				)
				( attribute "PHYS_PAGE" "216"
					( Origin gFrontEnd )
				)
				( attribute "ROT" "4"
					( Origin gFrontEnd )
				)
				( attribute "VALUE" "3D01R5F-GP"
					( Origin gFrontEnd )
				)
				( attribute "VER" "1"
					( Origin gFrontEnd )
				)
				( attribute "XY" "(2750,1475)"
					( Origin gFrontEnd )
				)
				( attribute "CHIPS_PART_NAME" "3D01R5F-GP"
					( Origin gPackager )
				)
				( attribute "CDS_PART_NAME" "3D01R5F-GP_SMD-RG5-3D01R5F-GP,A"
					( Origin gPackager )
				)
				( attribute "SEC" "1"
					( Origin gPackager )
				)
				( attribute "STATUS" "NOPOP"
					( Origin gFrontEnd )
				)
				( objectStatus "RT34" )
				( pin "\1\"
					( attribute "PN" "1"
						( Origin gPackager )
					)
					( objectStatus "RT34.1" )
				)
				( pin "\2\"
					( attribute "PN" "2"
						( Origin gPackager )
					)
					( objectStatus "RT34.2" )
				)
			)
			( gate "@baseboard_fab2_lib.baseboard_fab2(sch_1):page216_i118"
				( attribute "CDS_LIB" "mstr_discrete"
					( Origin gPackager )
				)
				( attribute "LOCATION" "CT49"
					( Origin gFrontEnd )
				)
				( attribute "MATERIAL" "X7R"
					( Origin gFrontEnd )
				)
				( attribute "PACK_TYPE" "0402LF"
					( Origin gFrontEnd )
				)
				( attribute "PART_NUMBER" "A36096-046"
					( Origin gFrontEnd )
				)
				( attribute "PHYS_PAGE" "216"
					( Origin gFrontEnd )
				)
				( attribute "ROOM" "VDDQ_KLM_PWR_VR"
					( Origin gFrontEnd )
				)
				( attribute "ROT" "0"
					( Origin gFrontEnd )
				)
				( attribute "TOLERANCE" "10%"
					( Origin gFrontEnd )
				)
				( attribute "VALUE" "1000PF"
					( Origin gFrontEnd )
				)
				( attribute "VER" "1"
					( Origin gFrontEnd )
				)
				( attribute "VOLTAGE" "50V"
					( Units "uVoltage" "V" 1.000000)
					( Origin gFrontEnd )
				)
				( attribute "XY" "(2650,2325)"
					( Origin gFrontEnd )
				)
				( attribute "CHIPS_PART_NAME" "CAP"
					( Origin gPackager )
				)
				( attribute "CDS_PART_NAME" "CAP_0402LF-1000PF,50V,10%,X7R,A"
					( Origin gPackager )
				)
				( attribute "CDS_LOCATION" "CT49"
					( Origin gPackager )
				)
				( attribute "CDS_SEC" "1"
					( Origin gPackager )
				)
				( attribute "SEC" "1"
					( Origin gPackager )
				)
				( attribute "STATUS" "NOPOP"
					( Origin gFrontEnd )
				)
				( objectStatus "CT49" )
				( pin "a"
					( attribute "PN" "1"
						( Origin gPackager )
					)
					( objectStatus "CT49.1" )
				)
				( pin "b"
					( attribute "PN" "2"
						( Origin gPackager )
					)
					( objectStatus "CT49.2" )
				)
			)
			( gate "@baseboard_fab2_lib.baseboard_fab2(sch_1):page216_i119"
				( attribute "CDS_LIB" "w_hdl"
					( Origin gPackager )
				)
				( attribute "CDS_LMAN_SYM_OUTLINE" "-50,25,50,-25"
					( Origin gPackager )
				)
				( attribute "LOCATION" "CT53"
					( Origin gFrontEnd )
				)
				( attribute "PACK_TYPE" "SMD-BCG6"
					( Origin gFrontEnd )
				)
				( attribute "PART_NUMBER" "78.22224.2BL"
					( Origin gFrontEnd )
				)
				( attribute "PHYS_PAGE" "216"
					( Origin gFrontEnd )
				)
				( attribute "ROT" "0"
					( Origin gFrontEnd )
				)
				( attribute "VALUE" "SC2K2P50V3KX-GP"
					( Origin gFrontEnd )
				)
				( attribute "VER" "1"
					( Origin gFrontEnd )
				)
				( attribute "XY" "(2700,-600)"
					( Origin gFrontEnd )
				)
				( attribute "CHIPS_PART_NAME" "SC2K2P50V3KX-GP"
					( Origin gPackager )
				)
				( attribute "CDS_PART_NAME" "SC2K2P50V3KX-GP_SMD-BCG6-SC2K2A"
					( Origin gPackager )
				)
				( attribute "CDS_LOCATION" "CT53"
					( Origin gPackager )
				)
				( attribute "CDS_SEC" "1"
					( Origin gPackager )
				)
				( attribute "SEC" "1"
					( Origin gPackager )
				)
				( attribute "STATUS" "NOPOP"
					( Origin gFrontEnd )
				)
				( objectStatus "CT53" )
				( pin "\1\"
					( attribute "PN" "1"
						( Origin gPackager )
					)
					( objectStatus "CT53.1" )
				)
				( pin "\2\"
					( attribute "PN" "2"
						( Origin gPackager )
					)
					( objectStatus "CT53.2" )
				)
			)
			( gate "@baseboard_fab2_lib.baseboard_fab2(sch_1):page216_i121"
				( attribute "CDS_LIB" "mstr_discrete"
					( Origin gPackager )
				)
				( attribute "LOCATION" "CT54"
					( Origin gFrontEnd )
				)
				( attribute "MATERIAL" "X7R"
					( Origin gFrontEnd )
				)
				( attribute "PACK_TYPE" "0402LF"
					( Origin gFrontEnd )
				)
				( attribute "PART_NUMBER" "A36096-046"
					( Origin gFrontEnd )
				)
				( attribute "PHYS_PAGE" "216"
					( Origin gFrontEnd )
				)
				( attribute "ROOM" "VDDQ_KLM_PWR_VR"
					( Origin gFrontEnd )
				)
				( attribute "ROT" "0"
					( Origin gFrontEnd )
				)
				( attribute "TOLERANCE" "10%"
					( Origin gFrontEnd )
				)
				( attribute "VALUE" "1000PF"
					( Origin gFrontEnd )
				)
				( attribute "VER" "1"
					( Origin gFrontEnd )
				)
				( attribute "VOLTAGE" "50V"
					( Units "uVoltage" "V" 1.000000)
					( Origin gFrontEnd )
				)
				( attribute "XY" "(2550,-125)"
					( Origin gFrontEnd )
				)
				( attribute "CHIPS_PART_NAME" "CAP"
					( Origin gPackager )
				)
				( attribute "CDS_PART_NAME" "CAP_0402LF-1000PF,50V,10%,X7R,A"
					( Origin gPackager )
				)
				( attribute "CDS_LOCATION" "CT54"
					( Origin gPackager )
				)
				( attribute "CDS_SEC" "1"
					( Origin gPackager )
				)
				( attribute "SEC" "1"
					( Origin gPackager )
				)
				( attribute "STATUS" "NOPOP"
					( Origin gFrontEnd )
				)
				( objectStatus "CT54" )
				( pin "a"
					( attribute "PN" "1"
						( Origin gPackager )
					)
					( objectStatus "CT54.1" )
				)
				( pin "b"
					( attribute "PN" "2"
						( Origin gPackager )
					)
					( objectStatus "CT54.2" )
				)
			)
			( gate "@baseboard_fab2_lib.baseboard_fab2(sch_1):page216_i123"
				( attribute "CDS_LIB" "w_hdl"
					( Origin gPackager )
				)
				( attribute "CDS_LMAN_SYM_OUTLINE" "-50,75,50,-75"
					( Origin gPackager )
				)
				( attribute "CDS_LOCATION" "RT35"
					( Origin gPackager )
				)
				( attribute "CDS_SEC" "1"
					( Origin gPackager )
				)
				( attribute "LOCATION" "RT35"
					( Origin gFrontEnd )
				)
				( attribute "PACK_TYPE" "SMD-RG5"
					( Origin gFrontEnd )
				)
				( attribute "PART_NUMBER" "64.3R015.16L"
					( Origin gFrontEnd )
				)
				( attribute "PHYS_PAGE" "216"
					( Origin gFrontEnd )
				)
				( attribute "ROT" "4"
					( Origin gFrontEnd )
				)
				( attribute "VALUE" "3D01R5F-GP"
					( Origin gFrontEnd )
				)
				( attribute "VER" "1"
					( Origin gFrontEnd )
				)
				( attribute "XY" "(2700,-900)"
					( Origin gFrontEnd )
				)
				( attribute "CHIPS_PART_NAME" "3D01R5F-GP"
					( Origin gPackager )
				)
				( attribute "CDS_PART_NAME" "3D01R5F-GP_SMD-RG5-3D01R5F-GP,A"
					( Origin gPackager )
				)
				( attribute "SEC" "1"
					( Origin gPackager )
				)
				( attribute "STATUS" "NOPOP"
					( Origin gFrontEnd )
				)
				( objectStatus "RT35" )
				( pin "\1\"
					( attribute "PN" "1"
						( Origin gPackager )
					)
					( objectStatus "RT35.1" )
				)
				( pin "\2\"
					( attribute "PN" "2"
						( Origin gPackager )
					)
					( objectStatus "RT35.2" )
				)
			)
			( gate "@baseboard_fab2_lib.baseboard_fab2(sch_1):page216_i124"
				( attribute "CDS_LIB" "w_hdl"
					( Origin gPackager )
				)
				( attribute "CDS_LMAN_SYM_OUTLINE" "-50,25,50,-25"
					( Origin gPackager )
				)
				( attribute "LOCATION" "CT50"
					( Origin gFrontEnd )
				)
				( attribute "PACK_TYPE" "SMD-BCG6"
					( Origin gFrontEnd )
				)
				( attribute "PART_NUMBER" "78.22224.2BL"
					( Origin gFrontEnd )
				)
				( attribute "PHYS_PAGE" "216"
					( Origin gFrontEnd )
				)
				( attribute "ROT" "0"
					( Origin gFrontEnd )
				)
				( attribute "VALUE" "SC2K2P50V3KX-GP"
					( Origin gFrontEnd )
				)
				( attribute "VER" "1"
					( Origin gFrontEnd )
				)
				( attribute "XY" "(2750,1800)"
					( Origin gFrontEnd )
				)
				( attribute "CHIPS_PART_NAME" "SC2K2P50V3KX-GP"
					( Origin gPackager )
				)
				( attribute "CDS_PART_NAME" "SC2K2P50V3KX-GP_SMD-BCG6-SC2K2A"
					( Origin gPackager )
				)
				( attribute "CDS_LOCATION" "CT50"
					( Origin gPackager )
				)
				( attribute "CDS_SEC" "1"
					( Origin gPackager )
				)
				( attribute "SEC" "1"
					( Origin gPackager )
				)
				( attribute "STATUS" "NOPOP"
					( Origin gFrontEnd )
				)
				( objectStatus "CT50" )
				( pin "\1\"
					( attribute "PN" "1"
						( Origin gPackager )
					)
					( objectStatus "CT50.1" )
				)
				( pin "\2\"
					( attribute "PN" "2"
						( Origin gPackager )
					)
					( objectStatus "CT50.2" )
				)
			)
			( gate "@baseboard_fab2_lib.baseboard_fab2(sch_1):page216_i125"
				( attribute "CDS_LIB" "mstr_discrete"
					( Origin gPackager )
				)
				( attribute "CDS_LOCATION" "L7G1"
					( Origin gPackager )
				)
				( attribute "CDS_SEC" "1"
					( Origin gPackager )
				)
				( attribute "LOCATION" "L7G1"
					( Origin gFrontEnd )
				)
				( attribute "MATERIAL" "IND"
					( Origin gFrontEnd )
				)
				( attribute "PACK_TYPE" "SM"
					( Origin gFrontEnd )
				)
				( attribute "PART_NUMBER" "D92183-034"
					( Origin gFrontEnd )
				)
				( attribute "PHYS_PAGE" "216"
					( Origin gFrontEnd )
				)
				( attribute "ROOM" "VDDQ_ABC_PWR_VR"
					( Origin gFrontEnd )
				)
				( attribute "ROT" "0"
					( Origin gFrontEnd )
				)
				( attribute "SEC" "1"
					( Origin gFrontEnd )
				)
				( attribute "SEC_TYPE" "SM"
					( Origin gFrontEnd )
				)
				( attribute "VALUE" "0.12UH"
					( Origin gFrontEnd )
				)
				( attribute "VER" "1"
					( Origin gFrontEnd )
				)
				( attribute "XY" "(3175,1950)"
					( Origin gFrontEnd )
				)
				( attribute "CHIPS_PART_NAME" "INDUCTOR"
					( Origin gPackager )
				)
				( attribute "CDS_PART_NAME" "INDUCTOR_SM-0.12UH,IND,D92183-A"
					( Origin gPackager )
				)
				( objectStatus "L7G1" )
				( pin "ina"
					( attribute "PN" "1"
						( Origin gPackager )
					)
					( objectStatus "L7G1.1" )
				)
				( pin "inb"
					( attribute "PN" "2"
						( Origin gPackager )
					)
					( objectStatus "L7G1.2" )
				)
			)
			( gate "@baseboard_fab2_lib.baseboard_fab2(sch_1):page205_i72"
				( attribute "BOM_COST" "DEBUG"
					( Origin gFrontEnd )
				)
				( attribute "CDS_LIB" "mstr_discrete"
					( Origin gPackager )
				)
				( attribute "LOCATION" "RT40"
					( Origin gFrontEnd )
				)
				( attribute "MATERIAL" "CHIP"
					( Origin gFrontEnd )
				)
				( attribute "PACK_TYPE" "0402"
					( Origin gFrontEnd )
				)
				( attribute "PART_NUMBER" "G21497-005"
					( Origin gFrontEnd )
				)
				( attribute "PHYS_PAGE" "205"
					( Origin gFrontEnd )
				)
				( attribute "ROOM" "BMC_DEBUG_HEADER"
					( Origin gFrontEnd )
				)
				( attribute "ROT" "0"
					( Origin gFrontEnd )
				)
				( attribute "TOLERANCE" "5%"
					( Origin gFrontEnd )
				)
				( attribute "VALUE" "0.0"
					( Origin gFrontEnd )
				)
				( attribute "VER" "1"
					( Origin gFrontEnd )
				)
				( attribute "WATTAGE" "1/16W"
					( Origin gFrontEnd )
				)
				( attribute "XY" "(-5600,3500)"
					( Origin gFrontEnd )
				)
				( attribute "CHIPS_PART_NAME" "RES"
					( Origin gPackager )
				)
				( attribute "CDS_PART_NAME" "RES_0402-0.0,5%,1/16W,CHIP,G21A"
					( Origin gPackager )
				)
				( attribute "CDS_LOCATION" "RT40"
					( Origin gPackager )
				)
				( attribute "CDS_SEC" "1"
					( Origin gPackager )
				)
				( attribute "SEC" "1"
					( Origin gPackager )
				)
				( objectStatus "RT40" )
				( pin "a"
					( attribute "PN" "1"
						( Origin gPackager )
					)
					( objectStatus "RT40.1" )
				)
				( pin "b"
					( attribute "PN" "2"
						( Origin gPackager )
					)
					( objectStatus "RT40.2" )
				)
			)
			( gate "@baseboard_fab2_lib.baseboard_fab2(sch_1):page210_i57"
				( attribute "CDS_LIB" "w_hdl"
					( Origin gPackager )
				)
				( attribute "CDS_LMAN_SYM_OUTLINE" "-50,25,50,-25"
					( Origin gPackager )
				)
				( attribute "LOCATION" "CT56"
					( Origin gFrontEnd )
				)
				( attribute "PACK_TYPE" "SMD-BCG6"
					( Origin gFrontEnd )
				)
				( attribute "PART_NUMBER" "78.22224.2BL"
					( Origin gFrontEnd )
				)
				( attribute "PHYS_PAGE" "210"
					( Origin gFrontEnd )
				)
				( attribute "ROT" "0"
					( Origin gFrontEnd )
				)
				( attribute "VALUE" "SC2K2P50V3KX-GP"
					( Origin gFrontEnd )
				)
				( attribute "VER" "1"
					( Origin gFrontEnd )
				)
				( attribute "XY" "(-2500,3125)"
					( Origin gFrontEnd )
				)
				( attribute "CHIPS_PART_NAME" "SC2K2P50V3KX-GP"
					( Origin gPackager )
				)
				( attribute "CDS_PART_NAME" "SC2K2P50V3KX-GP_SMD-BCG6-SC2K2A"
					( Origin gPackager )
				)
				( attribute "CDS_LOCATION" "CT56"
					( Origin gPackager )
				)
				( attribute "CDS_SEC" "1"
					( Origin gPackager )
				)
				( attribute "SEC" "1"
					( Origin gPackager )
				)
				( attribute "STATUS" "NOPOP"
					( Origin gFrontEnd )
				)
				( objectStatus "CT56" )
				( pin "\1\"
					( attribute "PN" "1"
						( Origin gPackager )
					)
					( objectStatus "CT56.1" )
				)
				( pin "\2\"
					( attribute "PN" "2"
						( Origin gPackager )
					)
					( objectStatus "CT56.2" )
				)
			)
			( gate "@baseboard_fab2_lib.baseboard_fab2(sch_1):page210_i59"
				( attribute "CDS_LIB" "w_hdl"
					( Origin gPackager )
				)
				( attribute "CDS_LMAN_SYM_OUTLINE" "-50,75,50,-75"
					( Origin gPackager )
				)
				( attribute "CDS_LOCATION" "RT38"
					( Origin gPackager )
				)
				( attribute "CDS_SEC" "1"
					( Origin gPackager )
				)
				( attribute "LOCATION" "RT38"
					( Origin gFrontEnd )
				)
				( attribute "PACK_TYPE" "SMD-RG5"
					( Origin gFrontEnd )
				)
				( attribute "PART_NUMBER" "64.3R015.16L"
					( Origin gFrontEnd )
				)
				( attribute "PHYS_PAGE" "210"
					( Origin gFrontEnd )
				)
				( attribute "ROT" "4"
					( Origin gFrontEnd )
				)
				( attribute "VALUE" "3D01R5F-GP"
					( Origin gFrontEnd )
				)
				( attribute "VER" "1"
					( Origin gFrontEnd )
				)
				( attribute "XY" "(-2500,2825)"
					( Origin gFrontEnd )
				)
				( attribute "CHIPS_PART_NAME" "3D01R5F-GP"
					( Origin gPackager )
				)
				( attribute "CDS_PART_NAME" "3D01R5F-GP_SMD-RG5-3D01R5F-GP,A"
					( Origin gPackager )
				)
				( attribute "SEC" "1"
					( Origin gPackager )
				)
				( attribute "STATUS" "NOPOP"
					( Origin gFrontEnd )
				)
				( objectStatus "RT38" )
				( pin "\1\"
					( attribute "PN" "1"
						( Origin gPackager )
					)
					( objectStatus "RT38.1" )
				)
				( pin "\2\"
					( attribute "PN" "2"
						( Origin gPackager )
					)
					( objectStatus "RT38.2" )
				)
			)
			( gate "@baseboard_fab2_lib.baseboard_fab2(sch_1):page210_i60"
				( attribute "CDS_LIB" "mstr_discrete"
					( Origin gPackager )
				)
				( attribute "LOCATION" "CT55"
					( Origin gFrontEnd )
				)
				( attribute "MATERIAL" "X7R"
					( Origin gFrontEnd )
				)
				( attribute "PACK_TYPE" "0402LF"
					( Origin gFrontEnd )
				)
				( attribute "PART_NUMBER" "A36096-046"
					( Origin gFrontEnd )
				)
				( attribute "PHYS_PAGE" "210"
					( Origin gFrontEnd )
				)
				( attribute "ROOM" "VDDQ_KLM_PWR_VR"
					( Origin gFrontEnd )
				)
				( attribute "ROT" "0"
					( Origin gFrontEnd )
				)
				( attribute "TOLERANCE" "10%"
					( Origin gFrontEnd )
				)
				( attribute "VALUE" "1000PF"
					( Origin gFrontEnd )
				)
				( attribute "VER" "1"
					( Origin gFrontEnd )
				)
				( attribute "VOLTAGE" "50V"
					( Units "uVoltage" "V" 1.000000)
					( Origin gFrontEnd )
				)
				( attribute "XY" "(-2650,3625)"
					( Origin gFrontEnd )
				)
				( attribute "CHIPS_PART_NAME" "CAP"
					( Origin gPackager )
				)
				( attribute "CDS_PART_NAME" "CAP_0402LF-1000PF,50V,10%,X7R,A"
					( Origin gPackager )
				)
				( attribute "STATUS" "NOPOP"
					( Origin gFrontEnd )
				)
				( attribute "CDS_LOCATION" "CT55"
					( Origin gPackager )
				)
				( attribute "CDS_SEC" "1"
					( Origin gPackager )
				)
				( attribute "SEC" "1"
					( Origin gPackager )
				)
				( objectStatus "CT55" )
				( pin "a"
					( attribute "PN" "1"
						( Origin gPackager )
					)
					( objectStatus "CT55.1" )
				)
				( pin "b"
					( attribute "PN" "2"
						( Origin gPackager )
					)
					( objectStatus "CT55.2" )
				)
			)
			( gate "@baseboard_fab2_lib.baseboard_fab2(sch_1):page205_i64"
				( attribute "CDS_LIB" "w_hdl"
					( Origin gPackager )
				)
				( attribute "CDS_LMAN_SYM_OUTLINE" "-50,25,50,-25"
					( Origin gPackager )
				)
				( attribute "LOCATION" "CT59"
					( Origin gFrontEnd )
				)
				( attribute "PACK_TYPE" "SMD-BCG6"
					( Origin gFrontEnd )
				)
				( attribute "PART_NUMBER" "78.22224.2BL"
					( Origin gFrontEnd )
				)
				( attribute "PHYS_PAGE" "205"
					( Origin gFrontEnd )
				)
				( attribute "ROT" "0"
					( Origin gFrontEnd )
				)
				( attribute "VALUE" "SC2K2P50V3KX-GP"
					( Origin gFrontEnd )
				)
				( attribute "VER" "1"
					( Origin gFrontEnd )
				)
				( attribute "XY" "(-2225,3250)"
					( Origin gFrontEnd )
				)
				( attribute "CHIPS_PART_NAME" "SC2K2P50V3KX-GP"
					( Origin gPackager )
				)
				( attribute "CDS_PART_NAME" "SC2K2P50V3KX-GP_SMD-BCG6-SC2K2A"
					( Origin gPackager )
				)
				( attribute "CDS_LOCATION" "CT59"
					( Origin gPackager )
				)
				( attribute "CDS_SEC" "1"
					( Origin gPackager )
				)
				( attribute "SEC" "1"
					( Origin gPackager )
				)
				( attribute "STATUS" "NOPOP"
					( Origin gFrontEnd )
				)
				( objectStatus "CT59" )
				( pin "\1\"
					( attribute "PN" "1"
						( Origin gPackager )
					)
					( objectStatus "CT59.1" )
				)
				( pin "\2\"
					( attribute "PN" "2"
						( Origin gPackager )
					)
					( objectStatus "CT59.2" )
				)
			)
			( gate "@baseboard_fab2_lib.baseboard_fab2(sch_1):page205_i65"
				( attribute "CDS_LIB" "mstr_discrete"
					( Origin gPackager )
				)
				( attribute "LOCATION" "CT58"
					( Origin gFrontEnd )
				)
				( attribute "MATERIAL" "X7R"
					( Origin gFrontEnd )
				)
				( attribute "PACK_TYPE" "0402LF"
					( Origin gFrontEnd )
				)
				( attribute "PART_NUMBER" "A36096-046"
					( Origin gFrontEnd )
				)
				( attribute "PHYS_PAGE" "205"
					( Origin gFrontEnd )
				)
				( attribute "ROOM" "VDDQ_KLM_PWR_VR"
					( Origin gFrontEnd )
				)
				( attribute "ROT" "0"
					( Origin gFrontEnd )
				)
				( attribute "TOLERANCE" "10%"
					( Origin gFrontEnd )
				)
				( attribute "VALUE" "1000PF"
					( Origin gFrontEnd )
				)
				( attribute "VER" "1"
					( Origin gFrontEnd )
				)
				( attribute "VOLTAGE" "50V"
					( Units "uVoltage" "V" 1.000000)
					( Origin gFrontEnd )
				)
				( attribute "XY" "(-2375,3750)"
					( Origin gFrontEnd )
				)
				( attribute "CHIPS_PART_NAME" "CAP"
					( Origin gPackager )
				)
				( attribute "CDS_PART_NAME" "CAP_0402LF-1000PF,50V,10%,X7R,A"
					( Origin gPackager )
				)
				( attribute "CDS_LOCATION" "CT58"
					( Origin gPackager )
				)
				( attribute "CDS_SEC" "1"
					( Origin gPackager )
				)
				( attribute "SEC" "1"
					( Origin gPackager )
				)
				( attribute "STATUS" "NOPOP"
					( Origin gFrontEnd )
				)
				( objectStatus "CT58" )
				( pin "a"
					( attribute "PN" "1"
						( Origin gPackager )
					)
					( objectStatus "CT58.1" )
				)
				( pin "b"
					( attribute "PN" "2"
						( Origin gPackager )
					)
					( objectStatus "CT58.2" )
				)
			)
			( gate "@baseboard_fab2_lib.baseboard_fab2(sch_1):page205_i68"
				( attribute "CDS_LIB" "w_hdl"
					( Origin gPackager )
				)
				( attribute "CDS_LMAN_SYM_OUTLINE" "-50,75,50,-75"
					( Origin gPackager )
				)
				( attribute "CDS_LOCATION" "RT39"
					( Origin gPackager )
				)
				( attribute "CDS_SEC" "1"
					( Origin gPackager )
				)
				( attribute "LOCATION" "RT39"
					( Origin gFrontEnd )
				)
				( attribute "PACK_TYPE" "SMD-RG5"
					( Origin gFrontEnd )
				)
				( attribute "PART_NUMBER" "64.3R015.16L"
					( Origin gFrontEnd )
				)
				( attribute "PHYS_PAGE" "205"
					( Origin gFrontEnd )
				)
				( attribute "ROT" "4"
					( Origin gFrontEnd )
				)
				( attribute "VALUE" "3D01R5F-GP"
					( Origin gFrontEnd )
				)
				( attribute "VER" "1"
					( Origin gFrontEnd )
				)
				( attribute "XY" "(-2225,2950)"
					( Origin gFrontEnd )
				)
				( attribute "CHIPS_PART_NAME" "3D01R5F-GP"
					( Origin gPackager )
				)
				( attribute "CDS_PART_NAME" "3D01R5F-GP_SMD-RG5-3D01R5F-GP,A"
					( Origin gPackager )
				)
				( attribute "SEC" "1"
					( Origin gPackager )
				)
				( attribute "STATUS" "NOPOP"
					( Origin gFrontEnd )
				)
				( objectStatus "RT39" )
				( pin "\1\"
					( attribute "PN" "1"
						( Origin gPackager )
					)
					( objectStatus "RT39.1" )
				)
				( pin "\2\"
					( attribute "PN" "2"
						( Origin gPackager )
					)
					( objectStatus "RT39.2" )
				)
			)
			( gate "@baseboard_fab2_lib.baseboard_fab2(sch_1):page205_i69"
				( attribute "CDS_LIB" "dev_discrete"
					( Origin gPackager )
				)
				( attribute "LOCATION" "CT60"
					( Origin gFrontEnd )
				)
				( attribute "MATERIAL" "X7R"
					( Origin gFrontEnd )
				)
				( attribute "PACK_TYPE" "0402V"
					( Origin gFrontEnd )
				)
				( attribute "PART_NUMBER" "A36096-030"
					( Origin gFrontEnd )
				)
				( attribute "PHYS_PAGE" "205"
					( Origin gFrontEnd )
				)
				( attribute "ROOM" "PVCCIN_CPU0_PWR_VR"
					( Origin gFrontEnd )
				)
				( attribute "ROT" "0"
					( Origin gFrontEnd )
				)
				( attribute "TOLERANCE" "10%"
					( Origin gFrontEnd )
				)
				( attribute "VALUE" "0.1UF"
					( Origin gFrontEnd )
				)
				( attribute "VER" "1"
					( Origin gFrontEnd )
				)
				( attribute "VOLTAGE" "16V"
					( Units "uVoltage" "V" 1.000000)
					( Origin gFrontEnd )
				)
				( attribute "XY" "(-4200,3225)"
					( Origin gFrontEnd )
				)
				( attribute "CHIPS_PART_NAME" "CAP_A"
					( Origin gPackager )
				)
				( attribute "CDS_PART_NAME" "CAP_A_0402V-0.1UF,16V,10%,X7R,A"
					( Origin gPackager )
				)
				( attribute "CDS_LOCATION" "CT60"
					( Origin gPackager )
				)
				( attribute "CDS_SEC" "1"
					( Origin gPackager )
				)
				( attribute "SEC" "1"
					( Origin gPackager )
				)
				( attribute "STATUS" "NOPOP"
					( Origin gFrontEnd )
				)
				( objectStatus "CT60" )
				( pin "a"
					( attribute "PN" "1"
						( Origin gPackager )
					)
					( objectStatus "CT60.1" )
				)
				( pin "b"
					( attribute "PN" "2"
						( Origin gPackager )
					)
					( objectStatus "CT60.2" )
				)
			)
			( gate "@baseboard_fab2_lib.baseboard_fab2(sch_1):page214_i139"
				( attribute "BOM_COST" "DEBUG"
					( Origin gFrontEnd )
				)
				( attribute "CDS_LIB" "mstr_discrete"
					( Origin gPackager )
				)
				( attribute "LOCATION" "RT41"
					( Origin gFrontEnd )
				)
				( attribute "MATERIAL" "CHIP"
					( Origin gFrontEnd )
				)
				( attribute "PACK_TYPE" "0402"
					( Origin gFrontEnd )
				)
				( attribute "PART_NUMBER" "G21497-005"
					( Origin gFrontEnd )
				)
				( attribute "PHYS_PAGE" "214"
					( Origin gFrontEnd )
				)
				( attribute "ROOM" "BMC_DEBUG_HEADER"
					( Origin gFrontEnd )
				)
				( attribute "ROT" "0"
					( Origin gFrontEnd )
				)
				( attribute "TOLERANCE" "5%"
					( Origin gFrontEnd )
				)
				( attribute "VALUE" "0.0"
					( Origin gFrontEnd )
				)
				( attribute "VER" "1"
					( Origin gFrontEnd )
				)
				( attribute "WATTAGE" "1/16W"
					( Origin gFrontEnd )
				)
				( attribute "XY" "(-950,3250)"
					( Origin gFrontEnd )
				)
				( attribute "CHIPS_PART_NAME" "RES"
					( Origin gPackager )
				)
				( attribute "CDS_PART_NAME" "RES_0402-0.0,5%,1/16W,CHIP,G21A"
					( Origin gPackager )
				)
				( attribute "CDS_LOCATION" "RT41"
					( Origin gPackager )
				)
				( attribute "CDS_SEC" "1"
					( Origin gPackager )
				)
				( attribute "SEC" "1"
					( Origin gPackager )
				)
				( objectStatus "RT41" )
				( pin "a"
					( attribute "PN" "1"
						( Origin gPackager )
					)
					( objectStatus "RT41.1" )
				)
				( pin "b"
					( attribute "PN" "2"
						( Origin gPackager )
					)
					( objectStatus "RT41.2" )
				)
			)
			( gate "@baseboard_fab2_lib.baseboard_fab2(sch_1):page214_i131"
				( attribute "CDS_LIB" "w_hdl"
					( Origin gPackager )
				)
				( attribute "CDS_LMAN_SYM_OUTLINE" "-50,25,50,-25"
					( Origin gPackager )
				)
				( attribute "LOCATION" "CT62"
					( Origin gFrontEnd )
				)
				( attribute "PACK_TYPE" "SMD-BCG6"
					( Origin gFrontEnd )
				)
				( attribute "PART_NUMBER" "78.22224.2BL"
					( Origin gFrontEnd )
				)
				( attribute "PHYS_PAGE" "214"
					( Origin gFrontEnd )
				)
				( attribute "ROT" "0"
					( Origin gFrontEnd )
				)
				( attribute "VALUE" "SC2K2P50V3KX-GP"
					( Origin gFrontEnd )
				)
				( attribute "VER" "1"
					( Origin gFrontEnd )
				)
				( attribute "XY" "(2150,3025)"
					( Origin gFrontEnd )
				)
				( attribute "CHIPS_PART_NAME" "SC2K2P50V3KX-GP"
					( Origin gPackager )
				)
				( attribute "CDS_PART_NAME" "SC2K2P50V3KX-GP_SMD-BCG6-SC2K2A"
					( Origin gPackager )
				)
				( attribute "CDS_LOCATION" "CT62"
					( Origin gPackager )
				)
				( attribute "CDS_SEC" "1"
					( Origin gPackager )
				)
				( attribute "SEC" "1"
					( Origin gPackager )
				)
				( attribute "STATUS" "NOPOP"
					( Origin gFrontEnd )
				)
				( objectStatus "CT62" )
				( pin "\1\"
					( attribute "PN" "1"
						( Origin gPackager )
					)
					( objectStatus "CT62.1" )
				)
				( pin "\2\"
					( attribute "PN" "2"
						( Origin gPackager )
					)
					( objectStatus "CT62.2" )
				)
			)
			( gate "@baseboard_fab2_lib.baseboard_fab2(sch_1):page214_i132"
				( attribute "CDS_LIB" "w_hdl"
					( Origin gPackager )
				)
				( attribute "CDS_LMAN_SYM_OUTLINE" "-50,75,50,-75"
					( Origin gPackager )
				)
				( attribute "CDS_LOCATION" "RT42"
					( Origin gPackager )
				)
				( attribute "CDS_SEC" "1"
					( Origin gPackager )
				)
				( attribute "LOCATION" "RT42"
					( Origin gFrontEnd )
				)
				( attribute "PACK_TYPE" "SMD-RG5"
					( Origin gFrontEnd )
				)
				( attribute "PART_NUMBER" "64.3R015.16L"
					( Origin gFrontEnd )
				)
				( attribute "PHYS_PAGE" "214"
					( Origin gFrontEnd )
				)
				( attribute "ROT" "4"
					( Origin gFrontEnd )
				)
				( attribute "VALUE" "3D01R5F-GP"
					( Origin gFrontEnd )
				)
				( attribute "VER" "1"
					( Origin gFrontEnd )
				)
				( attribute "XY" "(2150,2725)"
					( Origin gFrontEnd )
				)
				( attribute "CHIPS_PART_NAME" "3D01R5F-GP"
					( Origin gPackager )
				)
				( attribute "CDS_PART_NAME" "3D01R5F-GP_SMD-RG5-3D01R5F-GP,A"
					( Origin gPackager )
				)
				( attribute "SEC" "1"
					( Origin gPackager )
				)
				( attribute "STATUS" "NOPOP"
					( Origin gFrontEnd )
				)
				( objectStatus "RT42" )
				( pin "\1\"
					( attribute "PN" "1"
						( Origin gPackager )
					)
					( objectStatus "RT42.1" )
				)
				( pin "\2\"
					( attribute "PN" "2"
						( Origin gPackager )
					)
					( objectStatus "RT42.2" )
				)
			)
			( gate "@baseboard_fab2_lib.baseboard_fab2(sch_1):page214_i134"
				( attribute "CDS_LIB" "mstr_discrete"
					( Origin gPackager )
				)
				( attribute "LOCATION" "CT61"
					( Origin gFrontEnd )
				)
				( attribute "MATERIAL" "X7R"
					( Origin gFrontEnd )
				)
				( attribute "PACK_TYPE" "0402LF"
					( Origin gFrontEnd )
				)
				( attribute "PART_NUMBER" "A36096-046"
					( Origin gFrontEnd )
				)
				( attribute "PHYS_PAGE" "214"
					( Origin gFrontEnd )
				)
				( attribute "ROOM" "VDDQ_KLM_PWR_VR"
					( Origin gFrontEnd )
				)
				( attribute "ROT" "0"
					( Origin gFrontEnd )
				)
				( attribute "TOLERANCE" "10%"
					( Origin gFrontEnd )
				)
				( attribute "VALUE" "1000PF"
					( Origin gFrontEnd )
				)
				( attribute "VER" "1"
					( Origin gFrontEnd )
				)
				( attribute "VOLTAGE" "50V"
					( Units "uVoltage" "V" 1.000000)
					( Origin gFrontEnd )
				)
				( attribute "XY" "(2050,3500)"
					( Origin gFrontEnd )
				)
				( attribute "CHIPS_PART_NAME" "CAP"
					( Origin gPackager )
				)
				( attribute "CDS_PART_NAME" "CAP_0402LF-1000PF,50V,10%,X7R,A"
					( Origin gPackager )
				)
				( attribute "CDS_LOCATION" "CT61"
					( Origin gPackager )
				)
				( attribute "CDS_SEC" "1"
					( Origin gPackager )
				)
				( attribute "SEC" "1"
					( Origin gPackager )
				)
				( attribute "STATUS" "NOPOP"
					( Origin gFrontEnd )
				)
				( objectStatus "CT61" )
				( pin "a"
					( attribute "PN" "1"
						( Origin gPackager )
					)
					( objectStatus "CT61.1" )
				)
				( pin "b"
					( attribute "PN" "2"
						( Origin gPackager )
					)
					( objectStatus "CT61.2" )
				)
			)
			( gate "@baseboard_fab2_lib.baseboard_fab2(sch_1):page214_i137"
				( attribute "CDS_LIB" "dev_discrete"
					( Origin gPackager )
				)
				( attribute "LOCATION" "CT63"
					( Origin gFrontEnd )
				)
				( attribute "MATERIAL" "X7R"
					( Origin gFrontEnd )
				)
				( attribute "PACK_TYPE" "0402V"
					( Origin gFrontEnd )
				)
				( attribute "PART_NUMBER" "A36096-030"
					( Origin gFrontEnd )
				)
				( attribute "PHYS_PAGE" "214"
					( Origin gFrontEnd )
				)
				( attribute "ROOM" "PVCCIN_CPU0_PWR_VR"
					( Origin gFrontEnd )
				)
				( attribute "ROT" "0"
					( Origin gFrontEnd )
				)
				( attribute "TOLERANCE" "10%"
					( Origin gFrontEnd )
				)
				( attribute "VALUE" "0.1UF"
					( Origin gFrontEnd )
				)
				( attribute "VER" "1"
					( Origin gFrontEnd )
				)
				( attribute "VOLTAGE" "16V"
					( Units "uVoltage" "V" 1.000000)
					( Origin gFrontEnd )
				)
				( attribute "XY" "(50,2975)"
					( Origin gFrontEnd )
				)
				( attribute "CHIPS_PART_NAME" "CAP_A"
					( Origin gPackager )
				)
				( attribute "CDS_PART_NAME" "CAP_A_0402V-0.1UF,16V,10%,X7R,A"
					( Origin gPackager )
				)
				( attribute "CDS_LOCATION" "CT63"
					( Origin gPackager )
				)
				( attribute "CDS_SEC" "1"
					( Origin gPackager )
				)
				( attribute "SEC" "1"
					( Origin gPackager )
				)
				( attribute "STATUS" "NOPOP"
					( Origin gFrontEnd )
				)
				( objectStatus "CT63" )
				( pin "a"
					( attribute "PN" "1"
						( Origin gPackager )
					)
					( objectStatus "CT63.1" )
				)
				( pin "b"
					( attribute "PN" "2"
						( Origin gPackager )
					)
					( objectStatus "CT63.2" )
				)
			)
			( gate "@baseboard_fab2_lib.baseboard_fab2(sch_1):page236_i141"
				( attribute "BOM_COST" "DEBUG"
					( Origin gFrontEnd )
				)
				( attribute "CDS_LIB" "mstr_discrete"
					( Origin gPackager )
				)
				( attribute "LOCATION" "RT44"
					( Origin gFrontEnd )
				)
				( attribute "MATERIAL" "CHIP"
					( Origin gFrontEnd )
				)
				( attribute "PACK_TYPE" "0402"
					( Origin gFrontEnd )
				)
				( attribute "PART_NUMBER" "G21497-005"
					( Origin gFrontEnd )
				)
				( attribute "PHYS_PAGE" "236"
					( Origin gFrontEnd )
				)
				( attribute "ROOM" "BMC_DEBUG_HEADER"
					( Origin gFrontEnd )
				)
				( attribute "ROT" "0"
					( Origin gFrontEnd )
				)
				( attribute "TOLERANCE" "5%"
					( Origin gFrontEnd )
				)
				( attribute "VALUE" "0.0"
					( Origin gFrontEnd )
				)
				( attribute "VER" "1"
					( Origin gFrontEnd )
				)
				( attribute "WATTAGE" "1/16W"
					( Origin gFrontEnd )
				)
				( attribute "XY" "(7850,4025)"
					( Origin gFrontEnd )
				)
				( attribute "CHIPS_PART_NAME" "RES"
					( Origin gPackager )
				)
				( attribute "CDS_PART_NAME" "RES_0402-0.0,5%,1/16W,CHIP,G21A"
					( Origin gPackager )
				)
				( attribute "CDS_LOCATION" "RT44"
					( Origin gPackager )
				)
				( attribute "CDS_SEC" "1"
					( Origin gPackager )
				)
				( attribute "SEC" "1"
					( Origin gPackager )
				)
				( objectStatus "RT44" )
				( pin "a"
					( attribute "PN" "1"
						( Origin gPackager )
					)
					( objectStatus "RT44.1" )
				)
				( pin "b"
					( attribute "PN" "2"
						( Origin gPackager )
					)
					( objectStatus "RT44.2" )
				)
			)
			( gate "@baseboard_fab2_lib.baseboard_fab2(sch_1):page181_i280"
				( attribute "CDS_LIB" "mstr_discrete"
					( Origin gPackager )
				)
				( attribute "CDS_LOCATION" "R9F70"
					( Origin gPackager )
				)
				( attribute "CDS_SEC" "1"
					( Origin gPackager )
				)
				( attribute "LOCATION" "R9F70"
					( Origin gFrontEnd )
				)
				( attribute "MATERIAL" "EMPTY"
					( Origin gFrontEnd )
				)
				( attribute "PACK_TYPE" "0402"
					( Origin gFrontEnd )
				)
				( attribute "PART_NUMBER" "G21497-005"
					( Origin gFrontEnd )
				)
				( attribute "PHYS_PAGE" "181"
					( Origin gFrontEnd )
				)
				( attribute "ROOM" "UART_MUX"
					( Origin gFrontEnd )
				)
				( attribute "ROT" "0"
					( Origin gFrontEnd )
				)
				( attribute "SEC" "1"
					( Origin gFrontEnd )
				)
				( attribute "SEC_TYPE" "0402"
					( Origin gFrontEnd )
				)
				( attribute "TOLERANCE" "5%"
					( Origin gFrontEnd )
				)
				( attribute "VALUE" "0.0"
					( Origin gFrontEnd )
				)
				( attribute "VER" "1"
					( Origin gFrontEnd )
				)
				( attribute "WATTAGE" "1/16W"
					( Origin gFrontEnd )
				)
				( attribute "XY" "(-2350,3400)"
					( Origin gFrontEnd )
				)
				( attribute "CHIPS_PART_NAME" "RES"
					( Origin gPackager )
				)
				( attribute "CDS_PART_NAME" "RES_0402-0.0,5%,1/16W,EMPTY,G2A"
					( Origin gPackager )
				)
				( objectStatus "R9F70" )
				( pin "a"
					( attribute "PN" "1"
						( Origin gPackager )
					)
					( objectStatus "R9F70.1" )
				)
				( pin "b"
					( attribute "PN" "2"
						( Origin gPackager )
					)
					( objectStatus "R9F70.2" )
				)
			)
			( gate "@baseboard_fab2_lib.baseboard_fab2(sch_1):page236_i124"
				( attribute "CDS_LIB" "dev_discrete"
					( Origin gPackager )
				)
				( attribute "LOCATION" "CT67"
					( Origin gFrontEnd )
				)
				( attribute "MATERIAL" "X7R"
					( Origin gFrontEnd )
				)
				( attribute "PACK_TYPE" "0402V"
					( Origin gFrontEnd )
				)
				( attribute "PART_NUMBER" "A36096-030"
					( Origin gFrontEnd )
				)
				( attribute "PHYS_PAGE" "236"
					( Origin gFrontEnd )
				)
				( attribute "ROOM" "PVCCIN_CPU0_PWR_VR"
					( Origin gFrontEnd )
				)
				( attribute "ROT" "0"
					( Origin gFrontEnd )
				)
				( attribute "TOLERANCE" "10%"
					( Origin gFrontEnd )
				)
				( attribute "VALUE" "0.1UF"
					( Origin gFrontEnd )
				)
				( attribute "VER" "1"
					( Origin gFrontEnd )
				)
				( attribute "VOLTAGE" "16V"
					( Units "uVoltage" "V" 1.000000)
					( Origin gFrontEnd )
				)
				( attribute "XY" "(8975,2000)"
					( Origin gFrontEnd )
				)
				( attribute "CHIPS_PART_NAME" "CAP_A"
					( Origin gPackager )
				)
				( attribute "CDS_PART_NAME" "CAP_A_0402V-0.1UF,16V,10%,X7R,A"
					( Origin gPackager )
				)
				( attribute "CDS_LOCATION" "CT67"
					( Origin gPackager )
				)
				( attribute "CDS_SEC" "1"
					( Origin gPackager )
				)
				( attribute "SEC" "1"
					( Origin gPackager )
				)
				( attribute "STATUS" "NOPOP"
					( Origin gFrontEnd )
				)
				( objectStatus "CT67" )
				( pin "a"
					( attribute "PN" "1"
						( Origin gPackager )
					)
					( objectStatus "CT67.1" )
				)
				( pin "b"
					( attribute "PN" "2"
						( Origin gPackager )
					)
					( objectStatus "CT67.2" )
				)
			)
			( gate "@baseboard_fab2_lib.baseboard_fab2(sch_1):page236_i127"
				( attribute "CDS_LIB" "dev_discrete"
					( Origin gPackager )
				)
				( attribute "LOCATION" "CT66"
					( Origin gFrontEnd )
				)
				( attribute "MATERIAL" "X7R"
					( Origin gFrontEnd )
				)
				( attribute "PACK_TYPE" "0402V"
					( Origin gFrontEnd )
				)
				( attribute "PART_NUMBER" "A36096-030"
					( Origin gFrontEnd )
				)
				( attribute "PHYS_PAGE" "236"
					( Origin gFrontEnd )
				)
				( attribute "ROOM" "PVCCIN_CPU0_PWR_VR"
					( Origin gFrontEnd )
				)
				( attribute "ROT" "0"
					( Origin gFrontEnd )
				)
				( attribute "TOLERANCE" "10%"
					( Origin gFrontEnd )
				)
				( attribute "VALUE" "0.1UF"
					( Origin gFrontEnd )
				)
				( attribute "VER" "1"
					( Origin gFrontEnd )
				)
				( attribute "VOLTAGE" "16V"
					( Units "uVoltage" "V" 1.000000)
					( Origin gFrontEnd )
				)
				( attribute "XY" "(8975,3750)"
					( Origin gFrontEnd )
				)
				( attribute "CHIPS_PART_NAME" "CAP_A"
					( Origin gPackager )
				)
				( attribute "CDS_PART_NAME" "CAP_A_0402V-0.1UF,16V,10%,X7R,A"
					( Origin gPackager )
				)
				( attribute "CDS_LOCATION" "CT66"
					( Origin gPackager )
				)
				( attribute "CDS_SEC" "1"
					( Origin gPackager )
				)
				( attribute "SEC" "1"
					( Origin gPackager )
				)
				( attribute "STATUS" "NOPOP"
					( Origin gFrontEnd )
				)
				( objectStatus "CT66" )
				( pin "a"
					( attribute "PN" "1"
						( Origin gPackager )
					)
					( objectStatus "CT66.1" )
				)
				( pin "b"
					( attribute "PN" "2"
						( Origin gPackager )
					)
					( objectStatus "CT66.2" )
				)
			)
			( gate "@baseboard_fab2_lib.baseboard_fab2(sch_1):page212_i114"
				( attribute "BOM_COST" "DEBUG"
					( Origin gFrontEnd )
				)
				( attribute "CDS_LIB" "mstr_discrete"
					( Origin gPackager )
				)
				( attribute "LOCATION" "RT47"
					( Origin gFrontEnd )
				)
				( attribute "MATERIAL" "CHIP"
					( Origin gFrontEnd )
				)
				( attribute "PACK_TYPE" "0402"
					( Origin gFrontEnd )
				)
				( attribute "PART_NUMBER" "G21497-005"
					( Origin gFrontEnd )
				)
				( attribute "PHYS_PAGE" "212"
					( Origin gFrontEnd )
				)
				( attribute "ROOM" "BMC_DEBUG_HEADER"
					( Origin gFrontEnd )
				)
				( attribute "ROT" "0"
					( Origin gFrontEnd )
				)
				( attribute "TOLERANCE" "5%"
					( Origin gFrontEnd )
				)
				( attribute "VALUE" "0.0"
					( Origin gFrontEnd )
				)
				( attribute "VER" "1"
					( Origin gFrontEnd )
				)
				( attribute "WATTAGE" "1/16W"
					( Origin gFrontEnd )
				)
				( attribute "XY" "(-950,3575)"
					( Origin gFrontEnd )
				)
				( attribute "CHIPS_PART_NAME" "RES"
					( Origin gPackager )
				)
				( attribute "CDS_PART_NAME" "RES_0402-0.0,5%,1/16W,CHIP,G21A"
					( Origin gPackager )
				)
				( attribute "CDS_LOCATION" "RT47"
					( Origin gPackager )
				)
				( attribute "CDS_SEC" "1"
					( Origin gPackager )
				)
				( attribute "SEC" "1"
					( Origin gPackager )
				)
				( objectStatus "RT47" )
				( pin "a"
					( attribute "PN" "1"
						( Origin gPackager )
					)
					( objectStatus "RT47.1" )
				)
				( pin "b"
					( attribute "PN" "2"
						( Origin gPackager )
					)
					( objectStatus "RT47.2" )
				)
			)
			( gate "@baseboard_fab2_lib.baseboard_fab2(sch_1):page236_i131"
				( attribute "CDS_LIB" "w_hdl"
					( Origin gPackager )
				)
				( attribute "CDS_LMAN_SYM_OUTLINE" "-50,25,50,-25"
					( Origin gPackager )
				)
				( attribute "LOCATION" "CT65"
					( Origin gFrontEnd )
				)
				( attribute "PACK_TYPE" "SMD-BCG6"
					( Origin gFrontEnd )
				)
				( attribute "PART_NUMBER" "78.22224.2BL"
					( Origin gFrontEnd )
				)
				( attribute "PHYS_PAGE" "236"
					( Origin gFrontEnd )
				)
				( attribute "ROT" "0"
					( Origin gFrontEnd )
				)
				( attribute "VALUE" "SC2K2P50V3KX-GP"
					( Origin gFrontEnd )
				)
				( attribute "VER" "1"
					( Origin gFrontEnd )
				)
				( attribute "XY" "(10750,3850)"
					( Origin gFrontEnd )
				)
				( attribute "CHIPS_PART_NAME" "SC2K2P50V3KX-GP"
					( Origin gPackager )
				)
				( attribute "CDS_PART_NAME" "SC2K2P50V3KX-GP_SMD-BCG6-SC2K2A"
					( Origin gPackager )
				)
				( attribute "STATUS" "NOPOP"
					( Origin gFrontEnd )
				)
				( attribute "CDS_LOCATION" "CT65"
					( Origin gPackager )
				)
				( attribute "CDS_SEC" "1"
					( Origin gPackager )
				)
				( attribute "SEC" "1"
					( Origin gPackager )
				)
				( objectStatus "CT65" )
				( pin "\1\"
					( attribute "PN" "1"
						( Origin gPackager )
					)
					( objectStatus "CT65.1" )
				)
				( pin "\2\"
					( attribute "PN" "2"
						( Origin gPackager )
					)
					( objectStatus "CT65.2" )
				)
			)
			( gate "@baseboard_fab2_lib.baseboard_fab2(sch_1):page236_i132"
				( attribute "CDS_LIB" "w_hdl"
					( Origin gPackager )
				)
				( attribute "CDS_LMAN_SYM_OUTLINE" "-50,75,50,-75"
					( Origin gPackager )
				)
				( attribute "CDS_LOCATION" "RT43"
					( Origin gPackager )
				)
				( attribute "CDS_SEC" "1"
					( Origin gPackager )
				)
				( attribute "LOCATION" "RT43"
					( Origin gFrontEnd )
				)
				( attribute "PACK_TYPE" "SMD-RG5"
					( Origin gFrontEnd )
				)
				( attribute "PART_NUMBER" "64.3R015.16L"
					( Origin gFrontEnd )
				)
				( attribute "PHYS_PAGE" "236"
					( Origin gFrontEnd )
				)
				( attribute "ROT" "4"
					( Origin gFrontEnd )
				)
				( attribute "VALUE" "3D01R5F-GP"
					( Origin gFrontEnd )
				)
				( attribute "VER" "1"
					( Origin gFrontEnd )
				)
				( attribute "XY" "(10750,3575)"
					( Origin gFrontEnd )
				)
				( attribute "CHIPS_PART_NAME" "3D01R5F-GP"
					( Origin gPackager )
				)
				( attribute "CDS_PART_NAME" "3D01R5F-GP_SMD-RG5-3D01R5F-GP,A"
					( Origin gPackager )
				)
				( attribute "SEC" "1"
					( Origin gPackager )
				)
				( attribute "STATUS" "NOPOP"
					( Origin gFrontEnd )
				)
				( objectStatus "RT43" )
				( pin "\1\"
					( attribute "PN" "1"
						( Origin gPackager )
					)
					( objectStatus "RT43.1" )
				)
				( pin "\2\"
					( attribute "PN" "2"
						( Origin gPackager )
					)
					( objectStatus "RT43.2" )
				)
			)
			( gate "@baseboard_fab2_lib.baseboard_fab2(sch_1):page236_i134"
				( attribute "CDS_LIB" "mstr_discrete"
					( Origin gPackager )
				)
				( attribute "LOCATION" "CT69"
					( Origin gFrontEnd )
				)
				( attribute "MATERIAL" "X7R"
					( Origin gFrontEnd )
				)
				( attribute "PACK_TYPE" "0402LF"
					( Origin gFrontEnd )
				)
				( attribute "PART_NUMBER" "A36096-046"
					( Origin gFrontEnd )
				)
				( attribute "PHYS_PAGE" "236"
					( Origin gFrontEnd )
				)
				( attribute "ROOM" "VDDQ_KLM_PWR_VR"
					( Origin gFrontEnd )
				)
				( attribute "ROT" "0"
					( Origin gFrontEnd )
				)
				( attribute "TOLERANCE" "10%"
					( Origin gFrontEnd )
				)
				( attribute "VALUE" "1000PF"
					( Origin gFrontEnd )
				)
				( attribute "VER" "1"
					( Origin gFrontEnd )
				)
				( attribute "VOLTAGE" "50V"
					( Units "uVoltage" "V" 1.000000)
					( Origin gFrontEnd )
				)
				( attribute "XY" "(10750,2575)"
					( Origin gFrontEnd )
				)
				( attribute "CHIPS_PART_NAME" "CAP"
					( Origin gPackager )
				)
				( attribute "CDS_PART_NAME" "CAP_0402LF-1000PF,50V,10%,X7R,A"
					( Origin gPackager )
				)
				( attribute "STATUS" "NOPOP"
					( Origin gFrontEnd )
				)
				( attribute "CDS_LOCATION" "CT69"
					( Origin gPackager )
				)
				( attribute "CDS_SEC" "1"
					( Origin gPackager )
				)
				( attribute "SEC" "1"
					( Origin gPackager )
				)
				( objectStatus "CT69" )
				( pin "a"
					( attribute "PN" "1"
						( Origin gPackager )
					)
					( objectStatus "CT69.1" )
				)
				( pin "b"
					( attribute "PN" "2"
						( Origin gPackager )
					)
					( objectStatus "CT69.2" )
				)
			)
			( gate "@baseboard_fab2_lib.baseboard_fab2(sch_1):page236_i136"
				( attribute "CDS_LIB" "mstr_discrete"
					( Origin gPackager )
				)
				( attribute "LOCATION" "CT64"
					( Origin gFrontEnd )
				)
				( attribute "MATERIAL" "X7R"
					( Origin gFrontEnd )
				)
				( attribute "PACK_TYPE" "0402LF"
					( Origin gFrontEnd )
				)
				( attribute "PART_NUMBER" "A36096-046"
					( Origin gFrontEnd )
				)
				( attribute "PHYS_PAGE" "236"
					( Origin gFrontEnd )
				)
				( attribute "ROOM" "VDDQ_KLM_PWR_VR"
					( Origin gFrontEnd )
				)
				( attribute "ROT" "0"
					( Origin gFrontEnd )
				)
				( attribute "TOLERANCE" "10%"
					( Origin gFrontEnd )
				)
				( attribute "VALUE" "1000PF"
					( Origin gFrontEnd )
				)
				( attribute "VER" "1"
					( Origin gFrontEnd )
				)
				( attribute "VOLTAGE" "50V"
					( Units "uVoltage" "V" 1.000000)
					( Origin gFrontEnd )
				)
				( attribute "XY" "(10775,4275)"
					( Origin gFrontEnd )
				)
				( attribute "CHIPS_PART_NAME" "CAP"
					( Origin gPackager )
				)
				( attribute "CDS_PART_NAME" "CAP_0402LF-1000PF,50V,10%,X7R,A"
					( Origin gPackager )
				)
				( attribute "CDS_LOCATION" "CT64"
					( Origin gPackager )
				)
				( attribute "CDS_SEC" "1"
					( Origin gPackager )
				)
				( attribute "SEC" "1"
					( Origin gPackager )
				)
				( attribute "STATUS" "NOPOP"
					( Origin gFrontEnd )
				)
				( objectStatus "CT64" )
				( pin "a"
					( attribute "PN" "1"
						( Origin gPackager )
					)
					( objectStatus "CT64.1" )
				)
				( pin "b"
					( attribute "PN" "2"
						( Origin gPackager )
					)
					( objectStatus "CT64.2" )
				)
			)
			( gate "@baseboard_fab2_lib.baseboard_fab2(sch_1):page236_i137"
				( attribute "CDS_LIB" "w_hdl"
					( Origin gPackager )
				)
				( attribute "CDS_LMAN_SYM_OUTLINE" "-50,75,50,-75"
					( Origin gPackager )
				)
				( attribute "LOCATION" "RT45"
					( Origin gFrontEnd )
				)
				( attribute "PACK_TYPE" "SMD-RG5"
					( Origin gFrontEnd )
				)
				( attribute "PART_NUMBER" "64.3R015.16L"
					( Origin gFrontEnd )
				)
				( attribute "PHYS_PAGE" "236"
					( Origin gFrontEnd )
				)
				( attribute "ROT" "4"
					( Origin gFrontEnd )
				)
				( attribute "VALUE" "3D01R5F-GP"
					( Origin gFrontEnd )
				)
				( attribute "VER" "1"
					( Origin gFrontEnd )
				)
				( attribute "XY" "(10800,1850)"
					( Origin gFrontEnd )
				)
				( attribute "CHIPS_PART_NAME" "3D01R5F-GP"
					( Origin gPackager )
				)
				( attribute "CDS_PART_NAME" "3D01R5F-GP_SMD-RG5-3D01R5F-GP,A"
					( Origin gPackager )
				)
				( attribute "STATUS" "NOPOP"
					( Origin gFrontEnd )
				)
				( attribute "CDS_LOCATION" "RT45"
					( Origin gPackager )
				)
				( attribute "CDS_SEC" "1"
					( Origin gPackager )
				)
				( attribute "SEC" "1"
					( Origin gPackager )
				)
				( objectStatus "RT45" )
				( pin "\1\"
					( attribute "PN" "1"
						( Origin gPackager )
					)
					( objectStatus "RT45.1" )
				)
				( pin "\2\"
					( attribute "PN" "2"
						( Origin gPackager )
					)
					( objectStatus "RT45.2" )
				)
			)
			( gate "@baseboard_fab2_lib.baseboard_fab2(sch_1):page236_i140"
				( attribute "CDS_LIB" "w_hdl"
					( Origin gPackager )
				)
				( attribute "CDS_LMAN_SYM_OUTLINE" "-50,25,50,-25"
					( Origin gPackager )
				)
				( attribute "LOCATION" "CT68"
					( Origin gFrontEnd )
				)
				( attribute "PACK_TYPE" "SMD-BCG6"
					( Origin gFrontEnd )
				)
				( attribute "PART_NUMBER" "78.22224.2BL"
					( Origin gFrontEnd )
				)
				( attribute "PHYS_PAGE" "236"
					( Origin gFrontEnd )
				)
				( attribute "ROT" "0"
					( Origin gFrontEnd )
				)
				( attribute "VALUE" "SC2K2P50V3KX-GP"
					( Origin gFrontEnd )
				)
				( attribute "VER" "1"
					( Origin gFrontEnd )
				)
				( attribute "XY" "(10800,2100)"
					( Origin gFrontEnd )
				)
				( attribute "CHIPS_PART_NAME" "SC2K2P50V3KX-GP"
					( Origin gPackager )
				)
				( attribute "CDS_PART_NAME" "SC2K2P50V3KX-GP_SMD-BCG6-SC2K2A"
					( Origin gPackager )
				)
				( attribute "CDS_LOCATION" "CT68"
					( Origin gPackager )
				)
				( attribute "CDS_SEC" "1"
					( Origin gPackager )
				)
				( attribute "SEC" "1"
					( Origin gPackager )
				)
				( attribute "STATUS" "NOPOP"
					( Origin gFrontEnd )
				)
				( objectStatus "CT68" )
				( pin "\1\"
					( attribute "PN" "1"
						( Origin gPackager )
					)
					( objectStatus "CT68.1" )
				)
				( pin "\2\"
					( attribute "PN" "2"
						( Origin gPackager )
					)
					( objectStatus "CT68.2" )
				)
			)
			( gate "@baseboard_fab2_lib.baseboard_fab2(sch_1):page212_i106"
				( attribute "CDS_LIB" "dev_discrete"
					( Origin gPackager )
				)
				( attribute "LOCATION" "CT70"
					( Origin gFrontEnd )
				)
				( attribute "MATERIAL" "X7R"
					( Origin gFrontEnd )
				)
				( attribute "PACK_TYPE" "0402V"
					( Origin gFrontEnd )
				)
				( attribute "PART_NUMBER" "A36096-030"
					( Origin gFrontEnd )
				)
				( attribute "PHYS_PAGE" "212"
					( Origin gFrontEnd )
				)
				( attribute "ROOM" "PVCCIN_CPU0_PWR_VR"
					( Origin gFrontEnd )
				)
				( attribute "ROT" "0"
					( Origin gFrontEnd )
				)
				( attribute "TOLERANCE" "10%"
					( Origin gFrontEnd )
				)
				( attribute "VALUE" "0.1UF"
					( Origin gFrontEnd )
				)
				( attribute "VER" "1"
					( Origin gFrontEnd )
				)
				( attribute "VOLTAGE" "16V"
					( Units "uVoltage" "V" 1.000000)
					( Origin gFrontEnd )
				)
				( attribute "XY" "(25,3275)"
					( Origin gFrontEnd )
				)
				( attribute "CHIPS_PART_NAME" "CAP_A"
					( Origin gPackager )
				)
				( attribute "CDS_PART_NAME" "CAP_A_0402V-0.1UF,16V,10%,X7R,A"
					( Origin gPackager )
				)
				( attribute "CDS_LOCATION" "CT70"
					( Origin gPackager )
				)
				( attribute "CDS_SEC" "1"
					( Origin gPackager )
				)
				( attribute "SEC" "1"
					( Origin gPackager )
				)
				( attribute "STATUS" "NOPOP"
					( Origin gFrontEnd )
				)
				( objectStatus "CT70" )
				( pin "a"
					( attribute "PN" "1"
						( Origin gPackager )
					)
					( objectStatus "CT70.1" )
				)
				( pin "b"
					( attribute "PN" "2"
						( Origin gPackager )
					)
					( objectStatus "CT70.2" )
				)
			)
			( gate "@baseboard_fab2_lib.baseboard_fab2(sch_1):page158_i148"
				( attribute "BOM_COST" "DEBUG"
					( Origin gFrontEnd )
				)
				( attribute "CDS_LIB" "mstr_discrete"
					( Origin gPackager )
				)
				( attribute "LOCATION" "R9F65"
					( Origin gFrontEnd )
				)
				( attribute "MATERIAL" "CHIP"
					( Origin gFrontEnd )
				)
				( attribute "PACK_TYPE" "0402"
					( Origin gFrontEnd )
				)
				( attribute "PART_NUMBER" "G21497-005"
					( Origin gFrontEnd )
				)
				( attribute "PHYS_PAGE" "158"
					( Origin gFrontEnd )
				)
				( attribute "ROOM" "UART_MUX"
					( Origin gFrontEnd )
				)
				( attribute "ROT" "0"
					( Origin gFrontEnd )
				)
				( attribute "TOLERANCE" "5%"
					( Origin gFrontEnd )
				)
				( attribute "VALUE" "0.0"
					( Origin gFrontEnd )
				)
				( attribute "VER" "1"
					( Origin gFrontEnd )
				)
				( attribute "WATTAGE" "1/16W"
					( Origin gFrontEnd )
				)
				( attribute "XY" "(-3125,3750)"
					( Origin gFrontEnd )
				)
				( attribute "CHIPS_PART_NAME" "RES"
					( Origin gPackager )
				)
				( attribute "CDS_PART_NAME" "RES_0402-0.0,5%,1/16W,CHIP,G21A"
					( Origin gPackager )
				)
				( attribute "CDS_LOCATION" "R9F65"
					( Origin gPackager )
				)
				( attribute "CDS_SEC" "1"
					( Origin gPackager )
				)
				( attribute "SEC" "1"
					( Origin gPackager )
				)
				( objectStatus "R9F65" )
				( pin "a"
					( attribute "PN" "1"
						( Origin gPackager )
					)
					( objectStatus "R9F65.1" )
				)
				( pin "b"
					( attribute "PN" "2"
						( Origin gPackager )
					)
					( objectStatus "R9F65.2" )
				)
			)
			( gate "@baseboard_fab2_lib.baseboard_fab2(sch_1):page212_i109"
				( attribute "CDS_LIB" "mstr_discrete"
					( Origin gPackager )
				)
				( attribute "LOCATION" "CT71"
					( Origin gFrontEnd )
				)
				( attribute "MATERIAL" "X7R"
					( Origin gFrontEnd )
				)
				( attribute "PACK_TYPE" "0402LF"
					( Origin gFrontEnd )
				)
				( attribute "PART_NUMBER" "A36096-046"
					( Origin gFrontEnd )
				)
				( attribute "PHYS_PAGE" "212"
					( Origin gFrontEnd )
				)
				( attribute "ROOM" "VDDQ_KLM_PWR_VR"
					( Origin gFrontEnd )
				)
				( attribute "ROT" "0"
					( Origin gFrontEnd )
				)
				( attribute "TOLERANCE" "10%"
					( Origin gFrontEnd )
				)
				( attribute "VALUE" "1000PF"
					( Origin gFrontEnd )
				)
				( attribute "VER" "1"
					( Origin gFrontEnd )
				)
				( attribute "VOLTAGE" "50V"
					( Units "uVoltage" "V" 1.000000)
					( Origin gFrontEnd )
				)
				( attribute "XY" "(1950,3800)"
					( Origin gFrontEnd )
				)
				( attribute "CHIPS_PART_NAME" "CAP"
					( Origin gPackager )
				)
				( attribute "CDS_PART_NAME" "CAP_0402LF-1000PF,50V,10%,X7R,A"
					( Origin gPackager )
				)
				( attribute "CDS_LOCATION" "CT71"
					( Origin gPackager )
				)
				( attribute "CDS_SEC" "1"
					( Origin gPackager )
				)
				( attribute "SEC" "1"
					( Origin gPackager )
				)
				( attribute "STATUS" "NOPOP"
					( Origin gFrontEnd )
				)
				( objectStatus "CT71" )
				( pin "a"
					( attribute "PN" "1"
						( Origin gPackager )
					)
					( objectStatus "CT71.1" )
				)
				( pin "b"
					( attribute "PN" "2"
						( Origin gPackager )
					)
					( objectStatus "CT71.2" )
				)
			)
			( gate "@baseboard_fab2_lib.baseboard_fab2(sch_1):page212_i111"
				( attribute "CDS_LIB" "w_hdl"
					( Origin gPackager )
				)
				( attribute "CDS_LMAN_SYM_OUTLINE" "-50,25,50,-25"
					( Origin gPackager )
				)
				( attribute "LOCATION" "CT72"
					( Origin gFrontEnd )
				)
				( attribute "PACK_TYPE" "SMD-BCG6"
					( Origin gFrontEnd )
				)
				( attribute "PART_NUMBER" "78.22224.2BL"
					( Origin gFrontEnd )
				)
				( attribute "PHYS_PAGE" "212"
					( Origin gFrontEnd )
				)
				( attribute "ROT" "0"
					( Origin gFrontEnd )
				)
				( attribute "VALUE" "SC2K2P50V3KX-GP"
					( Origin gFrontEnd )
				)
				( attribute "VER" "1"
					( Origin gFrontEnd )
				)
				( attribute "XY" "(2050,3325)"
					( Origin gFrontEnd )
				)
				( attribute "CHIPS_PART_NAME" "SC2K2P50V3KX-GP"
					( Origin gPackager )
				)
				( attribute "CDS_PART_NAME" "SC2K2P50V3KX-GP_SMD-BCG6-SC2K2A"
					( Origin gPackager )
				)
				( attribute "CDS_LOCATION" "CT72"
					( Origin gPackager )
				)
				( attribute "CDS_SEC" "1"
					( Origin gPackager )
				)
				( attribute "SEC" "1"
					( Origin gPackager )
				)
				( attribute "STATUS" "NOPOP"
					( Origin gFrontEnd )
				)
				( objectStatus "CT72" )
				( pin "\1\"
					( attribute "PN" "1"
						( Origin gPackager )
					)
					( objectStatus "CT72.1" )
				)
				( pin "\2\"
					( attribute "PN" "2"
						( Origin gPackager )
					)
					( objectStatus "CT72.2" )
				)
			)
			( gate "@baseboard_fab2_lib.baseboard_fab2(sch_1):page212_i112"
				( attribute "CDS_LIB" "w_hdl"
					( Origin gPackager )
				)
				( attribute "CDS_LMAN_SYM_OUTLINE" "-50,75,50,-75"
					( Origin gPackager )
				)
				( attribute "CDS_LOCATION" "RT48"
					( Origin gPackager )
				)
				( attribute "CDS_SEC" "1"
					( Origin gPackager )
				)
				( attribute "LOCATION" "RT48"
					( Origin gFrontEnd )
				)
				( attribute "PACK_TYPE" "SMD-RG5"
					( Origin gFrontEnd )
				)
				( attribute "PART_NUMBER" "64.3R015.16L"
					( Origin gFrontEnd )
				)
				( attribute "PHYS_PAGE" "212"
					( Origin gFrontEnd )
				)
				( attribute "ROT" "4"
					( Origin gFrontEnd )
				)
				( attribute "VALUE" "3D01R5F-GP"
					( Origin gFrontEnd )
				)
				( attribute "VER" "1"
					( Origin gFrontEnd )
				)
				( attribute "XY" "(2050,3000)"
					( Origin gFrontEnd )
				)
				( attribute "CHIPS_PART_NAME" "3D01R5F-GP"
					( Origin gPackager )
				)
				( attribute "CDS_PART_NAME" "3D01R5F-GP_SMD-RG5-3D01R5F-GP,A"
					( Origin gPackager )
				)
				( attribute "SEC" "1"
					( Origin gPackager )
				)
				( attribute "STATUS" "NOPOP"
					( Origin gFrontEnd )
				)
				( objectStatus "RT48" )
				( pin "\1\"
					( attribute "PN" "1"
						( Origin gPackager )
					)
					( objectStatus "RT48.1" )
				)
				( pin "\2\"
					( attribute "PN" "2"
						( Origin gPackager )
					)
					( objectStatus "RT48.2" )
				)
			)
			( gate "@baseboard_fab2_lib.baseboard_fab2(sch_1):page207_i81"
				( attribute "CDS_LIB" "dev_discrete"
					( Origin gPackager )
				)
				( attribute "LOCATION" "CT25"
					( Origin gFrontEnd )
				)
				( attribute "MATERIAL" "X7R"
					( Origin gFrontEnd )
				)
				( attribute "PACK_TYPE" "0402V"
					( Origin gFrontEnd )
				)
				( attribute "PART_NUMBER" "A36096-030"
					( Origin gFrontEnd )
				)
				( attribute "PHYS_PAGE" "207"
					( Origin gFrontEnd )
				)
				( attribute "ROOM" "PVCCIN_CPU0_PWR_VR"
					( Origin gFrontEnd )
				)
				( attribute "ROT" "0"
					( Origin gFrontEnd )
				)
				( attribute "TOLERANCE" "10%"
					( Origin gFrontEnd )
				)
				( attribute "VALUE" "0.1UF"
					( Origin gFrontEnd )
				)
				( attribute "VER" "1"
					( Origin gFrontEnd )
				)
				( attribute "VOLTAGE" "16V"
					( Units "uVoltage" "V" 1.000000)
					( Origin gFrontEnd )
				)
				( attribute "XY" "(-4150,725)"
					( Origin gFrontEnd )
				)
				( attribute "CHIPS_PART_NAME" "CAP_A"
					( Origin gPackager )
				)
				( attribute "CDS_PART_NAME" "CAP_A_0402V-0.1UF,16V,10%,X7R,A"
					( Origin gPackager )
				)
				( attribute "CDS_LOCATION" "CT25"
					( Origin gPackager )
				)
				( attribute "CDS_SEC" "1"
					( Origin gPackager )
				)
				( attribute "SEC" "1"
					( Origin gPackager )
				)
				( attribute "STATUS" "NOPOP"
					( Origin gFrontEnd )
				)
				( objectStatus "CT25" )
				( pin "a"
					( attribute "PN" "1"
						( Origin gPackager )
					)
					( objectStatus "CT25.1" )
				)
				( pin "b"
					( attribute "PN" "2"
						( Origin gPackager )
					)
					( objectStatus "CT25.2" )
				)
			)
			( gate "@baseboard_fab2_lib.baseboard_fab2(sch_1):page207_i82"
				( attribute "CDS_LIB" "mstr_discrete"
					( Origin gPackager )
				)
				( attribute "LOCATION" "CT26"
					( Origin gFrontEnd )
				)
				( attribute "MATERIAL" "X7R"
					( Origin gFrontEnd )
				)
				( attribute "PACK_TYPE" "0402LF"
					( Origin gFrontEnd )
				)
				( attribute "PART_NUMBER" "A36096-046"
					( Origin gFrontEnd )
				)
				( attribute "PHYS_PAGE" "207"
					( Origin gFrontEnd )
				)
				( attribute "ROOM" "VDDQ_KLM_PWR_VR"
					( Origin gFrontEnd )
				)
				( attribute "ROT" "0"
					( Origin gFrontEnd )
				)
				( attribute "TOLERANCE" "10%"
					( Origin gFrontEnd )
				)
				( attribute "VALUE" "1000PF"
					( Origin gFrontEnd )
				)
				( attribute "VER" "1"
					( Origin gFrontEnd )
				)
				( attribute "VOLTAGE" "50V"
					( Units "uVoltage" "V" 1.000000)
					( Origin gFrontEnd )
				)
				( attribute "XY" "(-2400,1225)"
					( Origin gFrontEnd )
				)
				( attribute "CHIPS_PART_NAME" "CAP"
					( Origin gPackager )
				)
				( attribute "CDS_PART_NAME" "CAP_0402LF-1000PF,50V,10%,X7R,A"
					( Origin gPackager )
				)
				( attribute "CDS_LOCATION" "CT26"
					( Origin gPackager )
				)
				( attribute "CDS_SEC" "1"
					( Origin gPackager )
				)
				( attribute "SEC" "1"
					( Origin gPackager )
				)
				( attribute "STATUS" "NOPOP"
					( Origin gFrontEnd )
				)
				( objectStatus "CT26" )
				( pin "a"
					( attribute "PN" "1"
						( Origin gPackager )
					)
					( objectStatus "CT26.1" )
				)
				( pin "b"
					( attribute "PN" "2"
						( Origin gPackager )
					)
					( objectStatus "CT26.2" )
				)
			)
			( gate "@baseboard_fab2_lib.baseboard_fab2(sch_1):page207_i84"
				( attribute "CDS_LIB" "w_hdl"
					( Origin gPackager )
				)
				( attribute "CDS_LMAN_SYM_OUTLINE" "-50,25,50,-25"
					( Origin gPackager )
				)
				( attribute "LOCATION" "CT27"
					( Origin gFrontEnd )
				)
				( attribute "PACK_TYPE" "SMD-BCG6"
					( Origin gFrontEnd )
				)
				( attribute "PART_NUMBER" "78.22224.2BL"
					( Origin gFrontEnd )
				)
				( attribute "PHYS_PAGE" "207"
					( Origin gFrontEnd )
				)
				( attribute "ROT" "0"
					( Origin gFrontEnd )
				)
				( attribute "VALUE" "SC2K2P50V3KX-GP"
					( Origin gFrontEnd )
				)
				( attribute "VER" "1"
					( Origin gFrontEnd )
				)
				( attribute "XY" "(-2350,825)"
					( Origin gFrontEnd )
				)
				( attribute "CHIPS_PART_NAME" "SC2K2P50V3KX-GP"
					( Origin gPackager )
				)
				( attribute "CDS_PART_NAME" "SC2K2P50V3KX-GP_SMD-BCG6-SC2K2A"
					( Origin gPackager )
				)
				( attribute "CDS_LOCATION" "CT27"
					( Origin gPackager )
				)
				( attribute "CDS_SEC" "1"
					( Origin gPackager )
				)
				( attribute "SEC" "1"
					( Origin gPackager )
				)
				( attribute "STATUS" "NOPOP"
					( Origin gFrontEnd )
				)
				( objectStatus "CT27" )
				( pin "\1\"
					( attribute "PN" "1"
						( Origin gPackager )
					)
					( objectStatus "CT27.1" )
				)
				( pin "\2\"
					( attribute "PN" "2"
						( Origin gPackager )
					)
					( objectStatus "CT27.2" )
				)
			)
			( gate "@baseboard_fab2_lib.baseboard_fab2(sch_1):page207_i85"
				( attribute "CDS_LIB" "w_hdl"
					( Origin gPackager )
				)
				( attribute "CDS_LMAN_SYM_OUTLINE" "-50,75,50,-75"
					( Origin gPackager )
				)
				( attribute "CDS_LOCATION" "RT18"
					( Origin gPackager )
				)
				( attribute "CDS_SEC" "1"
					( Origin gPackager )
				)
				( attribute "LOCATION" "RT18"
					( Origin gFrontEnd )
				)
				( attribute "PACK_TYPE" "SMD-RG5"
					( Origin gFrontEnd )
				)
				( attribute "PART_NUMBER" "64.3R015.16L"
					( Origin gFrontEnd )
				)
				( attribute "PHYS_PAGE" "207"
					( Origin gFrontEnd )
				)
				( attribute "ROT" "4"
					( Origin gFrontEnd )
				)
				( attribute "VALUE" "3D01R5F-GP"
					( Origin gFrontEnd )
				)
				( attribute "VER" "1"
					( Origin gFrontEnd )
				)
				( attribute "XY" "(-2350,550)"
					( Origin gFrontEnd )
				)
				( attribute "CHIPS_PART_NAME" "3D01R5F-GP"
					( Origin gPackager )
				)
				( attribute "CDS_PART_NAME" "3D01R5F-GP_SMD-RG5-3D01R5F-GP,A"
					( Origin gPackager )
				)
				( attribute "SEC" "1"
					( Origin gPackager )
				)
				( attribute "STATUS" "NOPOP"
					( Origin gFrontEnd )
				)
				( objectStatus "RT18" )
				( pin "\1\"
					( attribute "PN" "1"
						( Origin gPackager )
					)
					( objectStatus "RT18.1" )
				)
				( pin "\2\"
					( attribute "PN" "2"
						( Origin gPackager )
					)
					( objectStatus "RT18.2" )
				)
			)
			( gate "@baseboard_fab2_lib.baseboard_fab2(sch_1):page227_i124"
				( attribute "CDS_LIB" "w_hdl"
					( Origin gPackager )
				)
				( attribute "CDS_LMAN_SYM_OUTLINE" "-50,75,50,-75"
					( Origin gPackager )
				)
				( attribute "LOCATION" "RT7"
					( Origin gFrontEnd )
				)
				( attribute "PACK_TYPE" "SMD-RG5"
					( Origin gFrontEnd )
				)
				( attribute "PART_NUMBER" "64.3R015.16L"
					( Origin gFrontEnd )
				)
				( attribute "PHYS_PAGE" "227"
					( Origin gFrontEnd )
				)
				( attribute "ROT" "0"
					( Origin gFrontEnd )
				)
				( attribute "VALUE" "3D01R5F-GP"
					( Origin gFrontEnd )
				)
				( attribute "VER" "1"
					( Origin gFrontEnd )
				)
				( attribute "XY" "(2575,-750)"
					( Origin gFrontEnd )
				)
				( attribute "CHIPS_PART_NAME" "3D01R5F-GP"
					( Origin gPackager )
				)
				( attribute "CDS_PART_NAME" "3D01R5F-GP_SMD-RG5-3D01R5F-GP,A"
					( Origin gPackager )
				)
				( attribute "CDS_LOCATION" "RT7"
					( Origin gPackager )
				)
				( attribute "CDS_SEC" "1"
					( Origin gPackager )
				)
				( attribute "SEC" "1"
					( Origin gPackager )
				)
				( attribute "STATUS" "NOPOP"
					( Origin gFrontEnd )
				)
				( objectStatus "RT7" )
				( pin "\1\"
					( attribute "PN" "1"
						( Origin gPackager )
					)
					( objectStatus "RT7.1" )
				)
				( pin "\2\"
					( attribute "PN" "2"
						( Origin gPackager )
					)
					( objectStatus "RT7.2" )
				)
			)
			( gate "@baseboard_fab2_lib.baseboard_fab2(sch_1):page202_i87"
				( attribute "CDS_LIB" "mstr_discrete"
					( Origin gPackager )
				)
				( attribute "CDS_LOCATION" "CT4"
					( Origin gPackager )
				)
				( attribute "CDS_SEC" "1"
					( Origin gPackager )
				)
				( attribute "LOCATION" "CT4"
					( Origin gFrontEnd )
				)
				( attribute "MATERIAL" "X7R"
					( Origin gFrontEnd )
				)
				( attribute "PACK_TYPE" "0402LF"
					( Origin gFrontEnd )
				)
				( attribute "PART_NUMBER" "A36096-046"
					( Origin gFrontEnd )
				)
				( attribute "PHYS_PAGE" "202"
					( Origin gFrontEnd )
				)
				( attribute "ROOM" "VDDQ_KLM_PWR_VR"
					( Origin gFrontEnd )
				)
				( attribute "ROT" "0"
					( Origin gFrontEnd )
				)
				( attribute "SEC" "1"
					( Origin gPackager )
				)
				( attribute "TOLERANCE" "10%"
					( Origin gFrontEnd )
				)
				( attribute "VALUE" "1000PF"
					( Origin gFrontEnd )
				)
				( attribute "VER" "1"
					( Origin gFrontEnd )
				)
				( attribute "VOLTAGE" "50V"
					( Units "uVoltage" "V" 1.000000)
					( Origin gFrontEnd )
				)
				( attribute "XY" "(-2450,1250)"
					( Origin gFrontEnd )
				)
				( attribute "CHIPS_PART_NAME" "CAP"
					( Origin gPackager )
				)
				( attribute "CDS_PART_NAME" "CAP_0402LF-1000PF,50V,10%,X7R,A"
					( Origin gPackager )
				)
				( attribute "STATUS" "NOPOP"
					( Origin gFrontEnd )
				)
				( objectStatus "CT4" )
				( pin "a"
					( attribute "PN" "1"
						( Origin gPackager )
					)
					( objectStatus "CT4.1" )
				)
				( pin "b"
					( attribute "PN" "2"
						( Origin gPackager )
					)
					( objectStatus "CT4.2" )
				)
			)
			( gate "@baseboard_fab2_lib.baseboard_fab2(sch_1):page244_i2"
				( attribute "CDS_LIB" "mstr_discrete"
					( Origin gPackager )
				)
				( attribute "CDS_LOCATION" "C831"
					( Origin gPackager )
				)
				( attribute "CDS_SEC" "1"
					( Origin gPackager )
				)
				( attribute "LOCATION" "C831"
					( Origin gPackager )
				)
				( attribute "MATERIAL" "X7R"
					( Origin gFrontEnd )
				)
				( attribute "PACK_TYPE" "0402"
					( Origin gFrontEnd )
				)
				( attribute "PART_NUMBER" "A36096-155"
					( Origin gFrontEnd )
				)
				( attribute "PHYS_PAGE" "244"
					( Origin gFrontEnd )
				)
				( attribute "ROOM" "OCP_STEERING"
					( Origin gFrontEnd )
				)
				( attribute "ROT" "2"
					( Origin gFrontEnd )
				)
				( attribute "SEC" "1"
					( Origin gPackager )
				)
				( attribute "TOLERANCE" "10%"
					( Origin gFrontEnd )
				)
				( attribute "VALUE" "0.22UF"
					( Origin gFrontEnd )
				)
				( attribute "VER" "1"
					( Origin gFrontEnd )
				)
				( attribute "VOLTAGE" "16V"
					( Units "uVoltage" "V" 1.000000)
					( Origin gFrontEnd )
				)
				( attribute "XY" "(-5925,1725)"
					( Origin gFrontEnd )
				)
				( attribute "CHIPS_PART_NAME" "CAP"
					( Origin gPackager )
				)
				( attribute "CDS_PART_NAME" "CAP_0402-0.22UF,16V,10%,X7R,A3A"
					( Origin gPackager )
				)
				( objectStatus "C831" )
				( pin "a"
					( attribute "PN" "1"
						( Origin gPackager )
					)
					( objectStatus "C831.1" )
				)
				( pin "b"
					( attribute "PN" "2"
						( Origin gPackager )
					)
					( objectStatus "C831.2" )
				)
			)
			( gate "@baseboard_fab2_lib.baseboard_fab2(sch_1):page244_i5"
				( attribute "CDS_LIB" "mstr_discrete"
					( Origin gPackager )
				)
				( attribute "CDS_LOCATION" "C829"
					( Origin gPackager )
				)
				( attribute "CDS_SEC" "1"
					( Origin gPackager )
				)
				( attribute "LOCATION" "C829"
					( Origin gPackager )
				)
				( attribute "MATERIAL" "X7R"
					( Origin gFrontEnd )
				)
				( attribute "PACK_TYPE" "0402"
					( Origin gFrontEnd )
				)
				( attribute "PART_NUMBER" "A36096-155"
					( Origin gFrontEnd )
				)
				( attribute "PHYS_PAGE" "244"
					( Origin gFrontEnd )
				)
				( attribute "ROOM" "OCP_STEERING"
					( Origin gFrontEnd )
				)
				( attribute "ROT" "2"
					( Origin gFrontEnd )
				)
				( attribute "SEC" "1"
					( Origin gPackager )
				)
				( attribute "TOLERANCE" "10%"
					( Origin gFrontEnd )
				)
				( attribute "VALUE" "0.22UF"
					( Origin gFrontEnd )
				)
				( attribute "VER" "1"
					( Origin gFrontEnd )
				)
				( attribute "VOLTAGE" "16V"
					( Units "uVoltage" "V" 1.000000)
					( Origin gFrontEnd )
				)
				( attribute "XY" "(-5525,1725)"
					( Origin gFrontEnd )
				)
				( attribute "CHIPS_PART_NAME" "CAP"
					( Origin gPackager )
				)
				( attribute "CDS_PART_NAME" "CAP_0402-0.22UF,16V,10%,X7R,A3A"
					( Origin gPackager )
				)
				( objectStatus "C829" )
				( pin "a"
					( attribute "PN" "1"
						( Origin gPackager )
					)
					( objectStatus "C829.1" )
				)
				( pin "b"
					( attribute "PN" "2"
						( Origin gPackager )
					)
					( objectStatus "C829.2" )
				)
			)
			( gate "@baseboard_fab2_lib.baseboard_fab2(sch_1):page244_i8"
				( attribute "CDS_LIB" "mstr_discrete"
					( Origin gPackager )
				)
				( attribute "CDS_LOCATION" "C833"
					( Origin gPackager )
				)
				( attribute "CDS_SEC" "1"
					( Origin gPackager )
				)
				( attribute "LOCATION" "C833"
					( Origin gPackager )
				)
				( attribute "MATERIAL" "X7R"
					( Origin gFrontEnd )
				)
				( attribute "PACK_TYPE" "0402"
					( Origin gFrontEnd )
				)
				( attribute "PART_NUMBER" "A36096-155"
					( Origin gFrontEnd )
				)
				( attribute "PHYS_PAGE" "244"
					( Origin gFrontEnd )
				)
				( attribute "ROOM" "OCP_STEERING"
					( Origin gFrontEnd )
				)
				( attribute "ROT" "2"
					( Origin gFrontEnd )
				)
				( attribute "SEC" "1"
					( Origin gPackager )
				)
				( attribute "TOLERANCE" "10%"
					( Origin gFrontEnd )
				)
				( attribute "VALUE" "0.22UF"
					( Origin gFrontEnd )
				)
				( attribute "VER" "1"
					( Origin gFrontEnd )
				)
				( attribute "VOLTAGE" "16V"
					( Units "uVoltage" "V" 1.000000)
					( Origin gFrontEnd )
				)
				( attribute "XY" "(-5125,1725)"
					( Origin gFrontEnd )
				)
				( attribute "CHIPS_PART_NAME" "CAP"
					( Origin gPackager )
				)
				( attribute "CDS_PART_NAME" "CAP_0402-0.22UF,16V,10%,X7R,A3A"
					( Origin gPackager )
				)
				( objectStatus "C833" )
				( pin "a"
					( attribute "PN" "1"
						( Origin gPackager )
					)
					( objectStatus "C833.1" )
				)
				( pin "b"
					( attribute "PN" "2"
						( Origin gPackager )
					)
					( objectStatus "C833.2" )
				)
			)
			( gate "@baseboard_fab2_lib.baseboard_fab2(sch_1):page244_i12"
				( attribute "CDS_LIB" "mstr_discrete"
					( Origin gPackager )
				)
				( attribute "CDS_LOCATION" "C827"
					( Origin gPackager )
				)
				( attribute "CDS_SEC" "1"
					( Origin gPackager )
				)
				( attribute "LOCATION" "C827"
					( Origin gPackager )
				)
				( attribute "MATERIAL" "X7R"
					( Origin gFrontEnd )
				)
				( attribute "PACK_TYPE" "0402"
					( Origin gFrontEnd )
				)
				( attribute "PART_NUMBER" "A36096-155"
					( Origin gFrontEnd )
				)
				( attribute "PHYS_PAGE" "244"
					( Origin gFrontEnd )
				)
				( attribute "ROOM" "OCP_STEERING"
					( Origin gFrontEnd )
				)
				( attribute "ROT" "2"
					( Origin gFrontEnd )
				)
				( attribute "SEC" "1"
					( Origin gPackager )
				)
				( attribute "TOLERANCE" "10%"
					( Origin gFrontEnd )
				)
				( attribute "VALUE" "0.22UF"
					( Origin gFrontEnd )
				)
				( attribute "VER" "1"
					( Origin gFrontEnd )
				)
				( attribute "VOLTAGE" "16V"
					( Units "uVoltage" "V" 1.000000)
					( Origin gFrontEnd )
				)
				( attribute "XY" "(-5725,2025)"
					( Origin gFrontEnd )
				)
				( attribute "CHIPS_PART_NAME" "CAP"
					( Origin gPackager )
				)
				( attribute "CDS_PART_NAME" "CAP_0402-0.22UF,16V,10%,X7R,A3A"
					( Origin gPackager )
				)
				( objectStatus "C827" )
				( pin "a"
					( attribute "PN" "1"
						( Origin gPackager )
					)
					( objectStatus "C827.1" )
				)
				( pin "b"
					( attribute "PN" "2"
						( Origin gPackager )
					)
					( objectStatus "C827.2" )
				)
			)
			( gate "@baseboard_fab2_lib.baseboard_fab2(sch_1):page244_i17"
				( attribute "CDS_LIB" "mstr_discrete"
					( Origin gPackager )
				)
				( attribute "CDS_LOCATION" "C841"
					( Origin gPackager )
				)
				( attribute "CDS_SEC" "1"
					( Origin gPackager )
				)
				( attribute "LOCATION" "C841"
					( Origin gPackager )
				)
				( attribute "MATERIAL" "X7R"
					( Origin gFrontEnd )
				)
				( attribute "PACK_TYPE" "0402"
					( Origin gFrontEnd )
				)
				( attribute "PART_NUMBER" "A36096-155"
					( Origin gFrontEnd )
				)
				( attribute "PHYS_PAGE" "244"
					( Origin gFrontEnd )
				)
				( attribute "ROOM" "OCP_STEERING"
					( Origin gFrontEnd )
				)
				( attribute "ROT" "2"
					( Origin gFrontEnd )
				)
				( attribute "SEC" "1"
					( Origin gPackager )
				)
				( attribute "TOLERANCE" "10%"
					( Origin gFrontEnd )
				)
				( attribute "VALUE" "0.22UF"
					( Origin gFrontEnd )
				)
				( attribute "VER" "1"
					( Origin gFrontEnd )
				)
				( attribute "VOLTAGE" "16V"
					( Units "uVoltage" "V" 1.000000)
					( Origin gFrontEnd )
				)
				( attribute "XY" "(-5325,2025)"
					( Origin gFrontEnd )
				)
				( attribute "CHIPS_PART_NAME" "CAP"
					( Origin gPackager )
				)
				( attribute "CDS_PART_NAME" "CAP_0402-0.22UF,16V,10%,X7R,A3A"
					( Origin gPackager )
				)
				( objectStatus "C841" )
				( pin "a"
					( attribute "PN" "1"
						( Origin gPackager )
					)
					( objectStatus "C841.1" )
				)
				( pin "b"
					( attribute "PN" "2"
						( Origin gPackager )
					)
					( objectStatus "C841.2" )
				)
			)
			( gate "@baseboard_fab2_lib.baseboard_fab2(sch_1):page244_i23"
				( attribute "CDS_LIB" "mstr_discrete"
					( Origin gPackager )
				)
				( attribute "CDS_LOCATION" "C830"
					( Origin gPackager )
				)
				( attribute "CDS_SEC" "1"
					( Origin gPackager )
				)
				( attribute "LOCATION" "C830"
					( Origin gPackager )
				)
				( attribute "MATERIAL" "X7R"
					( Origin gFrontEnd )
				)
				( attribute "PACK_TYPE" "0402"
					( Origin gFrontEnd )
				)
				( attribute "PART_NUMBER" "A36096-155"
					( Origin gFrontEnd )
				)
				( attribute "PHYS_PAGE" "244"
					( Origin gFrontEnd )
				)
				( attribute "ROOM" "OCP_STEERING"
					( Origin gFrontEnd )
				)
				( attribute "ROT" "2"
					( Origin gFrontEnd )
				)
				( attribute "SEC" "1"
					( Origin gPackager )
				)
				( attribute "TOLERANCE" "10%"
					( Origin gFrontEnd )
				)
				( attribute "VALUE" "0.22UF"
					( Origin gFrontEnd )
				)
				( attribute "VER" "1"
					( Origin gFrontEnd )
				)
				( attribute "VOLTAGE" "16V"
					( Units "uVoltage" "V" 1.000000)
					( Origin gFrontEnd )
				)
				( attribute "XY" "(-6025,3025)"
					( Origin gFrontEnd )
				)
				( attribute "CHIPS_PART_NAME" "CAP"
					( Origin gPackager )
				)
				( attribute "CDS_PART_NAME" "CAP_0402-0.22UF,16V,10%,X7R,A3A"
					( Origin gPackager )
				)
				( objectStatus "C830" )
				( pin "a"
					( attribute "PN" "1"
						( Origin gPackager )
					)
					( objectStatus "C830.1" )
				)
				( pin "b"
					( attribute "PN" "2"
						( Origin gPackager )
					)
					( objectStatus "C830.2" )
				)
			)
			( gate "@baseboard_fab2_lib.baseboard_fab2(sch_1):page244_i24"
				( attribute "CDS_LIB" "mstr_discrete"
					( Origin gPackager )
				)
				( attribute "CDS_LOCATION" "C826"
					( Origin gPackager )
				)
				( attribute "CDS_SEC" "1"
					( Origin gPackager )
				)
				( attribute "LOCATION" "C826"
					( Origin gPackager )
				)
				( attribute "MATERIAL" "X7R"
					( Origin gFrontEnd )
				)
				( attribute "PACK_TYPE" "0402"
					( Origin gFrontEnd )
				)
				( attribute "PART_NUMBER" "A36096-155"
					( Origin gFrontEnd )
				)
				( attribute "PHYS_PAGE" "244"
					( Origin gFrontEnd )
				)
				( attribute "ROOM" "OCP_STEERING"
					( Origin gFrontEnd )
				)
				( attribute "ROT" "2"
					( Origin gFrontEnd )
				)
				( attribute "SEC" "1"
					( Origin gPackager )
				)
				( attribute "TOLERANCE" "10%"
					( Origin gFrontEnd )
				)
				( attribute "VALUE" "0.22UF"
					( Origin gFrontEnd )
				)
				( attribute "VER" "1"
					( Origin gFrontEnd )
				)
				( attribute "VOLTAGE" "16V"
					( Units "uVoltage" "V" 1.000000)
					( Origin gFrontEnd )
				)
				( attribute "XY" "(-5825,3325)"
					( Origin gFrontEnd )
				)
				( attribute "CHIPS_PART_NAME" "CAP"
					( Origin gPackager )
				)
				( attribute "CDS_PART_NAME" "CAP_0402-0.22UF,16V,10%,X7R,A3A"
					( Origin gPackager )
				)
				( objectStatus "C826" )
				( pin "a"
					( attribute "PN" "1"
						( Origin gPackager )
					)
					( objectStatus "C826.1" )
				)
				( pin "b"
					( attribute "PN" "2"
						( Origin gPackager )
					)
					( objectStatus "C826.2" )
				)
			)
			( gate "@baseboard_fab2_lib.baseboard_fab2(sch_1):page244_i28"
				( attribute "CDS_LIB" "mstr_discrete"
					( Origin gPackager )
				)
				( attribute "CDS_LOCATION" "C828"
					( Origin gPackager )
				)
				( attribute "CDS_SEC" "1"
					( Origin gPackager )
				)
				( attribute "LOCATION" "C828"
					( Origin gPackager )
				)
				( attribute "MATERIAL" "X7R"
					( Origin gFrontEnd )
				)
				( attribute "PACK_TYPE" "0402"
					( Origin gFrontEnd )
				)
				( attribute "PART_NUMBER" "A36096-155"
					( Origin gFrontEnd )
				)
				( attribute "PHYS_PAGE" "244"
					( Origin gFrontEnd )
				)
				( attribute "ROOM" "OCP_STEERING"
					( Origin gFrontEnd )
				)
				( attribute "ROT" "2"
					( Origin gFrontEnd )
				)
				( attribute "SEC" "1"
					( Origin gPackager )
				)
				( attribute "TOLERANCE" "10%"
					( Origin gFrontEnd )
				)
				( attribute "VALUE" "0.22UF"
					( Origin gFrontEnd )
				)
				( attribute "VER" "1"
					( Origin gFrontEnd )
				)
				( attribute "VOLTAGE" "16V"
					( Units "uVoltage" "V" 1.000000)
					( Origin gFrontEnd )
				)
				( attribute "XY" "(-5625,3025)"
					( Origin gFrontEnd )
				)
				( attribute "CHIPS_PART_NAME" "CAP"
					( Origin gPackager )
				)
				( attribute "CDS_PART_NAME" "CAP_0402-0.22UF,16V,10%,X7R,A3A"
					( Origin gPackager )
				)
				( objectStatus "C828" )
				( pin "a"
					( attribute "PN" "1"
						( Origin gPackager )
					)
					( objectStatus "C828.1" )
				)
				( pin "b"
					( attribute "PN" "2"
						( Origin gPackager )
					)
					( objectStatus "C828.2" )
				)
			)
			( gate "@baseboard_fab2_lib.baseboard_fab2(sch_1):page244_i29"
				( attribute "CDS_LIB" "mstr_discrete"
					( Origin gPackager )
				)
				( attribute "CDS_LOCATION" "C840"
					( Origin gPackager )
				)
				( attribute "CDS_SEC" "1"
					( Origin gPackager )
				)
				( attribute "LOCATION" "C840"
					( Origin gPackager )
				)
				( attribute "MATERIAL" "X7R"
					( Origin gFrontEnd )
				)
				( attribute "PACK_TYPE" "0402"
					( Origin gFrontEnd )
				)
				( attribute "PART_NUMBER" "A36096-155"
					( Origin gFrontEnd )
				)
				( attribute "PHYS_PAGE" "244"
					( Origin gFrontEnd )
				)
				( attribute "ROOM" "OCP_STEERING"
					( Origin gFrontEnd )
				)
				( attribute "ROT" "2"
					( Origin gFrontEnd )
				)
				( attribute "SEC" "1"
					( Origin gPackager )
				)
				( attribute "TOLERANCE" "10%"
					( Origin gFrontEnd )
				)
				( attribute "VALUE" "0.22UF"
					( Origin gFrontEnd )
				)
				( attribute "VER" "1"
					( Origin gFrontEnd )
				)
				( attribute "VOLTAGE" "16V"
					( Units "uVoltage" "V" 1.000000)
					( Origin gFrontEnd )
				)
				( attribute "XY" "(-5425,3325)"
					( Origin gFrontEnd )
				)
				( attribute "CHIPS_PART_NAME" "CAP"
					( Origin gPackager )
				)
				( attribute "CDS_PART_NAME" "CAP_0402-0.22UF,16V,10%,X7R,A3A"
					( Origin gPackager )
				)
				( objectStatus "C840" )
				( pin "a"
					( attribute "PN" "1"
						( Origin gPackager )
					)
					( objectStatus "C840.1" )
				)
				( pin "b"
					( attribute "PN" "2"
						( Origin gPackager )
					)
					( objectStatus "C840.2" )
				)
			)
			( gate "@baseboard_fab2_lib.baseboard_fab2(sch_1):page244_i30"
				( attribute "CDS_LIB" "mstr_discrete"
					( Origin gPackager )
				)
				( attribute "CDS_LOCATION" "C832"
					( Origin gPackager )
				)
				( attribute "CDS_SEC" "1"
					( Origin gPackager )
				)
				( attribute "LOCATION" "C832"
					( Origin gPackager )
				)
				( attribute "MATERIAL" "X7R"
					( Origin gFrontEnd )
				)
				( attribute "PACK_TYPE" "0402"
					( Origin gFrontEnd )
				)
				( attribute "PART_NUMBER" "A36096-155"
					( Origin gFrontEnd )
				)
				( attribute "PHYS_PAGE" "244"
					( Origin gFrontEnd )
				)
				( attribute "ROOM" "OCP_STEERING"
					( Origin gFrontEnd )
				)
				( attribute "ROT" "2"
					( Origin gFrontEnd )
				)
				( attribute "SEC" "1"
					( Origin gPackager )
				)
				( attribute "TOLERANCE" "10%"
					( Origin gFrontEnd )
				)
				( attribute "VALUE" "0.22UF"
					( Origin gFrontEnd )
				)
				( attribute "VER" "1"
					( Origin gFrontEnd )
				)
				( attribute "VOLTAGE" "16V"
					( Units "uVoltage" "V" 1.000000)
					( Origin gFrontEnd )
				)
				( attribute "XY" "(-5225,3025)"
					( Origin gFrontEnd )
				)
				( attribute "CHIPS_PART_NAME" "CAP"
					( Origin gPackager )
				)
				( attribute "CDS_PART_NAME" "CAP_0402-0.22UF,16V,10%,X7R,A3A"
					( Origin gPackager )
				)
				( objectStatus "C832" )
				( pin "a"
					( attribute "PN" "1"
						( Origin gPackager )
					)
					( objectStatus "C832.1" )
				)
				( pin "b"
					( attribute "PN" "2"
						( Origin gPackager )
					)
					( objectStatus "C832.2" )
				)
			)
			( gate "@baseboard_fab2_lib.baseboard_fab2(sch_1):page244_i35"
				( attribute "CDS_LIB" "mstr_discrete"
					( Origin gPackager )
				)
				( attribute "CDS_LOCATION" "C845"
					( Origin gPackager )
				)
				( attribute "CDS_SEC" "1"
					( Origin gPackager )
				)
				( attribute "LOCATION" "C845"
					( Origin gPackager )
				)
				( attribute "MATERIAL" "X7R"
					( Origin gFrontEnd )
				)
				( attribute "PACK_TYPE" "0402"
					( Origin gFrontEnd )
				)
				( attribute "PART_NUMBER" "A36096-155"
					( Origin gFrontEnd )
				)
				( attribute "PHYS_PAGE" "244"
					( Origin gFrontEnd )
				)
				( attribute "ROOM" "OCP_STEERING"
					( Origin gFrontEnd )
				)
				( attribute "ROT" "2"
					( Origin gFrontEnd )
				)
				( attribute "SEC" "1"
					( Origin gPackager )
				)
				( attribute "TOLERANCE" "10%"
					( Origin gFrontEnd )
				)
				( attribute "VALUE" "0.22UF"
					( Origin gFrontEnd )
				)
				( attribute "VER" "1"
					( Origin gFrontEnd )
				)
				( attribute "VOLTAGE" "16V"
					( Units "uVoltage" "V" 1.000000)
					( Origin gFrontEnd )
				)
				( attribute "XY" "(-4725,1725)"
					( Origin gFrontEnd )
				)
				( attribute "CHIPS_PART_NAME" "CAP"
					( Origin gPackager )
				)
				( attribute "CDS_PART_NAME" "CAP_0402-0.22UF,16V,10%,X7R,A3A"
					( Origin gPackager )
				)
				( objectStatus "C845" )
				( pin "a"
					( attribute "PN" "1"
						( Origin gPackager )
					)
					( objectStatus "C845.1" )
				)
				( pin "b"
					( attribute "PN" "2"
						( Origin gPackager )
					)
					( objectStatus "C845.2" )
				)
			)
			( gate "@baseboard_fab2_lib.baseboard_fab2(sch_1):page244_i39"
				( attribute "CDS_LIB" "mstr_discrete"
					( Origin gPackager )
				)
				( attribute "CDS_LOCATION" "R767"
					( Origin gPackager )
				)
				( attribute "CDS_SEC" "1"
					( Origin gPackager )
				)
				( attribute "LOCATION" "R767"
					( Origin gPackager )
				)
				( attribute "MATERIAL" "CHIP"
					( Origin gFrontEnd )
				)
				( attribute "PACK_TYPE" "0402"
					( Origin gFrontEnd )
				)
				( attribute "PART_NUMBER" "G21497-005"
					( Origin gFrontEnd )
				)
				( attribute "PHYS_PAGE" "244"
					( Origin gFrontEnd )
				)
				( attribute "ROOM" "PCIE_STEERING"
					( Origin gFrontEnd )
				)
				( attribute "ROT" "0"
					( Origin gFrontEnd )
				)
				( attribute "SEC" "1"
					( Origin gPackager )
				)
				( attribute "TOLERANCE" "5%"
					( Origin gFrontEnd )
				)
				( attribute "VALUE" "0.0"
					( Origin gFrontEnd )
				)
				( attribute "VER" "2"
					( Origin gFrontEnd )
				)
				( attribute "WATTAGE" "1/16W"
					( Origin gFrontEnd )
				)
				( attribute "XY" "(-3425,1725)"
					( Origin gFrontEnd )
				)
				( attribute "CHIPS_PART_NAME" "RES"
					( Origin gPackager )
				)
				( attribute "CDS_PART_NAME" "RES_0402-0.0,5%,1/16W,CHIP,G21A"
					( Origin gPackager )
				)
				( objectStatus "R767" )
				( pin "a"
					( attribute "PN" "1"
						( Origin gPackager )
					)
					( objectStatus "R767.1" )
				)
				( pin "b"
					( attribute "PN" "2"
						( Origin gPackager )
					)
					( objectStatus "R767.2" )
				)
			)
			( gate "@baseboard_fab2_lib.baseboard_fab2(sch_1):page244_i41"
				( attribute "CDS_LIB" "mstr_discrete"
					( Origin gPackager )
				)
				( attribute "CDS_LOCATION" "C835"
					( Origin gPackager )
				)
				( attribute "CDS_SEC" "1"
					( Origin gPackager )
				)
				( attribute "LOCATION" "C835"
					( Origin gPackager )
				)
				( attribute "MATERIAL" "X7R"
					( Origin gFrontEnd )
				)
				( attribute "PACK_TYPE" "0402"
					( Origin gFrontEnd )
				)
				( attribute "PART_NUMBER" "A36096-155"
					( Origin gFrontEnd )
				)
				( attribute "PHYS_PAGE" "244"
					( Origin gFrontEnd )
				)
				( attribute "ROOM" "OCP_STEERING"
					( Origin gFrontEnd )
				)
				( attribute "ROT" "2"
					( Origin gFrontEnd )
				)
				( attribute "SEC" "1"
					( Origin gPackager )
				)
				( attribute "TOLERANCE" "10%"
					( Origin gFrontEnd )
				)
				( attribute "VALUE" "0.22UF"
					( Origin gFrontEnd )
				)
				( attribute "VER" "1"
					( Origin gFrontEnd )
				)
				( attribute "VOLTAGE" "16V"
					( Units "uVoltage" "V" 1.000000)
					( Origin gFrontEnd )
				)
				( attribute "XY" "(-4925,2025)"
					( Origin gFrontEnd )
				)
				( attribute "CHIPS_PART_NAME" "CAP"
					( Origin gPackager )
				)
				( attribute "CDS_PART_NAME" "CAP_0402-0.22UF,16V,10%,X7R,A3A"
					( Origin gPackager )
				)
				( objectStatus "C835" )
				( pin "a"
					( attribute "PN" "1"
						( Origin gPackager )
					)
					( objectStatus "C835.1" )
				)
				( pin "b"
					( attribute "PN" "2"
						( Origin gPackager )
					)
					( objectStatus "C835.2" )
				)
			)
			( gate "@baseboard_fab2_lib.baseboard_fab2(sch_1):page244_i47"
				( attribute "CDS_LIB" "mstr_discrete"
					( Origin gPackager )
				)
				( attribute "CDS_LOCATION" "C843"
					( Origin gPackager )
				)
				( attribute "CDS_SEC" "1"
					( Origin gPackager )
				)
				( attribute "LOCATION" "C843"
					( Origin gPackager )
				)
				( attribute "MATERIAL" "X7R"
					( Origin gFrontEnd )
				)
				( attribute "PACK_TYPE" "0402"
					( Origin gFrontEnd )
				)
				( attribute "PART_NUMBER" "A36096-155"
					( Origin gFrontEnd )
				)
				( attribute "PHYS_PAGE" "244"
					( Origin gFrontEnd )
				)
				( attribute "ROOM" "OCP_STEERING"
					( Origin gFrontEnd )
				)
				( attribute "ROT" "2"
					( Origin gFrontEnd )
				)
				( attribute "SEC" "1"
					( Origin gPackager )
				)
				( attribute "TOLERANCE" "10%"
					( Origin gFrontEnd )
				)
				( attribute "VALUE" "0.22UF"
					( Origin gFrontEnd )
				)
				( attribute "VER" "1"
					( Origin gFrontEnd )
				)
				( attribute "VOLTAGE" "16V"
					( Units "uVoltage" "V" 1.000000)
					( Origin gFrontEnd )
				)
				( attribute "XY" "(-4525,2025)"
					( Origin gFrontEnd )
				)
				( attribute "CHIPS_PART_NAME" "CAP"
					( Origin gPackager )
				)
				( attribute "CDS_PART_NAME" "CAP_0402-0.22UF,16V,10%,X7R,A3A"
					( Origin gPackager )
				)
				( objectStatus "C843" )
				( pin "a"
					( attribute "PN" "1"
						( Origin gPackager )
					)
					( objectStatus "C843.1" )
				)
				( pin "b"
					( attribute "PN" "2"
						( Origin gPackager )
					)
					( objectStatus "C843.2" )
				)
			)
			( gate "@baseboard_fab2_lib.baseboard_fab2(sch_1):page244_i50"
				( attribute "CDS_LIB" "mstr_discrete"
					( Origin gPackager )
				)
				( attribute "CDS_LOCATION" "C834"
					( Origin gPackager )
				)
				( attribute "CDS_SEC" "1"
					( Origin gPackager )
				)
				( attribute "LOCATION" "C834"
					( Origin gPackager )
				)
				( attribute "MATERIAL" "X7R"
					( Origin gFrontEnd )
				)
				( attribute "PACK_TYPE" "0402"
					( Origin gFrontEnd )
				)
				( attribute "PART_NUMBER" "A36096-155"
					( Origin gFrontEnd )
				)
				( attribute "PHYS_PAGE" "244"
					( Origin gFrontEnd )
				)
				( attribute "ROOM" "OCP_STEERING"
					( Origin gFrontEnd )
				)
				( attribute "ROT" "2"
					( Origin gFrontEnd )
				)
				( attribute "SEC" "1"
					( Origin gPackager )
				)
				( attribute "TOLERANCE" "10%"
					( Origin gFrontEnd )
				)
				( attribute "VALUE" "0.22UF"
					( Origin gFrontEnd )
				)
				( attribute "VER" "1"
					( Origin gFrontEnd )
				)
				( attribute "VOLTAGE" "16V"
					( Units "uVoltage" "V" 1.000000)
					( Origin gFrontEnd )
				)
				( attribute "XY" "(-5025,3325)"
					( Origin gFrontEnd )
				)
				( attribute "CHIPS_PART_NAME" "CAP"
					( Origin gPackager )
				)
				( attribute "CDS_PART_NAME" "CAP_0402-0.22UF,16V,10%,X7R,A3A"
					( Origin gPackager )
				)
				( objectStatus "C834" )
				( pin "a"
					( attribute "PN" "1"
						( Origin gPackager )
					)
					( objectStatus "C834.1" )
				)
				( pin "b"
					( attribute "PN" "2"
						( Origin gPackager )
					)
					( objectStatus "C834.2" )
				)
			)
			( gate "@baseboard_fab2_lib.baseboard_fab2(sch_1):page244_i51"
				( attribute "CDS_LIB" "mstr_discrete"
					( Origin gPackager )
				)
				( attribute "CDS_LOCATION" "C844"
					( Origin gPackager )
				)
				( attribute "CDS_SEC" "1"
					( Origin gPackager )
				)
				( attribute "LOCATION" "C844"
					( Origin gPackager )
				)
				( attribute "MATERIAL" "X7R"
					( Origin gFrontEnd )
				)
				( attribute "PACK_TYPE" "0402"
					( Origin gFrontEnd )
				)
				( attribute "PART_NUMBER" "A36096-155"
					( Origin gFrontEnd )
				)
				( attribute "PHYS_PAGE" "244"
					( Origin gFrontEnd )
				)
				( attribute "ROOM" "OCP_STEERING"
					( Origin gFrontEnd )
				)
				( attribute "ROT" "2"
					( Origin gFrontEnd )
				)
				( attribute "SEC" "1"
					( Origin gPackager )
				)
				( attribute "TOLERANCE" "10%"
					( Origin gFrontEnd )
				)
				( attribute "VALUE" "0.22UF"
					( Origin gFrontEnd )
				)
				( attribute "VER" "1"
					( Origin gFrontEnd )
				)
				( attribute "VOLTAGE" "16V"
					( Units "uVoltage" "V" 1.000000)
					( Origin gFrontEnd )
				)
				( attribute "XY" "(-4825,3025)"
					( Origin gFrontEnd )
				)
				( attribute "CHIPS_PART_NAME" "CAP"
					( Origin gPackager )
				)
				( attribute "CDS_PART_NAME" "CAP_0402-0.22UF,16V,10%,X7R,A3A"
					( Origin gPackager )
				)
				( objectStatus "C844" )
				( pin "a"
					( attribute "PN" "1"
						( Origin gPackager )
					)
					( objectStatus "C844.1" )
				)
				( pin "b"
					( attribute "PN" "2"
						( Origin gPackager )
					)
					( objectStatus "C844.2" )
				)
			)
			( gate "@baseboard_fab2_lib.baseboard_fab2(sch_1):page244_i52"
				( attribute "CDS_LIB" "mstr_discrete"
					( Origin gPackager )
				)
				( attribute "CDS_LOCATION" "C842"
					( Origin gPackager )
				)
				( attribute "CDS_SEC" "1"
					( Origin gPackager )
				)
				( attribute "LOCATION" "C842"
					( Origin gPackager )
				)
				( attribute "MATERIAL" "X7R"
					( Origin gFrontEnd )
				)
				( attribute "PACK_TYPE" "0402"
					( Origin gFrontEnd )
				)
				( attribute "PART_NUMBER" "A36096-155"
					( Origin gFrontEnd )
				)
				( attribute "PHYS_PAGE" "244"
					( Origin gFrontEnd )
				)
				( attribute "ROOM" "OCP_STEERING"
					( Origin gFrontEnd )
				)
				( attribute "ROT" "2"
					( Origin gFrontEnd )
				)
				( attribute "SEC" "1"
					( Origin gPackager )
				)
				( attribute "TOLERANCE" "10%"
					( Origin gFrontEnd )
				)
				( attribute "VALUE" "0.22UF"
					( Origin gFrontEnd )
				)
				( attribute "VER" "1"
					( Origin gFrontEnd )
				)
				( attribute "VOLTAGE" "16V"
					( Units "uVoltage" "V" 1.000000)
					( Origin gFrontEnd )
				)
				( attribute "XY" "(-4625,3300)"
					( Origin gFrontEnd )
				)
				( attribute "CHIPS_PART_NAME" "CAP"
					( Origin gPackager )
				)
				( attribute "CDS_PART_NAME" "CAP_0402-0.22UF,16V,10%,X7R,A3A"
					( Origin gPackager )
				)
				( objectStatus "C842" )
				( pin "a"
					( attribute "PN" "1"
						( Origin gPackager )
					)
					( objectStatus "C842.1" )
				)
				( pin "b"
					( attribute "PN" "2"
						( Origin gPackager )
					)
					( objectStatus "C842.2" )
				)
			)
			( gate "@baseboard_fab2_lib.baseboard_fab2(sch_1):page244_i58"
				( attribute "CDS_LIB" "mstr_discrete"
					( Origin gPackager )
				)
				( attribute "CDS_LOCATION" "R769"
					( Origin gPackager )
				)
				( attribute "CDS_SEC" "1"
					( Origin gPackager )
				)
				( attribute "LOCATION" "R769"
					( Origin gPackager )
				)
				( attribute "MATERIAL" "CHIP"
					( Origin gFrontEnd )
				)
				( attribute "PACK_TYPE" "0402"
					( Origin gFrontEnd )
				)
				( attribute "PART_NUMBER" "G21497-005"
					( Origin gFrontEnd )
				)
				( attribute "PHYS_PAGE" "244"
					( Origin gFrontEnd )
				)
				( attribute "ROOM" "PCIE_STEERING"
					( Origin gFrontEnd )
				)
				( attribute "ROT" "0"
					( Origin gFrontEnd )
				)
				( attribute "SEC" "1"
					( Origin gPackager )
				)
				( attribute "TOLERANCE" "5%"
					( Origin gFrontEnd )
				)
				( attribute "VALUE" "0.0"
					( Origin gFrontEnd )
				)
				( attribute "VER" "2"
					( Origin gFrontEnd )
				)
				( attribute "WATTAGE" "1/16W"
					( Origin gFrontEnd )
				)
				( attribute "XY" "(-3225,2025)"
					( Origin gFrontEnd )
				)
				( attribute "CHIPS_PART_NAME" "RES"
					( Origin gPackager )
				)
				( attribute "CDS_PART_NAME" "RES_0402-0.0,5%,1/16W,CHIP,G21A"
					( Origin gPackager )
				)
				( objectStatus "R769" )
				( pin "a"
					( attribute "PN" "1"
						( Origin gPackager )
					)
					( objectStatus "R769.1" )
				)
				( pin "b"
					( attribute "PN" "2"
						( Origin gPackager )
					)
					( objectStatus "R769.2" )
				)
			)
			( gate "@baseboard_fab2_lib.baseboard_fab2(sch_1):page244_i64"
				( attribute "CDS_LIB" "mstr_discrete"
					( Origin gPackager )
				)
				( attribute "CDS_LOCATION" "R760"
					( Origin gPackager )
				)
				( attribute "CDS_SEC" "1"
					( Origin gPackager )
				)
				( attribute "LOCATION" "R760"
					( Origin gPackager )
				)
				( attribute "MATERIAL" "CHIP"
					( Origin gFrontEnd )
				)
				( attribute "PACK_TYPE" "0402"
					( Origin gFrontEnd )
				)
				( attribute "PART_NUMBER" "G21497-005"
					( Origin gFrontEnd )
				)
				( attribute "PHYS_PAGE" "244"
					( Origin gFrontEnd )
				)
				( attribute "ROOM" "PCIE_STEERING"
					( Origin gFrontEnd )
				)
				( attribute "ROT" "0"
					( Origin gFrontEnd )
				)
				( attribute "SEC" "1"
					( Origin gPackager )
				)
				( attribute "TOLERANCE" "5%"
					( Origin gFrontEnd )
				)
				( attribute "VALUE" "0.0"
					( Origin gFrontEnd )
				)
				( attribute "VER" "2"
					( Origin gFrontEnd )
				)
				( attribute "WATTAGE" "1/16W"
					( Origin gFrontEnd )
				)
				( attribute "XY" "(-3500,3025)"
					( Origin gFrontEnd )
				)
				( attribute "CHIPS_PART_NAME" "RES"
					( Origin gPackager )
				)
				( attribute "CDS_PART_NAME" "RES_0402-0.0,5%,1/16W,CHIP,G21A"
					( Origin gPackager )
				)
				( objectStatus "R760" )
				( pin "a"
					( attribute "PN" "1"
						( Origin gPackager )
					)
					( objectStatus "R760.1" )
				)
				( pin "b"
					( attribute "PN" "2"
						( Origin gPackager )
					)
					( objectStatus "R760.2" )
				)
			)
			( gate "@baseboard_fab2_lib.baseboard_fab2(sch_1):page244_i65"
				( attribute "CDS_LIB" "mstr_discrete"
					( Origin gPackager )
				)
				( attribute "CDS_LOCATION" "R771"
					( Origin gPackager )
				)
				( attribute "CDS_SEC" "1"
					( Origin gPackager )
				)
				( attribute "LOCATION" "R771"
					( Origin gPackager )
				)
				( attribute "MATERIAL" "CHIP"
					( Origin gFrontEnd )
				)
				( attribute "PACK_TYPE" "0402"
					( Origin gFrontEnd )
				)
				( attribute "PART_NUMBER" "G21497-005"
					( Origin gFrontEnd )
				)
				( attribute "PHYS_PAGE" "244"
					( Origin gFrontEnd )
				)
				( attribute "ROOM" "PCIE_STEERING"
					( Origin gFrontEnd )
				)
				( attribute "ROT" "0"
					( Origin gFrontEnd )
				)
				( attribute "SEC" "1"
					( Origin gPackager )
				)
				( attribute "TOLERANCE" "5%"
					( Origin gFrontEnd )
				)
				( attribute "VALUE" "0.0"
					( Origin gFrontEnd )
				)
				( attribute "VER" "2"
					( Origin gFrontEnd )
				)
				( attribute "WATTAGE" "1/16W"
					( Origin gFrontEnd )
				)
				( attribute "XY" "(-3100,3025)"
					( Origin gFrontEnd )
				)
				( attribute "CHIPS_PART_NAME" "RES"
					( Origin gPackager )
				)
				( attribute "CDS_PART_NAME" "RES_0402-0.0,5%,1/16W,CHIP,G21A"
					( Origin gPackager )
				)
				( objectStatus "R771" )
				( pin "a"
					( attribute "PN" "1"
						( Origin gPackager )
					)
					( objectStatus "R771.1" )
				)
				( pin "b"
					( attribute "PN" "2"
						( Origin gPackager )
					)
					( objectStatus "R771.2" )
				)
			)
			( gate "@baseboard_fab2_lib.baseboard_fab2(sch_1):page244_i66"
				( attribute "CDS_LIB" "mstr_discrete"
					( Origin gPackager )
				)
				( attribute "CDS_LOCATION" "R768"
					( Origin gPackager )
				)
				( attribute "CDS_SEC" "1"
					( Origin gPackager )
				)
				( attribute "LOCATION" "R768"
					( Origin gPackager )
				)
				( attribute "MATERIAL" "CHIP"
					( Origin gFrontEnd )
				)
				( attribute "PACK_TYPE" "0402"
					( Origin gFrontEnd )
				)
				( attribute "PART_NUMBER" "G21497-005"
					( Origin gFrontEnd )
				)
				( attribute "PHYS_PAGE" "244"
					( Origin gFrontEnd )
				)
				( attribute "ROOM" "PCIE_STEERING"
					( Origin gFrontEnd )
				)
				( attribute "ROT" "0"
					( Origin gFrontEnd )
				)
				( attribute "SEC" "1"
					( Origin gPackager )
				)
				( attribute "TOLERANCE" "5%"
					( Origin gFrontEnd )
				)
				( attribute "VALUE" "0.0"
					( Origin gFrontEnd )
				)
				( attribute "VER" "2"
					( Origin gFrontEnd )
				)
				( attribute "WATTAGE" "1/16W"
					( Origin gFrontEnd )
				)
				( attribute "XY" "(-3300,3325)"
					( Origin gFrontEnd )
				)
				( attribute "CHIPS_PART_NAME" "RES"
					( Origin gPackager )
				)
				( attribute "CDS_PART_NAME" "RES_0402-0.0,5%,1/16W,CHIP,G21A"
					( Origin gPackager )
				)
				( objectStatus "R768" )
				( pin "a"
					( attribute "PN" "1"
						( Origin gPackager )
					)
					( objectStatus "R768.1" )
				)
				( pin "b"
					( attribute "PN" "2"
						( Origin gPackager )
					)
					( objectStatus "R768.2" )
				)
			)
			( gate "@baseboard_fab2_lib.baseboard_fab2(sch_1):page244_i72"
				( attribute "CDS_LIB" "mstr_discrete"
					( Origin gPackager )
				)
				( attribute "CDS_LOCATION" "R774"
					( Origin gPackager )
				)
				( attribute "CDS_SEC" "1"
					( Origin gPackager )
				)
				( attribute "LOCATION" "R774"
					( Origin gPackager )
				)
				( attribute "MATERIAL" "CHIP"
					( Origin gFrontEnd )
				)
				( attribute "PACK_TYPE" "0402"
					( Origin gFrontEnd )
				)
				( attribute "PART_NUMBER" "G21497-005"
					( Origin gFrontEnd )
				)
				( attribute "PHYS_PAGE" "244"
					( Origin gFrontEnd )
				)
				( attribute "ROOM" "PCIE_STEERING"
					( Origin gFrontEnd )
				)
				( attribute "ROT" "0"
					( Origin gFrontEnd )
				)
				( attribute "SEC" "1"
					( Origin gPackager )
				)
				( attribute "TOLERANCE" "5%"
					( Origin gFrontEnd )
				)
				( attribute "VALUE" "0.0"
					( Origin gFrontEnd )
				)
				( attribute "VER" "2"
					( Origin gFrontEnd )
				)
				( attribute "WATTAGE" "1/16W"
					( Origin gFrontEnd )
				)
				( attribute "XY" "(-3025,1725)"
					( Origin gFrontEnd )
				)
				( attribute "CHIPS_PART_NAME" "RES"
					( Origin gPackager )
				)
				( attribute "CDS_PART_NAME" "RES_0402-0.0,5%,1/16W,CHIP,G21A"
					( Origin gPackager )
				)
				( objectStatus "R774" )
				( pin "a"
					( attribute "PN" "1"
						( Origin gPackager )
					)
					( objectStatus "R774.1" )
				)
				( pin "b"
					( attribute "PN" "2"
						( Origin gPackager )
					)
					( objectStatus "R774.2" )
				)
			)
			( gate "@baseboard_fab2_lib.baseboard_fab2(sch_1):page244_i74"
				( attribute "CDS_LIB" "mstr_discrete"
					( Origin gPackager )
				)
				( attribute "CDS_LOCATION" "R779"
					( Origin gPackager )
				)
				( attribute "CDS_SEC" "1"
					( Origin gPackager )
				)
				( attribute "LOCATION" "R779"
					( Origin gPackager )
				)
				( attribute "MATERIAL" "CHIP"
					( Origin gFrontEnd )
				)
				( attribute "PACK_TYPE" "0402"
					( Origin gFrontEnd )
				)
				( attribute "PART_NUMBER" "G21497-005"
					( Origin gFrontEnd )
				)
				( attribute "PHYS_PAGE" "244"
					( Origin gFrontEnd )
				)
				( attribute "ROOM" "PCIE_STEERING"
					( Origin gFrontEnd )
				)
				( attribute "ROT" "0"
					( Origin gFrontEnd )
				)
				( attribute "SEC" "1"
					( Origin gPackager )
				)
				( attribute "TOLERANCE" "5%"
					( Origin gFrontEnd )
				)
				( attribute "VALUE" "0.0"
					( Origin gFrontEnd )
				)
				( attribute "VER" "2"
					( Origin gFrontEnd )
				)
				( attribute "WATTAGE" "1/16W"
					( Origin gFrontEnd )
				)
				( attribute "XY" "(-2625,1725)"
					( Origin gFrontEnd )
				)
				( attribute "CHIPS_PART_NAME" "RES"
					( Origin gPackager )
				)
				( attribute "CDS_PART_NAME" "RES_0402-0.0,5%,1/16W,CHIP,G21A"
					( Origin gPackager )
				)
				( objectStatus "R779" )
				( pin "a"
					( attribute "PN" "1"
						( Origin gPackager )
					)
					( objectStatus "R779.1" )
				)
				( pin "b"
					( attribute "PN" "2"
						( Origin gPackager )
					)
					( objectStatus "R779.2" )
				)
			)
			( gate "@baseboard_fab2_lib.baseboard_fab2(sch_1):page244_i77"
				( attribute "CDS_LIB" "mstr_discrete"
					( Origin gPackager )
				)
				( attribute "CDS_LOCATION" "R783"
					( Origin gPackager )
				)
				( attribute "CDS_SEC" "1"
					( Origin gPackager )
				)
				( attribute "LOCATION" "R783"
					( Origin gPackager )
				)
				( attribute "MATERIAL" "CHIP"
					( Origin gFrontEnd )
				)
				( attribute "PACK_TYPE" "0402"
					( Origin gFrontEnd )
				)
				( attribute "PART_NUMBER" "G21497-005"
					( Origin gFrontEnd )
				)
				( attribute "PHYS_PAGE" "244"
					( Origin gFrontEnd )
				)
				( attribute "ROOM" "PCIE_STEERING"
					( Origin gFrontEnd )
				)
				( attribute "ROT" "0"
					( Origin gFrontEnd )
				)
				( attribute "SEC" "1"
					( Origin gPackager )
				)
				( attribute "TOLERANCE" "5%"
					( Origin gFrontEnd )
				)
				( attribute "VALUE" "0.0"
					( Origin gFrontEnd )
				)
				( attribute "VER" "2"
					( Origin gFrontEnd )
				)
				( attribute "WATTAGE" "1/16W"
					( Origin gFrontEnd )
				)
				( attribute "XY" "(-2225,1725)"
					( Origin gFrontEnd )
				)
				( attribute "CHIPS_PART_NAME" "RES"
					( Origin gPackager )
				)
				( attribute "CDS_PART_NAME" "RES_0402-0.0,5%,1/16W,CHIP,G21A"
					( Origin gPackager )
				)
				( objectStatus "R783" )
				( pin "a"
					( attribute "PN" "1"
						( Origin gPackager )
					)
					( objectStatus "R783.1" )
				)
				( pin "b"
					( attribute "PN" "2"
						( Origin gPackager )
					)
					( objectStatus "R783.2" )
				)
			)
			( gate "@baseboard_fab2_lib.baseboard_fab2(sch_1):page244_i80"
				( attribute "CDS_LIB" "mstr_discrete"
					( Origin gPackager )
				)
				( attribute "CDS_LOCATION" "R777"
					( Origin gPackager )
				)
				( attribute "CDS_SEC" "1"
					( Origin gPackager )
				)
				( attribute "LOCATION" "R777"
					( Origin gPackager )
				)
				( attribute "MATERIAL" "CHIP"
					( Origin gFrontEnd )
				)
				( attribute "PACK_TYPE" "0402"
					( Origin gFrontEnd )
				)
				( attribute "PART_NUMBER" "G21497-005"
					( Origin gFrontEnd )
				)
				( attribute "PHYS_PAGE" "244"
					( Origin gFrontEnd )
				)
				( attribute "ROOM" "PCIE_STEERING"
					( Origin gFrontEnd )
				)
				( attribute "ROT" "0"
					( Origin gFrontEnd )
				)
				( attribute "SEC" "1"
					( Origin gPackager )
				)
				( attribute "TOLERANCE" "5%"
					( Origin gFrontEnd )
				)
				( attribute "VALUE" "0.0"
					( Origin gFrontEnd )
				)
				( attribute "VER" "2"
					( Origin gFrontEnd )
				)
				( attribute "WATTAGE" "1/16W"
					( Origin gFrontEnd )
				)
				( attribute "XY" "(-2825,2025)"
					( Origin gFrontEnd )
				)
				( attribute "CHIPS_PART_NAME" "RES"
					( Origin gPackager )
				)
				( attribute "CDS_PART_NAME" "RES_0402-0.0,5%,1/16W,CHIP,G21A"
					( Origin gPackager )
				)
				( objectStatus "R777" )
				( pin "a"
					( attribute "PN" "1"
						( Origin gPackager )
					)
					( objectStatus "R777.1" )
				)
				( pin "b"
					( attribute "PN" "2"
						( Origin gPackager )
					)
					( objectStatus "R777.2" )
				)
			)
			( gate "@baseboard_fab2_lib.baseboard_fab2(sch_1):page244_i86"
				( attribute "CDS_LIB" "mstr_discrete"
					( Origin gPackager )
				)
				( attribute "CDS_LOCATION" "R781"
					( Origin gPackager )
				)
				( attribute "CDS_SEC" "1"
					( Origin gPackager )
				)
				( attribute "LOCATION" "R781"
					( Origin gPackager )
				)
				( attribute "MATERIAL" "CHIP"
					( Origin gFrontEnd )
				)
				( attribute "PACK_TYPE" "0402"
					( Origin gFrontEnd )
				)
				( attribute "PART_NUMBER" "G21497-005"
					( Origin gFrontEnd )
				)
				( attribute "PHYS_PAGE" "244"
					( Origin gFrontEnd )
				)
				( attribute "ROOM" "PCIE_STEERING"
					( Origin gFrontEnd )
				)
				( attribute "ROT" "0"
					( Origin gFrontEnd )
				)
				( attribute "SEC" "1"
					( Origin gPackager )
				)
				( attribute "TOLERANCE" "5%"
					( Origin gFrontEnd )
				)
				( attribute "VALUE" "0.0"
					( Origin gFrontEnd )
				)
				( attribute "VER" "2"
					( Origin gFrontEnd )
				)
				( attribute "WATTAGE" "1/16W"
					( Origin gFrontEnd )
				)
				( attribute "XY" "(-2425,2025)"
					( Origin gFrontEnd )
				)
				( attribute "CHIPS_PART_NAME" "RES"
					( Origin gPackager )
				)
				( attribute "CDS_PART_NAME" "RES_0402-0.0,5%,1/16W,CHIP,G21A"
					( Origin gPackager )
				)
				( objectStatus "R781" )
				( pin "a"
					( attribute "PN" "1"
						( Origin gPackager )
					)
					( objectStatus "R781.1" )
				)
				( pin "b"
					( attribute "PN" "2"
						( Origin gPackager )
					)
					( objectStatus "R781.2" )
				)
			)
			( gate "@baseboard_fab2_lib.baseboard_fab2(sch_1):page244_i93"
				( attribute "CDS_LIB" "mstr_discrete"
					( Origin gPackager )
				)
				( attribute "CDS_LOCATION" "R775"
					( Origin gPackager )
				)
				( attribute "CDS_SEC" "1"
					( Origin gPackager )
				)
				( attribute "LOCATION" "R775"
					( Origin gPackager )
				)
				( attribute "MATERIAL" "CHIP"
					( Origin gFrontEnd )
				)
				( attribute "PACK_TYPE" "0402"
					( Origin gFrontEnd )
				)
				( attribute "PART_NUMBER" "G21497-005"
					( Origin gFrontEnd )
				)
				( attribute "PHYS_PAGE" "244"
					( Origin gFrontEnd )
				)
				( attribute "ROOM" "PCIE_STEERING"
					( Origin gFrontEnd )
				)
				( attribute "ROT" "0"
					( Origin gFrontEnd )
				)
				( attribute "SEC" "1"
					( Origin gPackager )
				)
				( attribute "TOLERANCE" "5%"
					( Origin gFrontEnd )
				)
				( attribute "VALUE" "0.0"
					( Origin gFrontEnd )
				)
				( attribute "VER" "2"
					( Origin gFrontEnd )
				)
				( attribute "WATTAGE" "1/16W"
					( Origin gFrontEnd )
				)
				( attribute "XY" "(-2900,3325)"
					( Origin gFrontEnd )
				)
				( attribute "CHIPS_PART_NAME" "RES"
					( Origin gPackager )
				)
				( attribute "CDS_PART_NAME" "RES_0402-0.0,5%,1/16W,CHIP,G21A"
					( Origin gPackager )
				)
				( objectStatus "R775" )
				( pin "a"
					( attribute "PN" "1"
						( Origin gPackager )
					)
					( objectStatus "R775.1" )
				)
				( pin "b"
					( attribute "PN" "2"
						( Origin gPackager )
					)
					( objectStatus "R775.2" )
				)
			)
			( gate "@baseboard_fab2_lib.baseboard_fab2(sch_1):page244_i94"
				( attribute "CDS_LIB" "mstr_discrete"
					( Origin gPackager )
				)
				( attribute "CDS_LOCATION" "R778"
					( Origin gPackager )
				)
				( attribute "CDS_SEC" "1"
					( Origin gPackager )
				)
				( attribute "LOCATION" "R778"
					( Origin gPackager )
				)
				( attribute "MATERIAL" "CHIP"
					( Origin gFrontEnd )
				)
				( attribute "PACK_TYPE" "0402"
					( Origin gFrontEnd )
				)
				( attribute "PART_NUMBER" "G21497-005"
					( Origin gFrontEnd )
				)
				( attribute "PHYS_PAGE" "244"
					( Origin gFrontEnd )
				)
				( attribute "ROOM" "PCIE_STEERING"
					( Origin gFrontEnd )
				)
				( attribute "ROT" "0"
					( Origin gFrontEnd )
				)
				( attribute "SEC" "1"
					( Origin gPackager )
				)
				( attribute "TOLERANCE" "5%"
					( Origin gFrontEnd )
				)
				( attribute "VALUE" "0.0"
					( Origin gFrontEnd )
				)
				( attribute "VER" "2"
					( Origin gFrontEnd )
				)
				( attribute "WATTAGE" "1/16W"
					( Origin gFrontEnd )
				)
				( attribute "XY" "(-2700,3025)"
					( Origin gFrontEnd )
				)
				( attribute "CHIPS_PART_NAME" "RES"
					( Origin gPackager )
				)
				( attribute "CDS_PART_NAME" "RES_0402-0.0,5%,1/16W,CHIP,G21A"
					( Origin gPackager )
				)
				( objectStatus "R778" )
				( pin "a"
					( attribute "PN" "1"
						( Origin gPackager )
					)
					( objectStatus "R778.1" )
				)
				( pin "b"
					( attribute "PN" "2"
						( Origin gPackager )
					)
					( objectStatus "R778.2" )
				)
			)
			( gate "@baseboard_fab2_lib.baseboard_fab2(sch_1):page244_i97"
				( attribute "CDS_LIB" "mstr_discrete"
					( Origin gPackager )
				)
				( attribute "CDS_LOCATION" "R780"
					( Origin gPackager )
				)
				( attribute "CDS_SEC" "1"
					( Origin gPackager )
				)
				( attribute "LOCATION" "R780"
					( Origin gPackager )
				)
				( attribute "MATERIAL" "CHIP"
					( Origin gFrontEnd )
				)
				( attribute "PACK_TYPE" "0402"
					( Origin gFrontEnd )
				)
				( attribute "PART_NUMBER" "G21497-005"
					( Origin gFrontEnd )
				)
				( attribute "PHYS_PAGE" "244"
					( Origin gFrontEnd )
				)
				( attribute "ROOM" "PCIE_STEERING"
					( Origin gFrontEnd )
				)
				( attribute "ROT" "0"
					( Origin gFrontEnd )
				)
				( attribute "SEC" "1"
					( Origin gPackager )
				)
				( attribute "TOLERANCE" "5%"
					( Origin gFrontEnd )
				)
				( attribute "VALUE" "0.0"
					( Origin gFrontEnd )
				)
				( attribute "VER" "2"
					( Origin gFrontEnd )
				)
				( attribute "WATTAGE" "1/16W"
					( Origin gFrontEnd )
				)
				( attribute "XY" "(-2500,3325)"
					( Origin gFrontEnd )
				)
				( attribute "CHIPS_PART_NAME" "RES"
					( Origin gPackager )
				)
				( attribute "CDS_PART_NAME" "RES_0402-0.0,5%,1/16W,CHIP,G21A"
					( Origin gPackager )
				)
				( objectStatus "R780" )
				( pin "a"
					( attribute "PN" "1"
						( Origin gPackager )
					)
					( objectStatus "R780.1" )
				)
				( pin "b"
					( attribute "PN" "2"
						( Origin gPackager )
					)
					( objectStatus "R780.2" )
				)
			)
			( gate "@baseboard_fab2_lib.baseboard_fab2(sch_1):page244_i98"
				( attribute "CDS_LIB" "mstr_discrete"
					( Origin gPackager )
				)
				( attribute "CDS_LOCATION" "R782"
					( Origin gPackager )
				)
				( attribute "CDS_SEC" "1"
					( Origin gPackager )
				)
				( attribute "LOCATION" "R782"
					( Origin gPackager )
				)
				( attribute "MATERIAL" "CHIP"
					( Origin gFrontEnd )
				)
				( attribute "PACK_TYPE" "0402"
					( Origin gFrontEnd )
				)
				( attribute "PART_NUMBER" "G21497-005"
					( Origin gFrontEnd )
				)
				( attribute "PHYS_PAGE" "244"
					( Origin gFrontEnd )
				)
				( attribute "ROOM" "PCIE_STEERING"
					( Origin gFrontEnd )
				)
				( attribute "ROT" "0"
					( Origin gFrontEnd )
				)
				( attribute "SEC" "1"
					( Origin gPackager )
				)
				( attribute "TOLERANCE" "5%"
					( Origin gFrontEnd )
				)
				( attribute "VALUE" "0.0"
					( Origin gFrontEnd )
				)
				( attribute "VER" "2"
					( Origin gFrontEnd )
				)
				( attribute "WATTAGE" "1/16W"
					( Origin gFrontEnd )
				)
				( attribute "XY" "(-2300,3025)"
					( Origin gFrontEnd )
				)
				( attribute "CHIPS_PART_NAME" "RES"
					( Origin gPackager )
				)
				( attribute "CDS_PART_NAME" "RES_0402-0.0,5%,1/16W,CHIP,G21A"
					( Origin gPackager )
				)
				( objectStatus "R782" )
				( pin "a"
					( attribute "PN" "1"
						( Origin gPackager )
					)
					( objectStatus "R782.1" )
				)
				( pin "b"
					( attribute "PN" "2"
						( Origin gPackager )
					)
					( objectStatus "R782.2" )
				)
			)
			( gate "@baseboard_fab2_lib.baseboard_fab2(sch_1):page244_i99"
				( attribute "CDS_LIB" "mstr_discrete"
					( Origin gPackager )
				)
				( attribute "CDS_LOCATION" "R784"
					( Origin gPackager )
				)
				( attribute "CDS_SEC" "1"
					( Origin gPackager )
				)
				( attribute "LOCATION" "R784"
					( Origin gPackager )
				)
				( attribute "MATERIAL" "CHIP"
					( Origin gFrontEnd )
				)
				( attribute "PACK_TYPE" "0402"
					( Origin gFrontEnd )
				)
				( attribute "PART_NUMBER" "G21497-005"
					( Origin gFrontEnd )
				)
				( attribute "PHYS_PAGE" "244"
					( Origin gFrontEnd )
				)
				( attribute "ROOM" "PCIE_STEERING"
					( Origin gFrontEnd )
				)
				( attribute "ROT" "0"
					( Origin gFrontEnd )
				)
				( attribute "SEC" "1"
					( Origin gPackager )
				)
				( attribute "TOLERANCE" "5%"
					( Origin gFrontEnd )
				)
				( attribute "VALUE" "0.0"
					( Origin gFrontEnd )
				)
				( attribute "VER" "2"
					( Origin gFrontEnd )
				)
				( attribute "WATTAGE" "1/16W"
					( Origin gFrontEnd )
				)
				( attribute "XY" "(-2100,3325)"
					( Origin gFrontEnd )
				)
				( attribute "CHIPS_PART_NAME" "RES"
					( Origin gPackager )
				)
				( attribute "CDS_PART_NAME" "RES_0402-0.0,5%,1/16W,CHIP,G21A"
					( Origin gPackager )
				)
				( objectStatus "R784" )
				( pin "a"
					( attribute "PN" "1"
						( Origin gPackager )
					)
					( objectStatus "R784.1" )
				)
				( pin "b"
					( attribute "PN" "2"
						( Origin gPackager )
					)
					( objectStatus "R784.2" )
				)
			)
			( gate "@baseboard_fab2_lib.baseboard_fab2(sch_1):page244_i103"
				( attribute "CDS_LIB" "mstr_discrete"
					( Origin gPackager )
				)
				( attribute "CDS_LOCATION" "R785"
					( Origin gPackager )
				)
				( attribute "CDS_SEC" "1"
					( Origin gPackager )
				)
				( attribute "LOCATION" "R785"
					( Origin gPackager )
				)
				( attribute "MATERIAL" "CHIP"
					( Origin gFrontEnd )
				)
				( attribute "PACK_TYPE" "0402"
					( Origin gFrontEnd )
				)
				( attribute "PART_NUMBER" "G21497-005"
					( Origin gFrontEnd )
				)
				( attribute "PHYS_PAGE" "244"
					( Origin gFrontEnd )
				)
				( attribute "ROOM" "PCIE_STEERING"
					( Origin gFrontEnd )
				)
				( attribute "ROT" "0"
					( Origin gFrontEnd )
				)
				( attribute "SEC" "1"
					( Origin gPackager )
				)
				( attribute "TOLERANCE" "5%"
					( Origin gFrontEnd )
				)
				( attribute "VALUE" "0.0"
					( Origin gFrontEnd )
				)
				( attribute "VER" "2"
					( Origin gFrontEnd )
				)
				( attribute "WATTAGE" "1/16W"
					( Origin gFrontEnd )
				)
				( attribute "XY" "(-2025,2025)"
					( Origin gFrontEnd )
				)
				( attribute "CHIPS_PART_NAME" "RES"
					( Origin gPackager )
				)
				( attribute "CDS_PART_NAME" "RES_0402-0.0,5%,1/16W,CHIP,G21A"
					( Origin gPackager )
				)
				( objectStatus "R785" )
				( pin "a"
					( attribute "PN" "1"
						( Origin gPackager )
					)
					( objectStatus "R785.1" )
				)
				( pin "b"
					( attribute "PN" "2"
						( Origin gPackager )
					)
					( objectStatus "R785.2" )
				)
			)
			( gate "@baseboard_fab2_lib.baseboard_fab2(sch_1):page245_i48"
				( attribute "CDS_LIB" "w_hdl"
					( Origin gPackager )
				)
				( attribute "CDS_LMAN_SYM_OUTLINE" "-100,900,100,-900"
					( Origin gPackager )
				)
				( attribute "CDS_LOCATION" "CONX8"
					( Origin gPackager )
				)
				( attribute "CDS_SEC" "1"
					( Origin gPackager )
				)
				( attribute "LOCATION" "CONX8"
					( Origin gFrontEnd )
				)
				( attribute "PACK_TYPE" "CONN-G7"
					( Origin gFrontEnd )
				)
				( attribute "PART_NUMBER" "020.C0082.0060"
					( Origin gFrontEnd )
				)
				( attribute "PHYS_PAGE" "245"
					( Origin gFrontEnd )
				)
				( attribute "ROT" "0"
					( Origin gFrontEnd )
				)
				( attribute "SEC" "1"
					( Origin gPackager )
				)
				( attribute "VALUE" "SMC-CONN60A-22-GP"
					( Origin gFrontEnd )
				)
				( attribute "VER" "1"
					( Origin gFrontEnd )
				)
				( attribute "XY" "(-4025,2775)"
					( Origin gFrontEnd )
				)
				( attribute "CHIPS_PART_NAME" "SMC-CONN60A-22-GP"
					( Origin gPackager )
				)
				( attribute "CDS_PART_NAME" "SMC-CONN60A-22-GP_CONN-G7-SMC-A"
					( Origin gPackager )
				)
				( objectStatus "CONX8" )
				( pin "\1\"
					( attribute "PN" "1"
						( Origin gPackager )
					)
					( objectStatus "CONX8.1" )
				)
				( pin "\2\"
					( attribute "PN" "2"
						( Origin gPackager )
					)
					( objectStatus "CONX8.2" )
				)
				( pin "\3\"
					( attribute "PN" "3"
						( Origin gPackager )
					)
					( objectStatus "CONX8.3" )
				)
				( pin "\4\"
					( attribute "PN" "4"
						( Origin gPackager )
					)
					( objectStatus "CONX8.4" )
				)
				( pin "\5\"
					( attribute "PN" "5"
						( Origin gPackager )
					)
					( objectStatus "CONX8.5" )
				)
				( pin "\6\"
					( attribute "PN" "6"
						( Origin gPackager )
					)
					( objectStatus "CONX8.6" )
				)
				( pin "\7\"
					( attribute "PN" "7"
						( Origin gPackager )
					)
					( objectStatus "CONX8.7" )
				)
				( pin "\8\"
					( attribute "PN" "8"
						( Origin gPackager )
					)
					( objectStatus "CONX8.8" )
				)
				( pin "\9\"
					( attribute "PN" "9"
						( Origin gPackager )
					)
					( objectStatus "CONX8.9" )
				)
				( pin "\10\"
					( attribute "PN" "10"
						( Origin gPackager )
					)
					( objectStatus "CONX8.10" )
				)
				( pin "\11\"
					( attribute "PN" "11"
						( Origin gPackager )
					)
					( objectStatus "CONX8.11" )
				)
				( pin "\12\"
					( attribute "PN" "12"
						( Origin gPackager )
					)
					( objectStatus "CONX8.12" )
				)
				( pin "\13\"
					( attribute "PN" "13"
						( Origin gPackager )
					)
					( objectStatus "CONX8.13" )
				)
				( pin "\14\"
					( attribute "PN" "14"
						( Origin gPackager )
					)
					( objectStatus "CONX8.14" )
				)
				( pin "\15\"
					( attribute "PN" "15"
						( Origin gPackager )
					)
					( objectStatus "CONX8.15" )
				)
				( pin "\16\"
					( attribute "PN" "16"
						( Origin gPackager )
					)
					( objectStatus "CONX8.16" )
				)
				( pin "\17\"
					( attribute "PN" "17"
						( Origin gPackager )
					)
					( objectStatus "CONX8.17" )
				)
				( pin "\18\"
					( attribute "PN" "18"
						( Origin gPackager )
					)
					( objectStatus "CONX8.18" )
				)
				( pin "\19\"
					( attribute "PN" "19"
						( Origin gPackager )
					)
					( objectStatus "CONX8.19" )
				)
				( pin "\20\"
					( attribute "PN" "20"
						( Origin gPackager )
					)
					( objectStatus "CONX8.20" )
				)
				( pin "\21\"
					( attribute "PN" "21"
						( Origin gPackager )
					)
					( objectStatus "CONX8.21" )
				)
				( pin "\22\"
					( attribute "PN" "22"
						( Origin gPackager )
					)
					( objectStatus "CONX8.22" )
				)
				( pin "\23\"
					( attribute "PN" "23"
						( Origin gPackager )
					)
					( objectStatus "CONX8.23" )
				)
				( pin "\24\"
					( attribute "PN" "24"
						( Origin gPackager )
					)
					( objectStatus "CONX8.24" )
				)
				( pin "\25\"
					( attribute "PN" "25"
						( Origin gPackager )
					)
					( objectStatus "CONX8.25" )
				)
				( pin "\26\"
					( attribute "PN" "26"
						( Origin gPackager )
					)
					( objectStatus "CONX8.26" )
				)
				( pin "\27\"
					( attribute "PN" "27"
						( Origin gPackager )
					)
					( objectStatus "CONX8.27" )
				)
				( pin "\28\"
					( attribute "PN" "28"
						( Origin gPackager )
					)
					( objectStatus "CONX8.28" )
				)
				( pin "\29\"
					( attribute "PN" "29"
						( Origin gPackager )
					)
					( objectStatus "CONX8.29" )
				)
				( pin "\30\"
					( attribute "PN" "30"
						( Origin gPackager )
					)
					( objectStatus "CONX8.30" )
				)
				( pin "\31\"
					( attribute "PN" "31"
						( Origin gPackager )
					)
					( objectStatus "CONX8.31" )
				)
				( pin "\32\"
					( attribute "PN" "32"
						( Origin gPackager )
					)
					( objectStatus "CONX8.32" )
				)
				( pin "\33\"
					( attribute "PN" "33"
						( Origin gPackager )
					)
					( objectStatus "CONX8.33" )
				)
				( pin "\34\"
					( attribute "PN" "34"
						( Origin gPackager )
					)
					( objectStatus "CONX8.34" )
				)
				( pin "\35\"
					( attribute "PN" "35"
						( Origin gPackager )
					)
					( objectStatus "CONX8.35" )
				)
				( pin "\36\"
					( attribute "PN" "36"
						( Origin gPackager )
					)
					( objectStatus "CONX8.36" )
				)
				( pin "\37\"
					( attribute "PN" "37"
						( Origin gPackager )
					)
					( objectStatus "CONX8.37" )
				)
				( pin "\38\"
					( attribute "PN" "38"
						( Origin gPackager )
					)
					( objectStatus "CONX8.38" )
				)
				( pin "\39\"
					( attribute "PN" "39"
						( Origin gPackager )
					)
					( objectStatus "CONX8.39" )
				)
				( pin "\40\"
					( attribute "PN" "40"
						( Origin gPackager )
					)
					( objectStatus "CONX8.40" )
				)
				( pin "\41\"
					( attribute "PN" "41"
						( Origin gPackager )
					)
					( objectStatus "CONX8.41" )
				)
				( pin "\42\"
					( attribute "PN" "42"
						( Origin gPackager )
					)
					( objectStatus "CONX8.42" )
				)
				( pin "\43\"
					( attribute "PN" "43"
						( Origin gPackager )
					)
					( objectStatus "CONX8.43" )
				)
				( pin "\44\"
					( attribute "PN" "44"
						( Origin gPackager )
					)
					( objectStatus "CONX8.44" )
				)
				( pin "\45\"
					( attribute "PN" "45"
						( Origin gPackager )
					)
					( objectStatus "CONX8.45" )
				)
				( pin "\46\"
					( attribute "PN" "46"
						( Origin gPackager )
					)
					( objectStatus "CONX8.46" )
				)
				( pin "\47\"
					( attribute "PN" "47"
						( Origin gPackager )
					)
					( objectStatus "CONX8.47" )
				)
				( pin "\48\"
					( attribute "PN" "48"
						( Origin gPackager )
					)
					( objectStatus "CONX8.48" )
				)
				( pin "\49\"
					( attribute "PN" "49"
						( Origin gPackager )
					)
					( objectStatus "CONX8.49" )
				)
				( pin "\50\"
					( attribute "PN" "50"
						( Origin gPackager )
					)
					( objectStatus "CONX8.50" )
				)
				( pin "\51\"
					( attribute "PN" "51"
						( Origin gPackager )
					)
					( objectStatus "CONX8.51" )
				)
				( pin "\52\"
					( attribute "PN" "52"
						( Origin gPackager )
					)
					( objectStatus "CONX8.52" )
				)
				( pin "\53\"
					( attribute "PN" "53"
						( Origin gPackager )
					)
					( objectStatus "CONX8.53" )
				)
				( pin "\54\"
					( attribute "PN" "54"
						( Origin gPackager )
					)
					( objectStatus "CONX8.54" )
				)
				( pin "\55\"
					( attribute "PN" "55"
						( Origin gPackager )
					)
					( objectStatus "CONX8.55" )
				)
				( pin "\56\"
					( attribute "PN" "56"
						( Origin gPackager )
					)
					( objectStatus "CONX8.56" )
				)
				( pin "\57\"
					( attribute "PN" "57"
						( Origin gPackager )
					)
					( objectStatus "CONX8.57" )
				)
				( pin "\58\"
					( attribute "PN" "58"
						( Origin gPackager )
					)
					( objectStatus "CONX8.58" )
				)
				( pin "\59\"
					( attribute "PN" "59"
						( Origin gPackager )
					)
					( objectStatus "CONX8.59" )
				)
				( pin "\60\"
					( attribute "PN" "60"
						( Origin gPackager )
					)
					( objectStatus "CONX8.60" )
				)
				( pin "np1"
					( attribute "PN" "NP1"
						( Origin gPackager )
					)
					( objectStatus "CONX8.NP1" )
				)
				( pin "np2"
					( attribute "PN" "NP2"
						( Origin gPackager )
					)
					( objectStatus "CONX8.NP2" )
				)
				( pin "pth1"
					( attribute "PN" "PTH1"
						( Origin gPackager )
					)
					( objectStatus "CONX8.PTH1" )
				)
				( pin "pth2"
					( attribute "PN" "PTH2"
						( Origin gPackager )
					)
					( objectStatus "CONX8.PTH2" )
				)
			)
			( gate "@baseboard_fab2_lib.baseboard_fab2(sch_1):page109_i78"
				( attribute "CDS_LIB" "mstr_sconn"
					( Origin gPackager )
				)
				( attribute "CDS_LMAN_SYM_OUTLINE" "-300,1350,300,-1350"
					( Origin gPackager )
				)
				( attribute "LOCATION" "J8G1"
					( Origin gFrontEnd )
				)
				( attribute "MATERIAL" "CONN"
					( Origin gFrontEnd )
				)
				( attribute "PACK_TYPE" "SM"
					( Origin gFrontEnd )
				)
				( attribute "PART_NUMBER" "H68296-001"
					( Origin gFrontEnd )
				)
				( attribute "PHYS_PAGE" "109"
					( Origin gFrontEnd )
				)
				( attribute "ROOM" "IO_SLOT"
					( Origin gFrontEnd )
				)
				( attribute "ROT" "0"
					( Origin gFrontEnd )
				)
				( attribute "SEC" "2"
					( Origin gFrontEnd )
				)
				( attribute "SEC_TYPE" "SM"
					( Origin gFrontEnd )
				)
				( attribute "VER" "2"
					( Origin gFrontEnd )
				)
				( attribute "XY" "(-975,3200)"
					( Origin gFrontEnd )
				)
				( attribute "CHIPS_PART_NAME" "SCONN200_H68296001"
					( Origin gPackager )
				)
				( attribute "CDS_PART_NAME" "SCONN200_H68296001_SM-CONN,H68A"
					( Origin gPackager )
				)
				( attribute "CDS_LOCATION" "J8G1"
					( Origin gPackager )
				)
				( attribute "CDS_SEC" "2"
					( Origin gPackager )
				)
				( objectStatus "J8G1" )
				( pin "io101"
					( attribute "PN" "101"
						( Origin gPackager )
					)
					( objectStatus "J8G1.101" )
				)
				( pin "io102"
					( attribute "PN" "102"
						( Origin gPackager )
					)
					( objectStatus "J8G1.102" )
				)
				( pin "io103"
					( attribute "PN" "103"
						( Origin gPackager )
					)
					( objectStatus "J8G1.103" )
				)
				( pin "io104"
					( attribute "PN" "104"
						( Origin gPackager )
					)
					( objectStatus "J8G1.104" )
				)
				( pin "io105"
					( attribute "PN" "105"
						( Origin gPackager )
					)
					( objectStatus "J8G1.105" )
				)
				( pin "io106"
					( attribute "PN" "106"
						( Origin gPackager )
					)
					( objectStatus "J8G1.106" )
				)
				( pin "io107"
					( attribute "PN" "107"
						( Origin gPackager )
					)
					( objectStatus "J8G1.107" )
				)
				( pin "io108"
					( attribute "PN" "108"
						( Origin gPackager )
					)
					( objectStatus "J8G1.108" )
				)
				( pin "io109"
					( attribute "PN" "109"
						( Origin gPackager )
					)
					( objectStatus "J8G1.109" )
				)
				( pin "io110"
					( attribute "PN" "110"
						( Origin gPackager )
					)
					( objectStatus "J8G1.110" )
				)
				( pin "io111"
					( attribute "PN" "111"
						( Origin gPackager )
					)
					( objectStatus "J8G1.111" )
				)
				( pin "io112"
					( attribute "PN" "112"
						( Origin gPackager )
					)
					( objectStatus "J8G1.112" )
				)
				( pin "io113"
					( attribute "PN" "113"
						( Origin gPackager )
					)
					( objectStatus "J8G1.113" )
				)
				( pin "io114"
					( attribute "PN" "114"
						( Origin gPackager )
					)
					( objectStatus "J8G1.114" )
				)
				( pin "io115"
					( attribute "PN" "115"
						( Origin gPackager )
					)
					( objectStatus "J8G1.115" )
				)
				( pin "io116"
					( attribute "PN" "116"
						( Origin gPackager )
					)
					( objectStatus "J8G1.116" )
				)
				( pin "io117"
					( attribute "PN" "117"
						( Origin gPackager )
					)
					( objectStatus "J8G1.117" )
				)
				( pin "io118"
					( attribute "PN" "118"
						( Origin gPackager )
					)
					( objectStatus "J8G1.118" )
				)
				( pin "io119"
					( attribute "PN" "119"
						( Origin gPackager )
					)
					( objectStatus "J8G1.119" )
				)
				( pin "io120"
					( attribute "PN" "120"
						( Origin gPackager )
					)
					( objectStatus "J8G1.120" )
				)
				( pin "io121"
					( attribute "PN" "121"
						( Origin gPackager )
					)
					( objectStatus "J8G1.121" )
				)
				( pin "io122"
					( attribute "PN" "122"
						( Origin gPackager )
					)
					( objectStatus "J8G1.122" )
				)
				( pin "io123"
					( attribute "PN" "123"
						( Origin gPackager )
					)
					( objectStatus "J8G1.123" )
				)
				( pin "io124"
					( attribute "PN" "124"
						( Origin gPackager )
					)
					( objectStatus "J8G1.124" )
				)
				( pin "io125"
					( attribute "PN" "125"
						( Origin gPackager )
					)
					( objectStatus "J8G1.125" )
				)
				( pin "io126"
					( attribute "PN" "126"
						( Origin gPackager )
					)
					( objectStatus "J8G1.126" )
				)
				( pin "io127"
					( attribute "PN" "127"
						( Origin gPackager )
					)
					( objectStatus "J8G1.127" )
				)
				( pin "io128"
					( attribute "PN" "128"
						( Origin gPackager )
					)
					( objectStatus "J8G1.128" )
				)
				( pin "io129"
					( attribute "PN" "129"
						( Origin gPackager )
					)
					( objectStatus "J8G1.129" )
				)
				( pin "io130"
					( attribute "PN" "130"
						( Origin gPackager )
					)
					( objectStatus "J8G1.130" )
				)
				( pin "io131"
					( attribute "PN" "131"
						( Origin gPackager )
					)
					( objectStatus "J8G1.131" )
				)
				( pin "io132"
					( attribute "PN" "132"
						( Origin gPackager )
					)
					( objectStatus "J8G1.132" )
				)
				( pin "io133"
					( attribute "PN" "133"
						( Origin gPackager )
					)
					( objectStatus "J8G1.133" )
				)
				( pin "io134"
					( attribute "PN" "134"
						( Origin gPackager )
					)
					( objectStatus "J8G1.134" )
				)
				( pin "io135"
					( attribute "PN" "135"
						( Origin gPackager )
					)
					( objectStatus "J8G1.135" )
				)
				( pin "io136"
					( attribute "PN" "136"
						( Origin gPackager )
					)
					( objectStatus "J8G1.136" )
				)
				( pin "io137"
					( attribute "PN" "137"
						( Origin gPackager )
					)
					( objectStatus "J8G1.137" )
				)
				( pin "io138"
					( attribute "PN" "138"
						( Origin gPackager )
					)
					( objectStatus "J8G1.138" )
				)
				( pin "io139"
					( attribute "PN" "139"
						( Origin gPackager )
					)
					( objectStatus "J8G1.139" )
				)
				( pin "io140"
					( attribute "PN" "140"
						( Origin gPackager )
					)
					( objectStatus "J8G1.140" )
				)
				( pin "io141"
					( attribute "PN" "141"
						( Origin gPackager )
					)
					( objectStatus "J8G1.141" )
				)
				( pin "io142"
					( attribute "PN" "142"
						( Origin gPackager )
					)
					( objectStatus "J8G1.142" )
				)
				( pin "io143"
					( attribute "PN" "143"
						( Origin gPackager )
					)
					( objectStatus "J8G1.143" )
				)
				( pin "io144"
					( attribute "PN" "144"
						( Origin gPackager )
					)
					( objectStatus "J8G1.144" )
				)
				( pin "io145"
					( attribute "PN" "145"
						( Origin gPackager )
					)
					( objectStatus "J8G1.145" )
				)
				( pin "io146"
					( attribute "PN" "146"
						( Origin gPackager )
					)
					( objectStatus "J8G1.146" )
				)
				( pin "io147"
					( attribute "PN" "147"
						( Origin gPackager )
					)
					( objectStatus "J8G1.147" )
				)
				( pin "io148"
					( attribute "PN" "148"
						( Origin gPackager )
					)
					( objectStatus "J8G1.148" )
				)
				( pin "io149"
					( attribute "PN" "149"
						( Origin gPackager )
					)
					( objectStatus "J8G1.149" )
				)
				( pin "io150"
					( attribute "PN" "150"
						( Origin gPackager )
					)
					( objectStatus "J8G1.150" )
				)
				( pin "io151"
					( attribute "PN" "151"
						( Origin gPackager )
					)
					( objectStatus "J8G1.151" )
				)
				( pin "io152"
					( attribute "PN" "152"
						( Origin gPackager )
					)
					( objectStatus "J8G1.152" )
				)
				( pin "io153"
					( attribute "PN" "153"
						( Origin gPackager )
					)
					( objectStatus "J8G1.153" )
				)
				( pin "io154"
					( attribute "PN" "154"
						( Origin gPackager )
					)
					( objectStatus "J8G1.154" )
				)
				( pin "io155"
					( attribute "PN" "155"
						( Origin gPackager )
					)
					( objectStatus "J8G1.155" )
				)
				( pin "io156"
					( attribute "PN" "156"
						( Origin gPackager )
					)
					( objectStatus "J8G1.156" )
				)
				( pin "io157"
					( attribute "PN" "157"
						( Origin gPackager )
					)
					( objectStatus "J8G1.157" )
				)
				( pin "io158"
					( attribute "PN" "158"
						( Origin gPackager )
					)
					( objectStatus "J8G1.158" )
				)
				( pin "io159"
					( attribute "PN" "159"
						( Origin gPackager )
					)
					( objectStatus "J8G1.159" )
				)
				( pin "io160"
					( attribute "PN" "160"
						( Origin gPackager )
					)
					( objectStatus "J8G1.160" )
				)
				( pin "io161"
					( attribute "PN" "161"
						( Origin gPackager )
					)
					( objectStatus "J8G1.161" )
				)
				( pin "io162"
					( attribute "PN" "162"
						( Origin gPackager )
					)
					( objectStatus "J8G1.162" )
				)
				( pin "io163"
					( attribute "PN" "163"
						( Origin gPackager )
					)
					( objectStatus "J8G1.163" )
				)
				( pin "io164"
					( attribute "PN" "164"
						( Origin gPackager )
					)
					( objectStatus "J8G1.164" )
				)
				( pin "io165"
					( attribute "PN" "165"
						( Origin gPackager )
					)
					( objectStatus "J8G1.165" )
				)
				( pin "io166"
					( attribute "PN" "166"
						( Origin gPackager )
					)
					( objectStatus "J8G1.166" )
				)
				( pin "io167"
					( attribute "PN" "167"
						( Origin gPackager )
					)
					( objectStatus "J8G1.167" )
				)
				( pin "io168"
					( attribute "PN" "168"
						( Origin gPackager )
					)
					( objectStatus "J8G1.168" )
				)
				( pin "io169"
					( attribute "PN" "169"
						( Origin gPackager )
					)
					( objectStatus "J8G1.169" )
				)
				( pin "io170"
					( attribute "PN" "170"
						( Origin gPackager )
					)
					( objectStatus "J8G1.170" )
				)
				( pin "io171"
					( attribute "PN" "171"
						( Origin gPackager )
					)
					( objectStatus "J8G1.171" )
				)
				( pin "io172"
					( attribute "PN" "172"
						( Origin gPackager )
					)
					( objectStatus "J8G1.172" )
				)
				( pin "io173"
					( attribute "PN" "173"
						( Origin gPackager )
					)
					( objectStatus "J8G1.173" )
				)
				( pin "io174"
					( attribute "PN" "174"
						( Origin gPackager )
					)
					( objectStatus "J8G1.174" )
				)
				( pin "io175"
					( attribute "PN" "175"
						( Origin gPackager )
					)
					( objectStatus "J8G1.175" )
				)
				( pin "io176"
					( attribute "PN" "176"
						( Origin gPackager )
					)
					( objectStatus "J8G1.176" )
				)
				( pin "io177"
					( attribute "PN" "177"
						( Origin gPackager )
					)
					( objectStatus "J8G1.177" )
				)
				( pin "io178"
					( attribute "PN" "178"
						( Origin gPackager )
					)
					( objectStatus "J8G1.178" )
				)
				( pin "io179"
					( attribute "PN" "179"
						( Origin gPackager )
					)
					( objectStatus "J8G1.179" )
				)
				( pin "io180"
					( attribute "PN" "180"
						( Origin gPackager )
					)
					( objectStatus "J8G1.180" )
				)
				( pin "io181"
					( attribute "PN" "181"
						( Origin gPackager )
					)
					( objectStatus "J8G1.181" )
				)
				( pin "io182"
					( attribute "PN" "182"
						( Origin gPackager )
					)
					( objectStatus "J8G1.182" )
				)
				( pin "io183"
					( attribute "PN" "183"
						( Origin gPackager )
					)
					( objectStatus "J8G1.183" )
				)
				( pin "io184"
					( attribute "PN" "184"
						( Origin gPackager )
					)
					( objectStatus "J8G1.184" )
				)
				( pin "io185"
					( attribute "PN" "185"
						( Origin gPackager )
					)
					( objectStatus "J8G1.185" )
				)
				( pin "io186"
					( attribute "PN" "186"
						( Origin gPackager )
					)
					( objectStatus "J8G1.186" )
				)
				( pin "io187"
					( attribute "PN" "187"
						( Origin gPackager )
					)
					( objectStatus "J8G1.187" )
				)
				( pin "io188"
					( attribute "PN" "188"
						( Origin gPackager )
					)
					( objectStatus "J8G1.188" )
				)
				( pin "io189"
					( attribute "PN" "189"
						( Origin gPackager )
					)
					( objectStatus "J8G1.189" )
				)
				( pin "io190"
					( attribute "PN" "190"
						( Origin gPackager )
					)
					( objectStatus "J8G1.190" )
				)
				( pin "io191"
					( attribute "PN" "191"
						( Origin gPackager )
					)
					( objectStatus "J8G1.191" )
				)
				( pin "io192"
					( attribute "PN" "192"
						( Origin gPackager )
					)
					( objectStatus "J8G1.192" )
				)
				( pin "io193"
					( attribute "PN" "193"
						( Origin gPackager )
					)
					( objectStatus "J8G1.193" )
				)
				( pin "io194"
					( attribute "PN" "194"
						( Origin gPackager )
					)
					( objectStatus "J8G1.194" )
				)
				( pin "io195"
					( attribute "PN" "195"
						( Origin gPackager )
					)
					( objectStatus "J8G1.195" )
				)
				( pin "io196"
					( attribute "PN" "196"
						( Origin gPackager )
					)
					( objectStatus "J8G1.196" )
				)
				( pin "io197"
					( attribute "PN" "197"
						( Origin gPackager )
					)
					( objectStatus "J8G1.197" )
				)
				( pin "io198"
					( attribute "PN" "198"
						( Origin gPackager )
					)
					( objectStatus "J8G1.198" )
				)
				( pin "io199"
					( attribute "PN" "199"
						( Origin gPackager )
					)
					( objectStatus "J8G1.199" )
				)
				( pin "io200"
					( attribute "PN" "200"
						( Origin gPackager )
					)
					( objectStatus "J8G1.200" )
				)
			)
			( gate "@baseboard_fab2_lib.baseboard_fab2(sch_1):page246_i5"
				( attribute "BOM_COST" "SM_MEM"
					( Origin gFrontEnd )
				)
				( attribute "CDS_LIB" "mstr_discrete"
					( Origin gPackager )
				)
				( attribute "CDS_LOCATION" "RN8F1"
					( Origin gPackager )
				)
				( attribute "CDS_SEC" "1"
					( Origin gPackager )
				)
				( attribute "LOCATION" "RN8F1"
					( Origin gFrontEnd )
				)
				( attribute "MATERIAL" "CHIP"
					( Origin gFrontEnd )
				)
				( attribute "PACK_TYPE" "0402"
					( Origin gFrontEnd )
				)
				( attribute "PART_NUMBER" "G21796-072"
					( Origin gFrontEnd )
				)
				( attribute "PHYS_PAGE" "246"
					( Origin gFrontEnd )
				)
				( attribute "ROOM" "BMC_BOOT_SPI"
					( Origin gFrontEnd )
				)
				( attribute "ROT" "2"
					( Origin gFrontEnd )
				)
				( attribute "SEC" "1"
					( Origin gPackager )
				)
				( attribute "TOLERANCE" "1%"
					( Origin gFrontEnd )
				)
				( attribute "VALUE" "4.75K"
					( Origin gFrontEnd )
				)
				( attribute "VER" "2"
					( Origin gFrontEnd )
				)
				( attribute "WATTAGE" "1/16W"
					( Origin gFrontEnd )
				)
				( attribute "XY" "(-6600,3175)"
					( Origin gFrontEnd )
				)
				( attribute "CHIPS_PART_NAME" "RES"
					( Origin gPackager )
				)
				( attribute "CDS_PART_NAME" "RES_0402-4.75K,1%,1/16W,CHIP,GA"
					( Origin gPackager )
				)
				( objectStatus "RN8F1" )
				( pin "a"
					( attribute "PN" "1"
						( Origin gPackager )
					)
					( objectStatus "RN8F1.1" )
				)
				( pin "b"
					( attribute "PN" "2"
						( Origin gPackager )
					)
					( objectStatus "RN8F1.2" )
				)
			)
			( gate "@baseboard_fab2_lib.baseboard_fab2(sch_1):page246_i8"
				( attribute "BOM_COST" "SM_MEM"
					( Origin gFrontEnd )
				)
				( attribute "CDS_LIB" "mstr_discrete"
					( Origin gPackager )
				)
				( attribute "CDS_LOCATION" "RN8F6"
					( Origin gPackager )
				)
				( attribute "CDS_SEC" "1"
					( Origin gPackager )
				)
				( attribute "LOCATION" "RN8F6"
					( Origin gFrontEnd )
				)
				( attribute "MATERIAL" "EMPTY"
					( Origin gFrontEnd )
				)
				( attribute "PACK_TYPE" "0402"
					( Origin gFrontEnd )
				)
				( attribute "PART_NUMBER" "G21796-026"
					( Origin gFrontEnd )
				)
				( attribute "PHYS_PAGE" "246"
					( Origin gFrontEnd )
				)
				( attribute "ROOM" "BMC_BOOT_SPI"
					( Origin gFrontEnd )
				)
				( attribute "ROT" "0"
					( Origin gFrontEnd )
				)
				( attribute "SEC" "1"
					( Origin gPackager )
				)
				( attribute "TOLERANCE" "1%"
					( Origin gFrontEnd )
				)
				( attribute "VALUE" "1.00K"
					( Origin gFrontEnd )
				)
				( attribute "VER" "2"
					( Origin gFrontEnd )
				)
				( attribute "WATTAGE" "1/16W"
					( Origin gFrontEnd )
				)
				( attribute "XY" "(-6275,2225)"
					( Origin gFrontEnd )
				)
				( attribute "CHIPS_PART_NAME" "RES"
					( Origin gPackager )
				)
				( attribute "CDS_PART_NAME" "RES_0402-1.00K,1%,1/16W,EMPTY,A"
					( Origin gPackager )
				)
				( objectStatus "RN8F6" )
				( pin "a"
					( attribute "PN" "1"
						( Origin gPackager )
					)
					( objectStatus "RN8F6.1" )
				)
				( pin "b"
					( attribute "PN" "2"
						( Origin gPackager )
					)
					( objectStatus "RN8F6.2" )
				)
			)
			( gate "@baseboard_fab2_lib.baseboard_fab2(sch_1):page246_i9"
				( attribute "BOM_COST" "SM_MEM"
					( Origin gFrontEnd )
				)
				( attribute "CDS_LIB" "mstr_discrete"
					( Origin gPackager )
				)
				( attribute "CDS_LOCATION" "RN8F5"
					( Origin gPackager )
				)
				( attribute "CDS_SEC" "1"
					( Origin gPackager )
				)
				( attribute "LOCATION" "RN8F5"
					( Origin gFrontEnd )
				)
				( attribute "MATERIAL" "CHIP"
					( Origin gFrontEnd )
				)
				( attribute "PACK_TYPE" "0402"
					( Origin gFrontEnd )
				)
				( attribute "PART_NUMBER" "G21796-074"
					( Origin gFrontEnd )
				)
				( attribute "PHYS_PAGE" "246"
					( Origin gFrontEnd )
				)
				( attribute "ROOM" "BMC_BOOT_SPI"
					( Origin gFrontEnd )
				)
				( attribute "ROT" "0"
					( Origin gFrontEnd )
				)
				( attribute "SEC" "1"
					( Origin gFrontEnd )
				)
				( attribute "SEC_TYPE" "0402"
					( Origin gFrontEnd )
				)
				( attribute "TOLERANCE" "1%"
					( Origin gFrontEnd )
				)
				( attribute "VALUE" "33.2"
					( Origin gFrontEnd )
				)
				( attribute "VER" "1"
					( Origin gFrontEnd )
				)
				( attribute "WATTAGE" "1/16W"
					( Origin gFrontEnd )
				)
				( attribute "XY" "(-5850,2725)"
					( Origin gFrontEnd )
				)
				( attribute "CHIPS_PART_NAME" "RES"
					( Origin gPackager )
				)
				( attribute "CDS_PART_NAME" "RES_0402-33.2,1%,1/16W,CHIP,G2A"
					( Origin gPackager )
				)
				( objectStatus "RN8F5" )
				( pin "a"
					( attribute "PN" "1"
						( Origin gPackager )
					)
					( objectStatus "RN8F5.1" )
				)
				( pin "b"
					( attribute "PN" "2"
						( Origin gPackager )
					)
					( objectStatus "RN8F5.2" )
				)
			)
			( gate "@baseboard_fab2_lib.baseboard_fab2(sch_1):page246_i10"
				( attribute "BOM_COST" "SM_MEM"
					( Origin gFrontEnd )
				)
				( attribute "CDS_LIB" "mstr_discrete"
					( Origin gPackager )
				)
				( attribute "CDS_LOCATION" "RN8F2"
					( Origin gPackager )
				)
				( attribute "CDS_SEC" "1"
					( Origin gPackager )
				)
				( attribute "LOCATION" "RN8F2"
					( Origin gFrontEnd )
				)
				( attribute "MATERIAL" "CHIP"
					( Origin gFrontEnd )
				)
				( attribute "PACK_TYPE" "0402"
					( Origin gFrontEnd )
				)
				( attribute "PART_NUMBER" "G21796-072"
					( Origin gFrontEnd )
				)
				( attribute "PHYS_PAGE" "246"
					( Origin gFrontEnd )
				)
				( attribute "ROOM" "BMC_BOOT_SPI"
					( Origin gFrontEnd )
				)
				( attribute "ROT" "2"
					( Origin gFrontEnd )
				)
				( attribute "SEC" "1"
					( Origin gPackager )
				)
				( attribute "TOLERANCE" "1%"
					( Origin gFrontEnd )
				)
				( attribute "VALUE" "4.75K"
					( Origin gFrontEnd )
				)
				( attribute "VER" "2"
					( Origin gFrontEnd )
				)
				( attribute "WATTAGE" "1/16W"
					( Origin gFrontEnd )
				)
				( attribute "XY" "(-6275,3150)"
					( Origin gFrontEnd )
				)
				( attribute "CHIPS_PART_NAME" "RES"
					( Origin gPackager )
				)
				( attribute "CDS_PART_NAME" "RES_0402-4.75K,1%,1/16W,CHIP,GA"
					( Origin gPackager )
				)
				( objectStatus "RN8F2" )
				( pin "a"
					( attribute "PN" "1"
						( Origin gPackager )
					)
					( objectStatus "RN8F2.1" )
				)
				( pin "b"
					( attribute "PN" "2"
						( Origin gPackager )
					)
					( objectStatus "RN8F2.2" )
				)
			)
			( gate "@baseboard_fab2_lib.baseboard_fab2(sch_1):page246_i11"
				( attribute "BOM_COST" "SM_MEM"
					( Origin gFrontEnd )
				)
				( attribute "CDS_LIB" "mstr_discrete"
					( Origin gPackager )
				)
				( attribute "CDS_LOCATION" "RN8F3"
					( Origin gPackager )
				)
				( attribute "CDS_SEC" "1"
					( Origin gPackager )
				)
				( attribute "LOCATION" "RN8F3"
					( Origin gFrontEnd )
				)
				( attribute "MATERIAL" "CHIP"
					( Origin gFrontEnd )
				)
				( attribute "PACK_TYPE" "0402"
					( Origin gFrontEnd )
				)
				( attribute "PART_NUMBER" "G21796-072"
					( Origin gFrontEnd )
				)
				( attribute "PHYS_PAGE" "246"
					( Origin gFrontEnd )
				)
				( attribute "ROOM" "BMC_BOOT_SPI"
					( Origin gFrontEnd )
				)
				( attribute "ROT" "2"
					( Origin gFrontEnd )
				)
				( attribute "SEC" "1"
					( Origin gFrontEnd )
				)
				( attribute "SEC_TYPE" "0402"
					( Origin gFrontEnd )
				)
				( attribute "TOLERANCE" "1%"
					( Origin gFrontEnd )
				)
				( attribute "VALUE" "4.75K"
					( Origin gFrontEnd )
				)
				( attribute "VER" "2"
					( Origin gFrontEnd )
				)
				( attribute "WATTAGE" "1/16W"
					( Origin gFrontEnd )
				)
				( attribute "XY" "(-6000,3175)"
					( Origin gFrontEnd )
				)
				( attribute "CHIPS_PART_NAME" "RES"
					( Origin gPackager )
				)
				( attribute "CDS_PART_NAME" "RES_0402-4.75K,1%,1/16W,CHIP,GA"
					( Origin gPackager )
				)
				( objectStatus "RN8F3" )
				( pin "a"
					( attribute "PN" "1"
						( Origin gPackager )
					)
					( objectStatus "RN8F3.1" )
				)
				( pin "b"
					( attribute "PN" "2"
						( Origin gPackager )
					)
					( objectStatus "RN8F3.2" )
				)
			)
			( gate "@baseboard_fab2_lib.baseboard_fab2(sch_1):page246_i12"
				( attribute "BOM_COST" "SM_MEM"
					( Origin gFrontEnd )
				)
				( attribute "CDS_LIB" "mstr_discrete"
					( Origin gPackager )
				)
				( attribute "CDS_LOCATION" "RN8F4"
					( Origin gPackager )
				)
				( attribute "CDS_SEC" "1"
					( Origin gPackager )
				)
				( attribute "LOCATION" "RN8F4"
					( Origin gFrontEnd )
				)
				( attribute "MATERIAL" "EMPTY"
					( Origin gFrontEnd )
				)
				( attribute "PACK_TYPE" "0402"
					( Origin gFrontEnd )
				)
				( attribute "PART_NUMBER" "G21796-072"
					( Origin gFrontEnd )
				)
				( attribute "PHYS_PAGE" "246"
					( Origin gFrontEnd )
				)
				( attribute "ROOM" "BMC_BOOT_SPI"
					( Origin gFrontEnd )
				)
				( attribute "ROT" "2"
					( Origin gFrontEnd )
				)
				( attribute "SEC" "1"
					( Origin gFrontEnd )
				)
				( attribute "SEC_TYPE" "0402"
					( Origin gFrontEnd )
				)
				( attribute "TOLERANCE" "1%"
					( Origin gFrontEnd )
				)
				( attribute "VALUE" "4.75K"
					( Origin gFrontEnd )
				)
				( attribute "VER" "2"
					( Origin gFrontEnd )
				)
				( attribute "WATTAGE" "1/16W"
					( Origin gFrontEnd )
				)
				( attribute "XY" "(-5425,3150)"
					( Origin gFrontEnd )
				)
				( attribute "CHIPS_PART_NAME" "RES"
					( Origin gPackager )
				)
				( attribute "CDS_PART_NAME" "RES_0402-4.75K,1%,1/16W,EMPTY,A"
					( Origin gPackager )
				)
				( objectStatus "RN8F4" )
				( pin "a"
					( attribute "PN" "1"
						( Origin gPackager )
					)
					( objectStatus "RN8F4.1" )
				)
				( pin "b"
					( attribute "PN" "2"
						( Origin gPackager )
					)
					( objectStatus "RN8F4.2" )
				)
			)
			( gate "@baseboard_fab2_lib.baseboard_fab2(sch_1):page246_i15"
				( attribute "BOM_COST" "SM_MEM"
					( Origin gFrontEnd )
				)
				( attribute "CDS_LIB" "mstr_discrete"
					( Origin gPackager )
				)
				( attribute "CDS_LOCATION" "CN8F1"
					( Origin gPackager )
				)
				( attribute "CDS_SEC" "1"
					( Origin gPackager )
				)
				( attribute "LOCATION" "CN8F1"
					( Origin gFrontEnd )
				)
				( attribute "MATERIAL" "X6S"
					( Origin gFrontEnd )
				)
				( attribute "PACK_TYPE" "0402"
					( Origin gFrontEnd )
				)
				( attribute "PART_NUMBER" "D97712-004"
					( Origin gFrontEnd )
				)
				( attribute "PHYS_PAGE" "246"
					( Origin gFrontEnd )
				)
				( attribute "ROOM" "BMC_BOOT_SPI"
					( Origin gFrontEnd )
				)
				( attribute "ROT" "0"
					( Origin gFrontEnd )
				)
				( attribute "SEC" "1"
					( Origin gPackager )
				)
				( attribute "TOLERANCE" "10%"
					( Origin gFrontEnd )
				)
				( attribute "VALUE" "1.0UF"
					( Origin gFrontEnd )
				)
				( attribute "VER" "1"
					( Origin gFrontEnd )
				)
				( attribute "VOLTAGE" "6.3V"
					( Units "uVoltage" "V" 1.000000)
					( Origin gFrontEnd )
				)
				( attribute "XY" "(-3525,3250)"
					( Origin gFrontEnd )
				)
				( attribute "CHIPS_PART_NAME" "CAP"
					( Origin gPackager )
				)
				( attribute "CDS_PART_NAME" "CAP_0402-1.0UF,6.3V,10%,X6S,D9A"
					( Origin gPackager )
				)
				( objectStatus "CN8F1" )
				( pin "a"
					( attribute "PN" "1"
						( Origin gPackager )
					)
					( objectStatus "CN8F1.1" )
				)
				( pin "b"
					( attribute "PN" "2"
						( Origin gPackager )
					)
					( objectStatus "CN8F1.2" )
				)
			)
			( gate "@baseboard_fab2_lib.baseboard_fab2(sch_1):page246_i16"
				( attribute "BOM_COST" "SM_MEM"
					( Origin gFrontEnd )
				)
				( attribute "CDS_LIB" "mstr_discrete"
					( Origin gPackager )
				)
				( attribute "CDS_LOCATION" "CN8F2"
					( Origin gPackager )
				)
				( attribute "CDS_SEC" "1"
					( Origin gPackager )
				)
				( attribute "LOCATION" "CN8F2"
					( Origin gFrontEnd )
				)
				( attribute "MATERIAL" "X7R"
					( Origin gFrontEnd )
				)
				( attribute "PACK_TYPE" "0402LF"
					( Origin gFrontEnd )
				)
				( attribute "PART_NUMBER" "A36096-045"
					( Origin gFrontEnd )
				)
				( attribute "PHYS_PAGE" "246"
					( Origin gFrontEnd )
				)
				( attribute "ROOM" "BMC_BOOT_SPI"
					( Origin gFrontEnd )
				)
				( attribute "ROT" "0"
					( Origin gFrontEnd )
				)
				( attribute "SEC" "1"
					( Origin gPackager )
				)
				( attribute "TOLERANCE" "10%"
					( Origin gFrontEnd )
				)
				( attribute "VALUE" "0.01UF"
					( Origin gFrontEnd )
				)
				( attribute "VER" "1"
					( Origin gFrontEnd )
				)
				( attribute "VOLTAGE" "25V"
					( Units "uVoltage" "V" 1.000000)
					( Origin gFrontEnd )
				)
				( attribute "XY" "(-3225,3250)"
					( Origin gFrontEnd )
				)
				( attribute "CHIPS_PART_NAME" "CAP"
					( Origin gPackager )
				)
				( attribute "CDS_PART_NAME" "CAP_0402LF-0.01UF,25V,10%,X7R,A"
					( Origin gPackager )
				)
				( objectStatus "CN8F2" )
				( pin "a"
					( attribute "PN" "1"
						( Origin gPackager )
					)
					( objectStatus "CN8F2.1" )
				)
				( pin "b"
					( attribute "PN" "2"
						( Origin gPackager )
					)
					( objectStatus "CN8F2.2" )
				)
			)
			( gate "@baseboard_fab2_lib.baseboard_fab2(sch_1):page246_i17"
				( attribute "BOM_COST" "SM_MEM"
					( Origin gFrontEnd )
				)
				( attribute "CDS_LIB" "mstr_memory"
					( Origin gPackager )
				)
				( attribute "CDS_LOCATION" "UN8F2"
					( Origin gPackager )
				)
				( attribute "CDS_SEC" "1"
					( Origin gPackager )
				)
				( attribute "LOCATION" "UN8F2"
					( Origin gFrontEnd )
				)
				( attribute "MATERIAL" "IC"
					( Origin gFrontEnd )
				)
				( attribute "PACK_TYPE" "XSOI"
					( Origin gFrontEnd )
				)
				( attribute "PART_NUMBER" "H25002-001"
					( Origin gFrontEnd )
				)
				( attribute "PHYS_PAGE" "246"
					( Origin gFrontEnd )
				)
				( attribute "ROOM" "BMC_BOOT_SPI"
					( Origin gFrontEnd )
				)
				( attribute "ROT" "0"
					( Origin gFrontEnd )
				)
				( attribute "SEC" "1"
					( Origin gFrontEnd )
				)
				( attribute "SEC_TYPE" "XSOI"
					( Origin gFrontEnd )
				)
				( attribute "VER" "1"
					( Origin gFrontEnd )
				)
				( attribute "XY" "(-4200,2725)"
					( Origin gFrontEnd )
				)
				( attribute "CHIPS_PART_NAME" "W25Q256"
					( Origin gPackager )
				)
				( attribute "CDS_PART_NAME" "W25Q256_XSOI-IC,H25002-001"
					( Origin gPackager )
				)
				( objectStatus "UN8F2" )
				( pin "clk"
					( attribute "PN" "16"
						( Origin gPackager )
					)
					( objectStatus "UN8F2.16" )
				)
				( pin "cs_n"
					( attribute "PN" "7"
						( Origin gPackager )
					)
					( objectStatus "UN8F2.7" )
				)
				( pin "di_io(0)"
					( attribute "PN" "15"
						( Origin gPackager )
					)
					( objectStatus "UN8F2.15" )
				)
				( pin "do_io(1)"
					( attribute "PN" "8"
						( Origin gPackager )
					)
					( objectStatus "UN8F2.8" )
				)
				( pin "gnd"
					( attribute "PN" "10"
						( Origin gPackager )
					)
					( objectStatus "UN8F2.10" )
				)
				( pin "hold_n_io(3)"
					( attribute "PN" "1"
						( Origin gPackager )
					)
					( objectStatus "UN8F2.1" )
				)
				( pin "nc(0)"
					( attribute "PN" "14"
						( Origin gPackager )
					)
					( objectStatus "UN8F2.14" )
				)
				( pin "nc(1)"
					( attribute "PN" "13"
						( Origin gPackager )
					)
					( objectStatus "UN8F2.13" )
				)
				( pin "nc(2)"
					( attribute "PN" "12"
						( Origin gPackager )
					)
					( objectStatus "UN8F2.12" )
				)
				( pin "nc(3)"
					( attribute "PN" "11"
						( Origin gPackager )
					)
					( objectStatus "UN8F2.11" )
				)
				( pin "nc(4)"
					( attribute "PN" "6"
						( Origin gPackager )
					)
					( objectStatus "UN8F2.6" )
				)
				( pin "nc(5)"
					( attribute "PN" "5"
						( Origin gPackager )
					)
					( objectStatus "UN8F2.5" )
				)
				( pin "nc(6)"
					( attribute "PN" "4"
						( Origin gPackager )
					)
					( objectStatus "UN8F2.4" )
				)
				( pin "reset_n"
					( attribute "PN" "3"
						( Origin gPackager )
					)
					( objectStatus "UN8F2.3" )
				)
				( pin "vcc"
					( attribute "PN" "2"
						( Origin gPackager )
					)
					( objectStatus "UN8F2.2" )
				)
				( pin "wp_n_io(2)"
					( attribute "PN" "9"
						( Origin gPackager )
					)
					( objectStatus "UN8F2.9" )
				)
			)
			( gate "@baseboard_fab2_lib.baseboard_fab2(sch_1):page200_i225"
				( attribute "CDS_LIB" "mstr_discrete"
					( Origin gPackager )
				)
				( attribute "LOCATION" "Q6W1"
					( Origin gFrontEnd )
				)
				( attribute "MATERIAL" "FET"
					( Origin gFrontEnd )
				)
				( attribute "PACK_TYPE" "SOT23LF"
					( Origin gFrontEnd )
				)
				( attribute "PART_NUMBER" "C79254-001"
					( Origin gFrontEnd )
				)
				( attribute "PHYS_PAGE" "200"
					( Origin gFrontEnd )
				)
				( attribute "ROOM" "HOT_SWAP"
					( Origin gFrontEnd )
				)
				( attribute "ROT" "0"
					( Origin gFrontEnd )
				)
				( attribute "VALUE" "2N7002"
					( Origin gFrontEnd )
				)
				( attribute "VER" "8"
					( Origin gFrontEnd )
				)
				( attribute "XY" "(-1500,1675)"
					( Origin gFrontEnd )
				)
				( attribute "CHIPS_PART_NAME" "FET_N"
					( Origin gPackager )
				)
				( attribute "CDS_PART_NAME" "FET_N_SOT23LF-2N7002,FET,C7925A"
					( Origin gPackager )
				)
				( attribute "CDS_LOCATION" "Q6W1"
					( Origin gPackager )
				)
				( attribute "CDS_SEC" "1"
					( Origin gPackager )
				)
				( attribute "SEC" "1"
					( Origin gPackager )
				)
				( objectStatus "Q6W1" )
				( pin "drn"
					( attribute "PN" "3"
						( Origin gPackager )
					)
					( objectStatus "Q6W1.3" )
				)
				( pin "gate"
					( attribute "PN" "1"
						( Origin gPackager )
					)
					( objectStatus "Q6W1.1" )
				)
				( pin "src"
					( attribute "PN" "2"
						( Origin gPackager )
					)
					( objectStatus "Q6W1.2" )
				)
			)
			( gate "@baseboard_fab2_lib.baseboard_fab2(sch_1):page247_i1"
				( attribute "BOM_COST" "SM_THERM"
					( Origin gFrontEnd )
				)
				( attribute "CDS_LIB" "mstr_discrete"
					( Origin gPackager )
				)
				( attribute "LOCATION" "R6W10"
					( Origin gFrontEnd )
				)
				( attribute "MATERIAL" "CHIP"
					( Origin gFrontEnd )
				)
				( attribute "PACK_TYPE" "0402"
					( Origin gFrontEnd )
				)
				( attribute "PART_NUMBER" "G21796-072"
					( Origin gFrontEnd )
				)
				( attribute "PHYS_PAGE" "247"
					( Origin gFrontEnd )
				)
				( attribute "ROOM" "CPU_FANS"
					( Origin gFrontEnd )
				)
				( attribute "ROT" "2"
					( Origin gFrontEnd )
				)
				( attribute "TOLERANCE" "1%"
					( Origin gFrontEnd )
				)
				( attribute "VALUE" "4.75K"
					( Origin gFrontEnd )
				)
				( attribute "VER" "2"
					( Origin gFrontEnd )
				)
				( attribute "WATTAGE" "1/16W"
					( Origin gFrontEnd )
				)
				( attribute "XY" "(-7375,3800)"
					( Origin gFrontEnd )
				)
				( attribute "CHIPS_PART_NAME" "RES"
					( Origin gPackager )
				)
				( attribute "CDS_PART_NAME" "RES_0402-4.75K,1%,1/16W,CHIP,GA"
					( Origin gPackager )
				)
				( attribute "CDS_LOCATION" "R6W10"
					( Origin gPackager )
				)
				( attribute "CDS_SEC" "1"
					( Origin gPackager )
				)
				( attribute "SEC" "1"
					( Origin gPackager )
				)
				( objectStatus "R6W10" )
				( pin "a"
					( attribute "PN" "1"
						( Origin gPackager )
					)
					( objectStatus "R6W10.1" )
				)
				( pin "b"
					( attribute "PN" "2"
						( Origin gPackager )
					)
					( objectStatus "R6W10.2" )
				)
			)
			( gate "@baseboard_fab2_lib.baseboard_fab2(sch_1):page200_i229"
				( attribute "CDS_LIB" "mstr_discrete"
					( Origin gPackager )
				)
				( attribute "LOCATION" "R6W1"
					( Origin gFrontEnd )
				)
				( attribute "MATERIAL" "CHIP"
					( Origin gFrontEnd )
				)
				( attribute "PACK_TYPE" "0402"
					( Origin gFrontEnd )
				)
				( attribute "PART_NUMBER" "G21796-160"
					( Origin gFrontEnd )
				)
				( attribute "PHYS_PAGE" "200"
					( Origin gFrontEnd )
				)
				( attribute "ROOM" "PVCCIN_CPU1_VR"
					( Origin gFrontEnd )
				)
				( attribute "ROT" "0"
					( Origin gFrontEnd )
				)
				( attribute "TOLERANCE" "1%"
					( Origin gFrontEnd )
				)
				( attribute "VALUE" "100.0K"
					( Origin gFrontEnd )
				)
				( attribute "VER" "2"
					( Origin gFrontEnd )
				)
				( attribute "WATTAGE" "1/16W"
					( Origin gFrontEnd )
				)
				( attribute "XY" "(-1950,1825)"
					( Origin gFrontEnd )
				)
				( attribute "CHIPS_PART_NAME" "RES"
					( Origin gPackager )
				)
				( attribute "CDS_PART_NAME" "RES_0402-100.0K,1%,1/16W,CHIP,B"
					( Origin gPackager )
				)
				( attribute "CDS_LOCATION" "R6W1"
					( Origin gPackager )
				)
				( attribute "CDS_SEC" "1"
					( Origin gPackager )
				)
				( attribute "SEC" "1"
					( Origin gPackager )
				)
				( objectStatus "R6W1" )
				( pin "a"
					( attribute "PN" "1"
						( Origin gPackager )
					)
					( objectStatus "R6W1.1" )
				)
				( pin "b"
					( attribute "PN" "2"
						( Origin gPackager )
					)
					( objectStatus "R6W1.2" )
				)
			)
			( gate "@baseboard_fab2_lib.baseboard_fab2(sch_1):page200_i230"
				( attribute "CDS_LIB" "mstr_discrete"
					( Origin gPackager )
				)
				( attribute "LOCATION" "R6W2"
					( Origin gFrontEnd )
				)
				( attribute "MATERIAL" "CHIP"
					( Origin gFrontEnd )
				)
				( attribute "PACK_TYPE" "0402"
					( Origin gFrontEnd )
				)
				( attribute "PART_NUMBER" "G21796-016"
					( Origin gFrontEnd )
				)
				( attribute "PHYS_PAGE" "200"
					( Origin gFrontEnd )
				)
				( attribute "ROOM" "HOT_SWAP"
					( Origin gFrontEnd )
				)
				( attribute "ROT" "0"
					( Origin gFrontEnd )
				)
				( attribute "TOLERANCE" "1%"
					( Origin gFrontEnd )
				)
				( attribute "VALUE" "10.0K"
					( Origin gFrontEnd )
				)
				( attribute "VER" "2"
					( Origin gFrontEnd )
				)
				( attribute "WATTAGE" "1/16W"
					( Origin gFrontEnd )
				)
				( attribute "XY" "(-1950,1425)"
					( Origin gFrontEnd )
				)
				( attribute "CHIPS_PART_NAME" "RES"
					( Origin gPackager )
				)
				( attribute "CDS_PART_NAME" "RES_0402-10.0K,1%,1/16W,CHIP,GA"
					( Origin gPackager )
				)
				( attribute "CDS_LOCATION" "R6W2"
					( Origin gPackager )
				)
				( attribute "CDS_SEC" "1"
					( Origin gPackager )
				)
				( attribute "SEC" "1"
					( Origin gPackager )
				)
				( attribute "STATUS" "NOPOP"
					( Origin gFrontEnd )
				)
				( objectStatus "R6W2" )
				( pin "a"
					( attribute "PN" "1"
						( Origin gPackager )
					)
					( objectStatus "R6W2.1" )
				)
				( pin "b"
					( attribute "PN" "2"
						( Origin gPackager )
					)
					( objectStatus "R6W2.2" )
				)
			)
			( gate "@baseboard_fab2_lib.baseboard_fab2(sch_1):page176_i124"
				( attribute "BOM_COST" "SM_THERM"
					( Origin gFrontEnd )
				)
				( attribute "CDS_LIB" "mstr_discrete"
					( Origin gPackager )
				)
				( attribute "LOCATION" "C6W10"
					( Origin gFrontEnd )
				)
				( attribute "MATERIAL" "X7R"
					( Origin gFrontEnd )
				)
				( attribute "PACK_TYPE" "0402LF"
					( Origin gFrontEnd )
				)
				( attribute "PART_NUMBER" "A36096-030"
					( Origin gFrontEnd )
				)
				( attribute "PHYS_PAGE" "176"
					( Origin gFrontEnd )
				)
				( attribute "ROOM" "CPUFANS"
					( Origin gFrontEnd )
				)
				( attribute "ROT" "0"
					( Origin gFrontEnd )
				)
				( attribute "TOLERANCE" "10%"
					( Origin gFrontEnd )
				)
				( attribute "VALUE" "0.1UF"
					( Origin gFrontEnd )
				)
				( attribute "VER" "1"
					( Origin gFrontEnd )
				)
				( attribute "VOLTAGE" "16V"
					( Units "uVoltage" "V" 1.000000)
					( Origin gFrontEnd )
				)
				( attribute "XY" "(-1175,2950)"
					( Origin gFrontEnd )
				)
				( attribute "CHIPS_PART_NAME" "CAP"
					( Origin gPackager )
				)
				( attribute "CDS_PART_NAME" "CAP_0402LF-0.1UF,16V,10%,X7R,AA"
					( Origin gPackager )
				)
				( attribute "CDS_LOCATION" "C6W10"
					( Origin gPackager )
				)
				( attribute "CDS_SEC" "1"
					( Origin gPackager )
				)
				( attribute "SEC" "1"
					( Origin gPackager )
				)
				( objectStatus "C6W10" )
				( pin "a"
					( attribute "PN" "1"
						( Origin gPackager )
					)
					( objectStatus "C6W10.1" )
				)
				( pin "b"
					( attribute "PN" "2"
						( Origin gPackager )
					)
					( objectStatus "C6W10.2" )
				)
			)
			( gate "@baseboard_fab2_lib.baseboard_fab2(sch_1):page247_i3"
				( attribute "BOM_COST" "SM_THERM"
					( Origin gFrontEnd )
				)
				( attribute "CDS_LIB" "mstr_discrete"
					( Origin gPackager )
				)
				( attribute "LOCATION" "R6W7"
					( Origin gFrontEnd )
				)
				( attribute "MATERIAL" "CHIP"
					( Origin gFrontEnd )
				)
				( attribute "PACK_TYPE" "0402"
					( Origin gFrontEnd )
				)
				( attribute "PART_NUMBER" "G21796-072"
					( Origin gFrontEnd )
				)
				( attribute "PHYS_PAGE" "247"
					( Origin gFrontEnd )
				)
				( attribute "ROOM" "CPU_FANS"
					( Origin gFrontEnd )
				)
				( attribute "ROT" "2"
					( Origin gFrontEnd )
				)
				( attribute "TOLERANCE" "1%"
					( Origin gFrontEnd )
				)
				( attribute "VALUE" "4.75K"
					( Origin gFrontEnd )
				)
				( attribute "VER" "2"
					( Origin gFrontEnd )
				)
				( attribute "WATTAGE" "1/16W"
					( Origin gFrontEnd )
				)
				( attribute "XY" "(-5650,3425)"
					( Origin gFrontEnd )
				)
				( attribute "CHIPS_PART_NAME" "RES"
					( Origin gPackager )
				)
				( attribute "CDS_PART_NAME" "RES_0402-4.75K,1%,1/16W,CHIP,GA"
					( Origin gPackager )
				)
				( attribute "CDS_LOCATION" "R6W7"
					( Origin gPackager )
				)
				( attribute "CDS_SEC" "1"
					( Origin gPackager )
				)
				( attribute "SEC" "1"
					( Origin gPackager )
				)
				( objectStatus "R6W7" )
				( pin "a"
					( attribute "PN" "1"
						( Origin gPackager )
					)
					( objectStatus "R6W7.1" )
				)
				( pin "b"
					( attribute "PN" "2"
						( Origin gPackager )
					)
					( objectStatus "R6W7.2" )
				)
			)
			( gate "@baseboard_fab2_lib.baseboard_fab2(sch_1):page247_i5"
				( attribute "CDS_LIB" "mstr_discrete"
					( Origin gPackager )
				)
				( attribute "LOCATION" "R6W4"
					( Origin gFrontEnd )
				)
				( attribute "MATERIAL" "EMPTY"
					( Origin gFrontEnd )
				)
				( attribute "NO_XNET_CONNECTION" "1"
					( Origin gFrontEnd )
				)
				( attribute "PACK_TYPE" "0402"
					( Origin gFrontEnd )
				)
				( attribute "PART_NUMBER" "G21796-072"
					( Origin gFrontEnd )
				)
				( attribute "PHYS_PAGE" "247"
					( Origin gFrontEnd )
				)
				( attribute "ROOM" "HOT_SWAP"
					( Origin gFrontEnd )
				)
				( attribute "ROT" "0"
					( Origin gFrontEnd )
				)
				( attribute "TOLERANCE" "1%"
					( Origin gFrontEnd )
				)
				( attribute "VALUE" "4.75K"
					( Origin gFrontEnd )
				)
				( attribute "VER" "2"
					( Origin gFrontEnd )
				)
				( attribute "WATTAGE" "1/16W"
					( Origin gFrontEnd )
				)
				( attribute "XY" "(-5650,4050)"
					( Origin gFrontEnd )
				)
				( attribute "CHIPS_PART_NAME" "RES"
					( Origin gPackager )
				)
				( attribute "CDS_PART_NAME" "RES_0402-4.75K,1%,1/16W,EMPTY,A"
					( Origin gPackager )
				)
				( attribute "CDS_LOCATION" "R6W4"
					( Origin gPackager )
				)
				( attribute "CDS_SEC" "1"
					( Origin gPackager )
				)
				( attribute "SEC" "1"
					( Origin gPackager )
				)
				( objectStatus "R6W4" )
				( pin "a"
					( attribute "PN" "1"
						( Origin gPackager )
					)
					( objectStatus "R6W4.1" )
				)
				( pin "b"
					( attribute "PN" "2"
						( Origin gPackager )
					)
					( objectStatus "R6W4.2" )
				)
			)
			( gate "@baseboard_fab2_lib.baseboard_fab2(sch_1):page247_i8"
				( attribute "BOM_COST" "SM_THERM"
					( Origin gFrontEnd )
				)
				( attribute "CDS_LIB" "mstr_discrete"
					( Origin gPackager )
				)
				( attribute "LOCATION" "R6W8"
					( Origin gFrontEnd )
				)
				( attribute "MATERIAL" "CHIP"
					( Origin gFrontEnd )
				)
				( attribute "PACK_TYPE" "0402"
					( Origin gFrontEnd )
				)
				( attribute "PART_NUMBER" "G21796-072"
					( Origin gFrontEnd )
				)
				( attribute "PHYS_PAGE" "247"
					( Origin gFrontEnd )
				)
				( attribute "ROOM" "CPU_FANS"
					( Origin gFrontEnd )
				)
				( attribute "ROT" "2"
					( Origin gFrontEnd )
				)
				( attribute "TOLERANCE" "1%"
					( Origin gFrontEnd )
				)
				( attribute "VALUE" "4.75K"
					( Origin gFrontEnd )
				)
				( attribute "VER" "2"
					( Origin gFrontEnd )
				)
				( attribute "WATTAGE" "1/16W"
					( Origin gFrontEnd )
				)
				( attribute "XY" "(-5250,3425)"
					( Origin gFrontEnd )
				)
				( attribute "CHIPS_PART_NAME" "RES"
					( Origin gPackager )
				)
				( attribute "CDS_PART_NAME" "RES_0402-4.75K,1%,1/16W,CHIP,GA"
					( Origin gPackager )
				)
				( attribute "CDS_LOCATION" "R6W8"
					( Origin gPackager )
				)
				( attribute "CDS_SEC" "1"
					( Origin gPackager )
				)
				( attribute "SEC" "1"
					( Origin gPackager )
				)
				( objectStatus "R6W8" )
				( pin "a"
					( attribute "PN" "1"
						( Origin gPackager )
					)
					( objectStatus "R6W8.1" )
				)
				( pin "b"
					( attribute "PN" "2"
						( Origin gPackager )
					)
					( objectStatus "R6W8.2" )
				)
			)
			( gate "@baseboard_fab2_lib.baseboard_fab2(sch_1):page247_i9"
				( attribute "BOM_COST" "SM_THERM"
					( Origin gFrontEnd )
				)
				( attribute "CDS_LIB" "mstr_discrete"
					( Origin gPackager )
				)
				( attribute "LOCATION" "R6W9"
					( Origin gFrontEnd )
				)
				( attribute "MATERIAL" "CHIP"
					( Origin gFrontEnd )
				)
				( attribute "PACK_TYPE" "0402"
					( Origin gFrontEnd )
				)
				( attribute "PART_NUMBER" "G21796-072"
					( Origin gFrontEnd )
				)
				( attribute "PHYS_PAGE" "247"
					( Origin gFrontEnd )
				)
				( attribute "ROOM" "CPU_FANS"
					( Origin gFrontEnd )
				)
				( attribute "ROT" "2"
					( Origin gFrontEnd )
				)
				( attribute "TOLERANCE" "1%"
					( Origin gFrontEnd )
				)
				( attribute "VALUE" "4.75K"
					( Origin gFrontEnd )
				)
				( attribute "VER" "2"
					( Origin gFrontEnd )
				)
				( attribute "WATTAGE" "1/16W"
					( Origin gFrontEnd )
				)
				( attribute "XY" "(-4850,3400)"
					( Origin gFrontEnd )
				)
				( attribute "CHIPS_PART_NAME" "RES"
					( Origin gPackager )
				)
				( attribute "CDS_PART_NAME" "RES_0402-4.75K,1%,1/16W,CHIP,GA"
					( Origin gPackager )
				)
				( attribute "CDS_LOCATION" "R6W9"
					( Origin gPackager )
				)
				( attribute "CDS_SEC" "1"
					( Origin gPackager )
				)
				( attribute "SEC" "1"
					( Origin gPackager )
				)
				( objectStatus "R6W9" )
				( pin "a"
					( attribute "PN" "1"
						( Origin gPackager )
					)
					( objectStatus "R6W9.1" )
				)
				( pin "b"
					( attribute "PN" "2"
						( Origin gPackager )
					)
					( objectStatus "R6W9.2" )
				)
			)
			( gate "@baseboard_fab2_lib.baseboard_fab2(sch_1):page247_i10"
				( attribute "CDS_LIB" "mstr_discrete"
					( Origin gPackager )
				)
				( attribute "LOCATION" "R6W5"
					( Origin gFrontEnd )
				)
				( attribute "MATERIAL" "EMPTY"
					( Origin gFrontEnd )
				)
				( attribute "NO_XNET_CONNECTION" "1"
					( Origin gFrontEnd )
				)
				( attribute "PACK_TYPE" "0402"
					( Origin gFrontEnd )
				)
				( attribute "PART_NUMBER" "G21796-072"
					( Origin gFrontEnd )
				)
				( attribute "PHYS_PAGE" "247"
					( Origin gFrontEnd )
				)
				( attribute "ROOM" "HOT_SWAP"
					( Origin gFrontEnd )
				)
				( attribute "ROT" "0"
					( Origin gFrontEnd )
				)
				( attribute "TOLERANCE" "1%"
					( Origin gFrontEnd )
				)
				( attribute "VALUE" "4.75K"
					( Origin gFrontEnd )
				)
				( attribute "VER" "2"
					( Origin gFrontEnd )
				)
				( attribute "WATTAGE" "1/16W"
					( Origin gFrontEnd )
				)
				( attribute "XY" "(-5250,4050)"
					( Origin gFrontEnd )
				)
				( attribute "CHIPS_PART_NAME" "RES"
					( Origin gPackager )
				)
				( attribute "CDS_PART_NAME" "RES_0402-4.75K,1%,1/16W,EMPTY,A"
					( Origin gPackager )
				)
				( attribute "CDS_LOCATION" "R6W5"
					( Origin gPackager )
				)
				( attribute "CDS_SEC" "1"
					( Origin gPackager )
				)
				( attribute "SEC" "1"
					( Origin gPackager )
				)
				( objectStatus "R6W5" )
				( pin "a"
					( attribute "PN" "1"
						( Origin gPackager )
					)
					( objectStatus "R6W5.1" )
				)
				( pin "b"
					( attribute "PN" "2"
						( Origin gPackager )
					)
					( objectStatus "R6W5.2" )
				)
			)
			( gate "@baseboard_fab2_lib.baseboard_fab2(sch_1):page247_i11"
				( attribute "CDS_LIB" "mstr_discrete"
					( Origin gPackager )
				)
				( attribute "LOCATION" "R6W6"
					( Origin gFrontEnd )
				)
				( attribute "MATERIAL" "EMPTY"
					( Origin gFrontEnd )
				)
				( attribute "NO_XNET_CONNECTION" "1"
					( Origin gFrontEnd )
				)
				( attribute "PACK_TYPE" "0402"
					( Origin gFrontEnd )
				)
				( attribute "PART_NUMBER" "G21796-072"
					( Origin gFrontEnd )
				)
				( attribute "PHYS_PAGE" "247"
					( Origin gFrontEnd )
				)
				( attribute "ROOM" "HOT_SWAP"
					( Origin gFrontEnd )
				)
				( attribute "ROT" "0"
					( Origin gFrontEnd )
				)
				( attribute "TOLERANCE" "1%"
					( Origin gFrontEnd )
				)
				( attribute "VALUE" "4.75K"
					( Origin gFrontEnd )
				)
				( attribute "VER" "2"
					( Origin gFrontEnd )
				)
				( attribute "WATTAGE" "1/16W"
					( Origin gFrontEnd )
				)
				( attribute "XY" "(-4850,4050)"
					( Origin gFrontEnd )
				)
				( attribute "CHIPS_PART_NAME" "RES"
					( Origin gPackager )
				)
				( attribute "CDS_PART_NAME" "RES_0402-4.75K,1%,1/16W,EMPTY,A"
					( Origin gPackager )
				)
				( attribute "CDS_LOCATION" "R6W6"
					( Origin gPackager )
				)
				( attribute "CDS_SEC" "1"
					( Origin gPackager )
				)
				( attribute "SEC" "1"
					( Origin gPackager )
				)
				( objectStatus "R6W6" )
				( pin "a"
					( attribute "PN" "1"
						( Origin gPackager )
					)
					( objectStatus "R6W6.1" )
				)
				( pin "b"
					( attribute "PN" "2"
						( Origin gPackager )
					)
					( objectStatus "R6W6.2" )
				)
			)
			( gate "@baseboard_fab2_lib.baseboard_fab2(sch_1):page146_i65"
				( attribute "BOM_COST" "SM_CONTROLLER"
					( Origin gFrontEnd )
				)
				( attribute "CDS_LIB" "mstr_discrete"
					( Origin gPackager )
				)
				( attribute "CDS_LOCATION" "R25W63"
					( Origin gPackager )
				)
				( attribute "CDS_SEC" "1"
					( Origin gPackager )
				)
				( attribute "LOCATION" "R25W63"
					( Origin gFrontEnd )
				)
				( attribute "MATERIAL" "CHIP"
					( Origin gFrontEnd )
				)
				( attribute "PACK_TYPE" "0402"
					( Origin gFrontEnd )
				)
				( attribute "PART_NUMBER" "G21796-010"
					( Origin gFrontEnd )
				)
				( attribute "PHYS_PAGE" "146"
					( Origin gFrontEnd )
				)
				( attribute "ROOM" "BMC"
					( Origin gFrontEnd )
				)
				( attribute "ROT" "0"
					( Origin gFrontEnd )
				)
				( attribute "SEC" "1"
					( Origin gFrontEnd )
				)
				( attribute "SEC_TYPE" "0402"
					( Origin gFrontEnd )
				)
				( attribute "TOLERANCE" "1%"
					( Origin gFrontEnd )
				)
				( attribute "VALUE" "100.0K"
					( Origin gFrontEnd )
				)
				( attribute "VER" "2"
					( Origin gFrontEnd )
				)
				( attribute "WATTAGE" "1/16W"
					( Origin gFrontEnd )
				)
				( attribute "XY" "(-1800,1100)"
					( Origin gFrontEnd )
				)
				( attribute "CHIPS_PART_NAME" "RES"
					( Origin gPackager )
				)
				( attribute "CDS_PART_NAME" "RES_0402-100.0K,1%,1/16W,CHIP,A"
					( Origin gPackager )
				)
				( objectStatus "R25W63" )
				( pin "a"
					( attribute "PN" "1"
						( Origin gPackager )
					)
					( objectStatus "R25W63.1" )
				)
				( pin "b"
					( attribute "PN" "2"
						( Origin gPackager )
					)
					( objectStatus "R25W63.2" )
				)
			)
			( gate "@baseboard_fab2_lib.baseboard_fab2(sch_1):page247_i18"
				( attribute "BOM_COST" "SM_THERM"
					( Origin gFrontEnd )
				)
				( attribute "CDS_LIB" "mstr_discrete"
					( Origin gPackager )
				)
				( attribute "LOCATION" "C6W1"
					( Origin gFrontEnd )
				)
				( attribute "MATERIAL" "X7R"
					( Origin gFrontEnd )
				)
				( attribute "PACK_TYPE" "0402LF"
					( Origin gFrontEnd )
				)
				( attribute "PART_NUMBER" "A36096-030"
					( Origin gFrontEnd )
				)
				( attribute "PHYS_PAGE" "247"
					( Origin gFrontEnd )
				)
				( attribute "ROOM" "CPUFANS"
					( Origin gFrontEnd )
				)
				( attribute "ROT" "0"
					( Origin gFrontEnd )
				)
				( attribute "TOLERANCE" "10%"
					( Origin gFrontEnd )
				)
				( attribute "VALUE" "0.1UF"
					( Origin gFrontEnd )
				)
				( attribute "VER" "1"
					( Origin gFrontEnd )
				)
				( attribute "VOLTAGE" "16V"
					( Units "uVoltage" "V" 1.000000)
					( Origin gFrontEnd )
				)
				( attribute "XY" "(-3600,3950)"
					( Origin gFrontEnd )
				)
				( attribute "CHIPS_PART_NAME" "CAP"
					( Origin gPackager )
				)
				( attribute "CDS_PART_NAME" "CAP_0402LF-0.1UF,16V,10%,X7R,AA"
					( Origin gPackager )
				)
				( attribute "CDS_LOCATION" "C6W1"
					( Origin gPackager )
				)
				( attribute "CDS_SEC" "1"
					( Origin gPackager )
				)
				( attribute "SEC" "1"
					( Origin gPackager )
				)
				( objectStatus "C6W1" )
				( pin "a"
					( attribute "PN" "1"
						( Origin gPackager )
					)
					( objectStatus "C6W1.1" )
				)
				( pin "b"
					( attribute "PN" "2"
						( Origin gPackager )
					)
					( objectStatus "C6W1.2" )
				)
			)
			( gate "@baseboard_fab2_lib.baseboard_fab2(sch_1):page168_i33"
				( attribute "BOM_COST" "SM_HM"
					( Origin gFrontEnd )
				)
				( attribute "CDS_LIB" "mstr_discrete"
					( Origin gPackager )
				)
				( attribute "LOCATION" "R6W14"
					( Origin gFrontEnd )
				)
				( attribute "MATERIAL" "CHIP"
					( Origin gFrontEnd )
				)
				( attribute "PACK_TYPE" "0402"
					( Origin gFrontEnd )
				)
				( attribute "PART_NUMBER" "G21796-140"
					( Origin gFrontEnd )
				)
				( attribute "PHYS_PAGE" "168"
					( Origin gFrontEnd )
				)
				( attribute "ROOM" "BMC_VOLT_MONITOR"
					( Origin gFrontEnd )
				)
				( attribute "ROT" "0"
					( Origin gFrontEnd )
				)
				( attribute "TOLERANCE" "1%"
					( Origin gFrontEnd )
				)
				( attribute "VALUE" "5.11K"
					( Origin gFrontEnd )
				)
				( attribute "VER" "2"
					( Origin gFrontEnd )
				)
				( attribute "WATTAGE" "1/16W"
					( Origin gFrontEnd )
				)
				( attribute "XY" "(-5250,1825)"
					( Origin gFrontEnd )
				)
				( attribute "CHIPS_PART_NAME" "RES"
					( Origin gPackager )
				)
				( attribute "CDS_PART_NAME" "RES_0402-5.11K,1%,1/16W,CHIP,GA"
					( Origin gPackager )
				)
				( attribute "CDS_LOCATION" "R6W14"
					( Origin gPackager )
				)
				( attribute "CDS_SEC" "1"
					( Origin gPackager )
				)
				( attribute "SEC" "1"
					( Origin gPackager )
				)
				( objectStatus "R6W14" )
				( pin "a"
					( attribute "PN" "1"
						( Origin gPackager )
					)
					( objectStatus "R6W14.1" )
				)
				( pin "b"
					( attribute "PN" "2"
						( Origin gPackager )
					)
					( objectStatus "R6W14.2" )
				)
			)
			( gate "@baseboard_fab2_lib.baseboard_fab2(sch_1):page168_i34"
				( attribute "CDS_LIB" "mstr_discrete"
					( Origin gPackager )
				)
				( attribute "LOCATION" "R6W13"
					( Origin gFrontEnd )
				)
				( attribute "MATERIAL" "CHIP"
					( Origin gFrontEnd )
				)
				( attribute "PACK_TYPE" "0402"
					( Origin gFrontEnd )
				)
				( attribute "PART_NUMBER" "G21796-107"
					( Origin gFrontEnd )
				)
				( attribute "PHYS_PAGE" "168"
					( Origin gFrontEnd )
				)
				( attribute "ROOM" "PVCCIN_CPU1_VR"
					( Origin gFrontEnd )
				)
				( attribute "ROT" "0"
					( Origin gFrontEnd )
				)
				( attribute "TOLERANCE" "1%"
					( Origin gFrontEnd )
				)
				( attribute "VALUE" "15.0K"
					( Origin gFrontEnd )
				)
				( attribute "VER" "2"
					( Origin gFrontEnd )
				)
				( attribute "WATTAGE" "1/16W"
					( Origin gFrontEnd )
				)
				( attribute "XY" "(-5250,2175)"
					( Origin gFrontEnd )
				)
				( attribute "CHIPS_PART_NAME" "RES"
					( Origin gPackager )
				)
				( attribute "CDS_PART_NAME" "RES_0402-15.0K,1%,1/16W,CHIP,GA"
					( Origin gPackager )
				)
				( attribute "CDS_LOCATION" "R6W13"
					( Origin gPackager )
				)
				( attribute "CDS_SEC" "1"
					( Origin gPackager )
				)
				( attribute "SEC" "1"
					( Origin gPackager )
				)
				( objectStatus "R6W13" )
				( pin "a"
					( attribute "PN" "1"
						( Origin gPackager )
					)
					( objectStatus "R6W13.1" )
				)
				( pin "b"
					( attribute "PN" "2"
						( Origin gPackager )
					)
					( objectStatus "R6W13.2" )
				)
			)
			( gate "@baseboard_fab2_lib.baseboard_fab2(sch_1):page168_i37"
				( attribute "BOM_COST" "DEBUG"
					( Origin gFrontEnd )
				)
				( attribute "CDS_LIB" "mstr_discrete"
					( Origin gPackager )
				)
				( attribute "CDS_LOCATION" "Q6W3"
					( Origin gPackager )
				)
				( attribute "CDS_SEC" "1"
					( Origin gPackager )
				)
				( attribute "LOCATION" "Q6W3"
					( Origin gFrontEnd )
				)
				( attribute "MATERIAL" "IC"
					( Origin gFrontEnd )
				)
				( attribute "PACK_TYPE" "SM"
					( Origin gFrontEnd )
				)
				( attribute "PART_NUMBER" "C52245-001"
					( Origin gFrontEnd )
				)
				( attribute "PHYS_PAGE" "168"
					( Origin gFrontEnd )
				)
				( attribute "ROOM" "UART_MUX"
					( Origin gFrontEnd )
				)
				( attribute "ROT" "5"
					( Origin gFrontEnd )
				)
				( attribute "SEC" "1"
					( Origin gFrontEnd )
				)
				( attribute "SEC_TYPE" "SM"
					( Origin gFrontEnd )
				)
				( attribute "VALUE" "MMBT3904"
					( Origin gFrontEnd )
				)
				( attribute "VER" "1"
					( Origin gFrontEnd )
				)
				( attribute "XY" "(-5975,1500)"
					( Origin gFrontEnd )
				)
				( attribute "CHIPS_PART_NAME" "NPN"
					( Origin gPackager )
				)
				( attribute "CDS_PART_NAME" "NPN_SM-MMBT3904,IC,C52245-001"
					( Origin gPackager )
				)
				( objectStatus "Q6W3" )
				( pin "b"
					( attribute "PN" "1"
						( Origin gPackager )
					)
					( objectStatus "Q6W3.1" )
				)
				( pin "c"
					( attribute "PN" "3"
						( Origin gPackager )
					)
					( objectStatus "Q6W3.3" )
				)
				( pin "e"
					( attribute "PN" "2"
						( Origin gPackager )
					)
					( objectStatus "Q6W3.2" )
				)
			)
			( gate "@baseboard_fab2_lib.baseboard_fab2(sch_1):page168_i39"
				( attribute "CDS_LIB" "mstr_discrete"
					( Origin gPackager )
				)
				( attribute "LOCATION" "R6W16"
					( Origin gFrontEnd )
				)
				( attribute "MATERIAL" "CHIP"
					( Origin gFrontEnd )
				)
				( attribute "PACK_TYPE" "0402"
					( Origin gFrontEnd )
				)
				( attribute "PART_NUMBER" "G21796-016"
					( Origin gFrontEnd )
				)
				( attribute "PHYS_PAGE" "168"
					( Origin gFrontEnd )
				)
				( attribute "ROOM" "HOT_SWAP"
					( Origin gFrontEnd )
				)
				( attribute "ROT" "0"
					( Origin gFrontEnd )
				)
				( attribute "TOLERANCE" "1%"
					( Origin gFrontEnd )
				)
				( attribute "VALUE" "10.0K"
					( Origin gFrontEnd )
				)
				( attribute "VER" "2"
					( Origin gFrontEnd )
				)
				( attribute "WATTAGE" "1/16W"
					( Origin gFrontEnd )
				)
				( attribute "XY" "(-3950,2000)"
					( Origin gFrontEnd )
				)
				( attribute "CHIPS_PART_NAME" "RES"
					( Origin gPackager )
				)
				( attribute "CDS_PART_NAME" "RES_0402-10.0K,1%,1/16W,CHIP,GA"
					( Origin gPackager )
				)
				( attribute "CDS_LOCATION" "R6W16"
					( Origin gPackager )
				)
				( attribute "CDS_SEC" "1"
					( Origin gPackager )
				)
				( attribute "SEC" "1"
					( Origin gPackager )
				)
				( objectStatus "R6W16" )
				( pin "a"
					( attribute "PN" "1"
						( Origin gPackager )
					)
					( objectStatus "R6W16.1" )
				)
				( pin "b"
					( attribute "PN" "2"
						( Origin gPackager )
					)
					( objectStatus "R6W16.2" )
				)
			)
			( gate "@baseboard_fab2_lib.baseboard_fab2(sch_1):page168_i40"
				( attribute "CDS_LIB" "mstr_discrete"
					( Origin gPackager )
				)
				( attribute "LOCATION" "R6W15"
					( Origin gFrontEnd )
				)
				( attribute "MATERIAL" "CHIP"
					( Origin gFrontEnd )
				)
				( attribute "PACK_TYPE" "0402"
					( Origin gFrontEnd )
				)
				( attribute "PART_NUMBER" "G21796-016"
					( Origin gFrontEnd )
				)
				( attribute "PHYS_PAGE" "168"
					( Origin gFrontEnd )
				)
				( attribute "ROOM" "HOT_SWAP"
					( Origin gFrontEnd )
				)
				( attribute "ROT" "0"
					( Origin gFrontEnd )
				)
				( attribute "TOLERANCE" "1%"
					( Origin gFrontEnd )
				)
				( attribute "VALUE" "10.0K"
					( Origin gFrontEnd )
				)
				( attribute "VER" "2"
					( Origin gFrontEnd )
				)
				( attribute "WATTAGE" "1/16W"
					( Origin gFrontEnd )
				)
				( attribute "XY" "(-4500,2000)"
					( Origin gFrontEnd )
				)
				( attribute "CHIPS_PART_NAME" "RES"
					( Origin gPackager )
				)
				( attribute "CDS_PART_NAME" "RES_0402-10.0K,1%,1/16W,CHIP,GA"
					( Origin gPackager )
				)
				( attribute "CDS_LOCATION" "R6W15"
					( Origin gPackager )
				)
				( attribute "CDS_SEC" "1"
					( Origin gPackager )
				)
				( attribute "SEC" "1"
					( Origin gPackager )
				)
				( objectStatus "R6W15" )
				( pin "a"
					( attribute "PN" "1"
						( Origin gPackager )
					)
					( objectStatus "R6W15.1" )
				)
				( pin "b"
					( attribute "PN" "2"
						( Origin gPackager )
					)
					( objectStatus "R6W15.2" )
				)
			)
			( gate "@baseboard_fab2_lib.baseboard_fab2(sch_1):page239_i99"
				( attribute "CDS_LIB" "w_hdl"
					( Origin gPackager )
				)
				( attribute "CDS_LMAN_SYM_OUTLINE" "-50,75,50,-75"
					( Origin gPackager )
				)
				( attribute "LOCATION" "R9W31"
					( Origin gFrontEnd )
				)
				( attribute "PACK_TYPE" "RCL_GP"
					( Origin gFrontEnd )
				)
				( attribute "PART_NUMBER" "64.21525.6DL"
					( Origin gFrontEnd )
				)
				( attribute "PHYS_PAGE" "239"
					( Origin gFrontEnd )
				)
				( attribute "ROT" "0"
					( Origin gFrontEnd )
				)
				( attribute "VALUE" "21K5R2F-GP"
					( Origin gFrontEnd )
				)
				( attribute "VER" "1"
					( Origin gFrontEnd )
				)
				( attribute "XY" "(9925,1325)"
					( Origin gFrontEnd )
				)
				( attribute "CHIPS_PART_NAME" "21K5R2F-GP"
					( Origin gPackager )
				)
				( attribute "CDS_PART_NAME" "21K5R2F-GP_RCL_GP-21K5R2F-GP,6A"
					( Origin gPackager )
				)
				( attribute "CDS_LOCATION" "R9W31"
					( Origin gPackager )
				)
				( attribute "CDS_SEC" "1"
					( Origin gPackager )
				)
				( attribute "SEC" "1"
					( Origin gPackager )
				)
				( objectStatus "R9W31" )
				( pin "\1\"
					( attribute "PN" "1"
						( Origin gPackager )
					)
					( objectStatus "R9W31.1" )
				)
				( pin "\2\"
					( attribute "PN" "2"
						( Origin gPackager )
					)
					( objectStatus "R9W31.2" )
				)
			)
			( gate "@baseboard_fab2_lib.baseboard_fab2(sch_1):page247_i53"
				( attribute "CHIPS_PART_NAME" "TTL1G07_A"
					( Origin gPackager )
				)
			)
			( gate "@baseboard_fab2_lib.baseboard_fab2(sch_1):page249_i2"
				( attribute "CDS_LIB" "mstr_discrete"
					( Origin gPackager )
				)
				( attribute "LOCATION" "R3W1"
					( Origin gFrontEnd )
				)
				( attribute "MATERIAL" "CHIP"
					( Origin gFrontEnd )
				)
				( attribute "PACK_TYPE" "0402"
					( Origin gFrontEnd )
				)
				( attribute "PART_NUMBER" "G21796-026"
					( Origin gFrontEnd )
				)
				( attribute "PHYS_PAGE" "249"
					( Origin gFrontEnd )
				)
				( attribute "ROOM" "BMC_DEBUG_HEADER"
					( Origin gFrontEnd )
				)
				( attribute "ROT" "0"
					( Origin gFrontEnd )
				)
				( attribute "TOLERANCE" "1%"
					( Origin gFrontEnd )
				)
				( attribute "VALUE" "1.00K"
					( Origin gFrontEnd )
				)
				( attribute "VER" "2"
					( Origin gFrontEnd )
				)
				( attribute "WATTAGE" "1/16W"
					( Origin gFrontEnd )
				)
				( attribute "XY" "(-6925,1950)"
					( Origin gFrontEnd )
				)
				( attribute "CHIPS_PART_NAME" "RES"
					( Origin gPackager )
				)
				( attribute "CDS_PART_NAME" "RES_0402-1.00K,1%,1/16W,CHIP,GA"
					( Origin gPackager )
				)
				( attribute "CDS_LOCATION" "R3W1"
					( Origin gPackager )
				)
				( attribute "CDS_SEC" "1"
					( Origin gPackager )
				)
				( attribute "SEC" "1"
					( Origin gPackager )
				)
				( objectStatus "R3W1" )
				( pin "a"
					( attribute "PN" "1"
						( Origin gPackager )
					)
					( objectStatus "R3W1.1" )
				)
				( pin "b"
					( attribute "PN" "2"
						( Origin gPackager )
					)
					( objectStatus "R3W1.2" )
				)
			)
			( gate "@baseboard_fab2_lib.baseboard_fab2(sch_1):page249_i7"
				( attribute "BOM_COST" "ST_FLASH"
					( Origin gFrontEnd )
				)
				( attribute "CDS_LIB" "mstr_discrete"
					( Origin gPackager )
				)
				( attribute "LOCATION" "R3W9"
					( Origin gFrontEnd )
				)
				( attribute "MATERIAL" "CHIP"
					( Origin gFrontEnd )
				)
				( attribute "PACK_TYPE" "0402"
					( Origin gFrontEnd )
				)
				( attribute "PART_NUMBER" "G21796-016"
					( Origin gFrontEnd )
				)
				( attribute "PHYS_PAGE" "249"
					( Origin gFrontEnd )
				)
				( attribute "ROOM" "M_2"
					( Origin gFrontEnd )
				)
				( attribute "ROT" "0"
					( Origin gFrontEnd )
				)
				( attribute "TOLERANCE" "1%"
					( Origin gFrontEnd )
				)
				( attribute "VALUE" "10.0K"
					( Origin gFrontEnd )
				)
				( attribute "VER" "2"
					( Origin gFrontEnd )
				)
				( attribute "WATTAGE" "1/16W"
					( Origin gFrontEnd )
				)
				( attribute "XY" "(-4225,2300)"
					( Origin gFrontEnd )
				)
				( attribute "CHIPS_PART_NAME" "RES"
					( Origin gPackager )
				)
				( attribute "CDS_PART_NAME" "RES_0402-10.0K,1%,1/16W,CHIP,GA"
					( Origin gPackager )
				)
				( attribute "CDS_LOCATION" "R3W9"
					( Origin gPackager )
				)
				( attribute "CDS_SEC" "1"
					( Origin gPackager )
				)
				( attribute "SEC" "1"
					( Origin gPackager )
				)
				( objectStatus "R3W9" )
				( pin "a"
					( attribute "PN" "1"
						( Origin gPackager )
					)
					( objectStatus "R3W9.1" )
				)
				( pin "b"
					( attribute "PN" "2"
						( Origin gPackager )
					)
					( objectStatus "R3W9.2" )
				)
			)
			( gate "@baseboard_fab2_lib.baseboard_fab2(sch_1):page249_i8"
				( attribute "BOM_COST" "MIO_BIOS_MEM"
					( Origin gFrontEnd )
				)
				( attribute "CDS_LIB" "mstr_discrete"
					( Origin gPackager )
				)
				( attribute "LOCATION" "R3W7"
					( Origin gFrontEnd )
				)
				( attribute "MATERIAL" "CHIP"
					( Origin gFrontEnd )
				)
				( attribute "NO_XNET_CONNECTION" "1"
					( Origin gFrontEnd )
				)
				( attribute "PACK_TYPE" "0402"
					( Origin gFrontEnd )
				)
				( attribute "PART_NUMBER" "G21796-072"
					( Origin gFrontEnd )
				)
				( attribute "PHYS_PAGE" "249"
					( Origin gFrontEnd )
				)
				( attribute "ROOM" "SB_SPI"
					( Origin gFrontEnd )
				)
				( attribute "ROT" "2"
					( Origin gFrontEnd )
				)
				( attribute "TOLERANCE" "1%"
					( Origin gFrontEnd )
				)
				( attribute "VALUE" "4.75K"
					( Origin gFrontEnd )
				)
				( attribute "VER" "2"
					( Origin gFrontEnd )
				)
				( attribute "WATTAGE" "1/16W"
					( Origin gFrontEnd )
				)
				( attribute "XY" "(-4225,2775)"
					( Origin gFrontEnd )
				)
				( attribute "CHIPS_PART_NAME" "RES"
					( Origin gPackager )
				)
				( attribute "CDS_PART_NAME" "RES_0402-4.75K,1%,1/16W,CHIP,GA"
					( Origin gPackager )
				)
				( attribute "CDS_LOCATION" "R3W7"
					( Origin gPackager )
				)
				( attribute "CDS_SEC" "1"
					( Origin gPackager )
				)
				( attribute "SEC" "1"
					( Origin gPackager )
				)
				( objectStatus "R3W7" )
				( pin "a"
					( attribute "PN" "1"
						( Origin gPackager )
					)
					( objectStatus "R3W7.1" )
				)
				( pin "b"
					( attribute "PN" "2"
						( Origin gPackager )
					)
					( objectStatus "R3W7.2" )
				)
			)
			( gate "@baseboard_fab2_lib.baseboard_fab2(sch_1):page249_i12"
				( attribute "CDS_LIB" "mstr_discrete"
					( Origin gPackager )
				)
				( attribute "LOCATION" "R3W2"
					( Origin gFrontEnd )
				)
				( attribute "MATERIAL" "CHIP"
					( Origin gFrontEnd )
				)
				( attribute "PACK_TYPE" "0402"
					( Origin gFrontEnd )
				)
				( attribute "PART_NUMBER" "G21796-026"
					( Origin gFrontEnd )
				)
				( attribute "PHYS_PAGE" "249"
					( Origin gFrontEnd )
				)
				( attribute "ROOM" "BMC_DEBUG_HEADER"
					( Origin gFrontEnd )
				)
				( attribute "ROT" "0"
					( Origin gFrontEnd )
				)
				( attribute "TOLERANCE" "1%"
					( Origin gFrontEnd )
				)
				( attribute "VALUE" "1.00K"
					( Origin gFrontEnd )
				)
				( attribute "VER" "2"
					( Origin gFrontEnd )
				)
				( attribute "WATTAGE" "1/16W"
					( Origin gFrontEnd )
				)
				( attribute "XY" "(-6325,1925)"
					( Origin gFrontEnd )
				)
				( attribute "CHIPS_PART_NAME" "RES"
					( Origin gPackager )
				)
				( attribute "CDS_PART_NAME" "RES_0402-1.00K,1%,1/16W,CHIP,GA"
					( Origin gPackager )
				)
				( attribute "CDS_LOCATION" "R3W2"
					( Origin gPackager )
				)
				( attribute "CDS_SEC" "1"
					( Origin gPackager )
				)
				( attribute "SEC" "1"
					( Origin gPackager )
				)
				( objectStatus "R3W2" )
				( pin "a"
					( attribute "PN" "1"
						( Origin gPackager )
					)
					( objectStatus "R3W2.1" )
				)
				( pin "b"
					( attribute "PN" "2"
						( Origin gPackager )
					)
					( objectStatus "R3W2.2" )
				)
			)
			( gate "@baseboard_fab2_lib.baseboard_fab2(sch_1):page249_i31"
				( attribute "CDS_LIB" "w_hdl"
					( Origin gPackager )
				)
				( attribute "CDS_LMAN_SYM_OUTLINE" "-50,75,50,-75"
					( Origin gPackager )
				)
				( attribute "LOCATION" "R3W4"
					( Origin gFrontEnd )
				)
				( attribute "PACK_TYPE" "RCL_GP"
					( Origin gFrontEnd )
				)
				( attribute "PART_NUMBER" "64.47025.6DL"
					( Origin gFrontEnd )
				)
				( attribute "PHYS_PAGE" "249"
					( Origin gFrontEnd )
				)
				( attribute "ROT" "1"
					( Origin gFrontEnd )
				)
				( attribute "VALUE" "47KR2F-GP"
					( Origin gFrontEnd )
				)
				( attribute "VER" "1"
					( Origin gFrontEnd )
				)
				( attribute "XY" "(-5375,3975)"
					( Origin gFrontEnd )
				)
				( attribute "CHIPS_PART_NAME" "47KR2F-GP"
					( Origin gPackager )
				)
				( attribute "CDS_PART_NAME" "47KR2F-GP_RCL_GP-47KR2F-GP,64.A"
					( Origin gPackager )
				)
				( attribute "CDS_LOCATION" "R3W4"
					( Origin gPackager )
				)
				( attribute "CDS_SEC" "1"
					( Origin gPackager )
				)
				( attribute "SEC" "1"
					( Origin gPackager )
				)
				( objectStatus "R3W4" )
				( pin "\1\"
					( attribute "PN" "1"
						( Origin gPackager )
					)
					( objectStatus "R3W4.1" )
				)
				( pin "\2\"
					( attribute "PN" "2"
						( Origin gPackager )
					)
					( objectStatus "R3W4.2" )
				)
			)
			( gate "@baseboard_fab2_lib.baseboard_fab2(sch_1):page249_i15"
				( attribute "CDS_LIB" "w_hdl"
					( Origin gPackager )
				)
				( attribute "CDS_LMAN_SYM_OUTLINE" "-100,100,100,-100"
					( Origin gPackager )
				)
				( attribute "PACK_TYPE" "DISCRET-G"
					( Origin gFrontEnd )
				)
				( attribute "PART_NUMBER" "74.00331.A2F"
					( Origin gFrontEnd )
				)
				( attribute "PHYS_PAGE" "249"
					( Origin gFrontEnd )
				)
				( attribute "ROT" "0"
					( Origin gFrontEnd )
				)
				( attribute "VALUE" "LMV331IDCKRG4-GP"
					( Origin gFrontEnd )
				)
				( attribute "VER" "1"
					( Origin gFrontEnd )
				)
				( attribute "XY" "(-3250,2550)"
					( Origin gFrontEnd )
				)
				( attribute "CHIPS_PART_NAME" "LMV331IDCKRG4-GP"
					( Origin gPackager )
				)
				( attribute "CDS_PART_NAME" "LMV331IDCKRG4-GP_DISCRET-G-LMVA"
					( Origin gPackager )
				)
				( attribute "LOCATION" "Q9W4"
					( Origin gFrontEnd )
				)
				( attribute "CDS_LOCATION" "Q9W4"
					( Origin gPackager )
				)
				( attribute "CDS_SEC" "1"
					( Origin gPackager )
				)
				( attribute "SEC" "1"
					( Origin gPackager )
				)
				( objectStatus "Q9W4" )
				( pin "\+in\"
					( attribute "PN" "1"
						( Origin gPackager )
					)
					( objectStatus "Q9W4.1" )
				)
				( pin "\-in\"
					( attribute "PN" "3"
						( Origin gPackager )
					)
					( objectStatus "Q9W4.3" )
				)
				( pin "gnd"
					( attribute "PN" "2"
						( Origin gPackager )
					)
					( objectStatus "Q9W4.2" )
				)
				( pin "\out\"
					( attribute "PN" "4"
						( Origin gPackager )
					)
					( objectStatus "Q9W4.4" )
				)
				( pin "vcc"
					( attribute "PN" "5"
						( Origin gPackager )
					)
					( objectStatus "Q9W4.5" )
				)
			)
			( gate "@baseboard_fab2_lib.baseboard_fab2(sch_1):page249_i17"
				( attribute "BOM_COST" "ST_FLASH"
					( Origin gFrontEnd )
				)
				( attribute "CDS_LIB" "mstr_discrete"
					( Origin gPackager )
				)
				( attribute "LOCATION" "R3W3"
					( Origin gFrontEnd )
				)
				( attribute "MATERIAL" "CHIP"
					( Origin gFrontEnd )
				)
				( attribute "PACK_TYPE" "0402"
					( Origin gFrontEnd )
				)
				( attribute "PART_NUMBER" "G21796-016"
					( Origin gFrontEnd )
				)
				( attribute "PHYS_PAGE" "249"
					( Origin gFrontEnd )
				)
				( attribute "ROOM" "M_2"
					( Origin gFrontEnd )
				)
				( attribute "ROT" "0"
					( Origin gFrontEnd )
				)
				( attribute "TOLERANCE" "1%"
					( Origin gFrontEnd )
				)
				( attribute "VALUE" "10.0K"
					( Origin gFrontEnd )
				)
				( attribute "VER" "2"
					( Origin gFrontEnd )
				)
				( attribute "WATTAGE" "1/16W"
					( Origin gFrontEnd )
				)
				( attribute "XY" "(-5875,2825)"
					( Origin gFrontEnd )
				)
				( attribute "CHIPS_PART_NAME" "RES"
					( Origin gPackager )
				)
				( attribute "CDS_PART_NAME" "RES_0402-10.0K,1%,1/16W,CHIP,GA"
					( Origin gPackager )
				)
				( attribute "CDS_LOCATION" "R3W3"
					( Origin gPackager )
				)
				( attribute "CDS_SEC" "1"
					( Origin gPackager )
				)
				( attribute "SEC" "1"
					( Origin gPackager )
				)
				( objectStatus "R3W3" )
				( pin "a"
					( attribute "PN" "1"
						( Origin gPackager )
					)
					( objectStatus "R3W3.1" )
				)
				( pin "b"
					( attribute "PN" "2"
						( Origin gPackager )
					)
					( objectStatus "R3W3.2" )
				)
			)
			( gate "@baseboard_fab2_lib.baseboard_fab2(sch_1):page249_i21"
				( attribute "BOM_COST" "SD_FLASH"
					( Origin gFrontEnd )
				)
				( attribute "CDS_LIB" "mstr_discrete"
					( Origin gPackager )
				)
				( attribute "LOCATION" "C8W2"
					( Origin gFrontEnd )
				)
				( attribute "MATERIAL" "X7R"
					( Origin gFrontEnd )
				)
				( attribute "PACK_TYPE" "0402LF"
					( Origin gFrontEnd )
				)
				( attribute "PART_NUMBER" "A36096-030"
					( Origin gFrontEnd )
				)
				( attribute "PHYS_PAGE" "249"
					( Origin gFrontEnd )
				)
				( attribute "ROOM" "M_2"
					( Origin gFrontEnd )
				)
				( attribute "ROT" "0"
					( Origin gFrontEnd )
				)
				( attribute "TOLERANCE" "10%"
					( Origin gFrontEnd )
				)
				( attribute "VALUE" "0.1UF"
					( Origin gFrontEnd )
				)
				( attribute "VER" "1"
					( Origin gFrontEnd )
				)
				( attribute "VOLTAGE" "16V"
					( Units "uVoltage" "V" 1.000000)
					( Origin gFrontEnd )
				)
				( attribute "XY" "(-2975,2950)"
					( Origin gFrontEnd )
				)
				( attribute "CHIPS_PART_NAME" "CAP"
					( Origin gPackager )
				)
				( attribute "CDS_PART_NAME" "CAP_0402LF-0.1UF,16V,10%,X7R,AA"
					( Origin gPackager )
				)
				( attribute "CDS_LOCATION" "C8W2"
					( Origin gPackager )
				)
				( attribute "CDS_SEC" "1"
					( Origin gPackager )
				)
				( attribute "SEC" "1"
					( Origin gPackager )
				)
				( objectStatus "C8W2" )
				( pin "a"
					( attribute "PN" "1"
						( Origin gPackager )
					)
					( objectStatus "C8W2.1" )
				)
				( pin "b"
					( attribute "PN" "2"
						( Origin gPackager )
					)
					( objectStatus "C8W2.2" )
				)
			)
			( gate "@baseboard_fab2_lib.baseboard_fab2(sch_1):page249_i26"
				( attribute "CDS_LIB" "mstr_discrete"
					( Origin gPackager )
				)
				( attribute "LOCATION" "Q9W3"
					( Origin gFrontEnd )
				)
				( attribute "MATERIAL" "IC"
					( Origin gFrontEnd )
				)
				( attribute "PACK_TYPE" "SM"
					( Origin gFrontEnd )
				)
				( attribute "PART_NUMBER" "C52245-001"
					( Origin gFrontEnd )
				)
				( attribute "PHYS_PAGE" "249"
					( Origin gFrontEnd )
				)
				( attribute "ROOM" "SB"
					( Origin gFrontEnd )
				)
				( attribute "ROT" "0"
					( Origin gFrontEnd )
				)
				( attribute "VALUE" "MMBT3904"
					( Origin gFrontEnd )
				)
				( attribute "VER" "1"
					( Origin gFrontEnd )
				)
				( attribute "XY" "(-4000,4125)"
					( Origin gFrontEnd )
				)
				( attribute "CHIPS_PART_NAME" "NPN"
					( Origin gPackager )
				)
				( attribute "CDS_PART_NAME" "NPN_SM-MMBT3904,IC,C52245-001"
					( Origin gPackager )
				)
				( attribute "CDS_LOCATION" "Q9W3"
					( Origin gPackager )
				)
				( attribute "CDS_SEC" "1"
					( Origin gPackager )
				)
				( attribute "SEC" "1"
					( Origin gPackager )
				)
				( objectStatus "Q9W3" )
				( pin "b"
					( attribute "PN" "1"
						( Origin gPackager )
					)
					( objectStatus "Q9W3.1" )
				)
				( pin "c"
					( attribute "PN" "3"
						( Origin gPackager )
					)
					( objectStatus "Q9W3.3" )
				)
				( pin "e"
					( attribute "PN" "2"
						( Origin gPackager )
					)
					( objectStatus "Q9W3.2" )
				)
			)
			( gate "@baseboard_fab2_lib.baseboard_fab2(sch_1):page249_i27"
				( attribute "BOM_COST" "MIO_BIOS_MEM"
					( Origin gFrontEnd )
				)
				( attribute "CDS_LIB" "mstr_discrete"
					( Origin gPackager )
				)
				( attribute "LOCATION" "R3W6"
					( Origin gFrontEnd )
				)
				( attribute "MATERIAL" "CHIP"
					( Origin gFrontEnd )
				)
				( attribute "NO_XNET_CONNECTION" "1"
					( Origin gFrontEnd )
				)
				( attribute "PACK_TYPE" "0402"
					( Origin gFrontEnd )
				)
				( attribute "PART_NUMBER" "G21796-072"
					( Origin gFrontEnd )
				)
				( attribute "PHYS_PAGE" "249"
					( Origin gFrontEnd )
				)
				( attribute "ROOM" "SB_SPI"
					( Origin gFrontEnd )
				)
				( attribute "ROT" "2"
					( Origin gFrontEnd )
				)
				( attribute "TOLERANCE" "1%"
					( Origin gFrontEnd )
				)
				( attribute "VALUE" "4.75K"
					( Origin gFrontEnd )
				)
				( attribute "VER" "2"
					( Origin gFrontEnd )
				)
				( attribute "WATTAGE" "1/16W"
					( Origin gFrontEnd )
				)
				( attribute "XY" "(-3950,4425)"
					( Origin gFrontEnd )
				)
				( attribute "CHIPS_PART_NAME" "RES"
					( Origin gPackager )
				)
				( attribute "CDS_PART_NAME" "RES_0402-4.75K,1%,1/16W,CHIP,GA"
					( Origin gPackager )
				)
				( attribute "CDS_LOCATION" "R3W6"
					( Origin gPackager )
				)
				( attribute "CDS_SEC" "1"
					( Origin gPackager )
				)
				( attribute "SEC" "1"
					( Origin gPackager )
				)
				( objectStatus "R3W6" )
				( pin "a"
					( attribute "PN" "1"
						( Origin gPackager )
					)
					( objectStatus "R3W6.1" )
				)
				( pin "b"
					( attribute "PN" "2"
						( Origin gPackager )
					)
					( objectStatus "R3W6.2" )
				)
			)
			( gate "@baseboard_fab2_lib.baseboard_fab2(sch_1):page249_i29"
				( attribute "CDS_LIB" "mstr_discrete"
					( Origin gPackager )
				)
				( attribute "LOCATION" "Q9W2"
					( Origin gFrontEnd )
				)
				( attribute "MATERIAL" "IC"
					( Origin gFrontEnd )
				)
				( attribute "PACK_TYPE" "SM"
					( Origin gFrontEnd )
				)
				( attribute "PART_NUMBER" "C52245-001"
					( Origin gFrontEnd )
				)
				( attribute "PHYS_PAGE" "249"
					( Origin gFrontEnd )
				)
				( attribute "ROOM" "SB"
					( Origin gFrontEnd )
				)
				( attribute "ROT" "0"
					( Origin gFrontEnd )
				)
				( attribute "VALUE" "MMBT3904"
					( Origin gFrontEnd )
				)
				( attribute "VER" "1"
					( Origin gFrontEnd )
				)
				( attribute "XY" "(-4600,3975)"
					( Origin gFrontEnd )
				)
				( attribute "CHIPS_PART_NAME" "NPN"
					( Origin gPackager )
				)
				( attribute "CDS_PART_NAME" "NPN_SM-MMBT3904,IC,C52245-001"
					( Origin gPackager )
				)
				( attribute "CDS_LOCATION" "Q9W2"
					( Origin gPackager )
				)
				( attribute "CDS_SEC" "1"
					( Origin gPackager )
				)
				( attribute "SEC" "1"
					( Origin gPackager )
				)
				( objectStatus "Q9W2" )
				( pin "b"
					( attribute "PN" "1"
						( Origin gPackager )
					)
					( objectStatus "Q9W2.1" )
				)
				( pin "c"
					( attribute "PN" "3"
						( Origin gPackager )
					)
					( objectStatus "Q9W2.3" )
				)
				( pin "e"
					( attribute "PN" "2"
						( Origin gPackager )
					)
					( objectStatus "Q9W2.2" )
				)
			)
			( gate "@baseboard_fab2_lib.baseboard_fab2(sch_1):page248_i11"
				( attribute "CHIPS_PART_NAME" "TTL1G08"
					( Origin gPackager )
				)
			)
			( gate "@baseboard_fab2_lib.baseboard_fab2(sch_1):page200_i239"
				( attribute "CDS_LIB" "w_hdl"
					( Origin gPackager )
				)
				( attribute "CDS_LMAN_SYM_OUTLINE" "-50,75,50,-75"
					( Origin gPackager )
				)
				( attribute "LOCATION" "R6W3"
					( Origin gFrontEnd )
				)
				( attribute "PACK_TYPE" "SMD-RG1"
					( Origin gFrontEnd )
				)
				( attribute "PART_NUMBER" "64.23235.L0L"
					( Origin gFrontEnd )
				)
				( attribute "PHYS_PAGE" "200"
					( Origin gFrontEnd )
				)
				( attribute "ROT" "1"
					( Origin gFrontEnd )
				)
				( attribute "VALUE" "232KR2F-2-GP"
					( Origin gFrontEnd )
				)
				( attribute "VER" "1"
					( Origin gFrontEnd )
				)
				( attribute "XY" "(-800,1950)"
					( Origin gFrontEnd )
				)
				( attribute "CHIPS_PART_NAME" "232KR2F-2-GP"
					( Origin gPackager )
				)
				( attribute "CDS_PART_NAME" "232KR2F-2-GP_SMD-RG1-232KR2F-2A"
					( Origin gPackager )
				)
				( attribute "CDS_LOCATION" "R6W3"
					( Origin gPackager )
				)
				( attribute "CDS_SEC" "1"
					( Origin gPackager )
				)
				( attribute "SEC" "1"
					( Origin gPackager )
				)
				( objectStatus "R6W3" )
				( pin "\1\"
					( attribute "PN" "1"
						( Origin gPackager )
					)
					( objectStatus "R6W3.1" )
				)
				( pin "\2\"
					( attribute "PN" "2"
						( Origin gPackager )
					)
					( objectStatus "R6W3.2" )
				)
			)
			( gate "@baseboard_fab2_lib.baseboard_fab2(sch_1):page150_i81"
				( attribute "BOM_COST" "SM_CONTROLLER"
					( Origin gFrontEnd )
				)
				( attribute "CDS_LIB" "mstr_discrete"
					( Origin gPackager )
				)
				( attribute "LOCATION" "C25W41"
					( Origin gFrontEnd )
				)
				( attribute "MATERIAL" "X6S"
					( Origin gFrontEnd )
				)
				( attribute "PACK_TYPE" "0402"
					( Origin gFrontEnd )
				)
				( attribute "PART_NUMBER" "D97712-004"
					( Origin gFrontEnd )
				)
				( attribute "PHYS_PAGE" "150"
					( Origin gFrontEnd )
				)
				( attribute "ROOM" "BMC"
					( Origin gFrontEnd )
				)
				( attribute "ROT" "0"
					( Origin gFrontEnd )
				)
				( attribute "TOLERANCE" "10%"
					( Origin gFrontEnd )
				)
				( attribute "VALUE" "1.0UF"
					( Origin gFrontEnd )
				)
				( attribute "VER" "1"
					( Origin gFrontEnd )
				)
				( attribute "VOLTAGE" "6.3V"
					( Units "uVoltage" "V" 1.000000)
					( Origin gFrontEnd )
				)
				( attribute "XY" "(-5375,2475)"
					( Origin gFrontEnd )
				)
				( attribute "CHIPS_PART_NAME" "CAP"
					( Origin gPackager )
				)
				( attribute "CDS_PART_NAME" "CAP_0402-1.0UF,6.3V,10%,X6S,D9A"
					( Origin gPackager )
				)
				( attribute "CDS_LOCATION" "C25W41"
					( Origin gPackager )
				)
				( attribute "CDS_SEC" "1"
					( Origin gPackager )
				)
				( attribute "SEC" "1"
					( Origin gPackager )
				)
				( objectStatus "C25W41" )
				( pin "a"
					( attribute "PN" "1"
						( Origin gPackager )
					)
					( objectStatus "C25W41.1" )
				)
				( pin "b"
					( attribute "PN" "2"
						( Origin gPackager )
					)
					( objectStatus "C25W41.2" )
				)
			)
			( gate "@baseboard_fab2_lib.baseboard_fab2(sch_1):page150_i80"
				( attribute "BOM_COST" "SM_CONTROLLER"
					( Origin gFrontEnd )
				)
				( attribute "CDS_LIB" "mstr_discrete"
					( Origin gPackager )
				)
				( attribute "LOCATION" "C25W42"
					( Origin gFrontEnd )
				)
				( attribute "MATERIAL" "X6S"
					( Origin gFrontEnd )
				)
				( attribute "PACK_TYPE" "0402"
					( Origin gFrontEnd )
				)
				( attribute "PART_NUMBER" "D97712-004"
					( Origin gFrontEnd )
				)
				( attribute "PHYS_PAGE" "150"
					( Origin gFrontEnd )
				)
				( attribute "ROOM" "BMC"
					( Origin gFrontEnd )
				)
				( attribute "ROT" "0"
					( Origin gFrontEnd )
				)
				( attribute "TOLERANCE" "10%"
					( Origin gFrontEnd )
				)
				( attribute "VALUE" "1.0UF"
					( Origin gFrontEnd )
				)
				( attribute "VER" "1"
					( Origin gFrontEnd )
				)
				( attribute "VOLTAGE" "6.3V"
					( Units "uVoltage" "V" 1.000000)
					( Origin gFrontEnd )
				)
				( attribute "XY" "(-5125,2475)"
					( Origin gFrontEnd )
				)
				( attribute "CHIPS_PART_NAME" "CAP"
					( Origin gPackager )
				)
				( attribute "CDS_PART_NAME" "CAP_0402-1.0UF,6.3V,10%,X6S,D9A"
					( Origin gPackager )
				)
				( attribute "CDS_LOCATION" "C25W42"
					( Origin gPackager )
				)
				( attribute "CDS_SEC" "1"
					( Origin gPackager )
				)
				( attribute "SEC" "1"
					( Origin gPackager )
				)
				( objectStatus "C25W42" )
				( pin "a"
					( attribute "PN" "1"
						( Origin gPackager )
					)
					( objectStatus "C25W42.1" )
				)
				( pin "b"
					( attribute "PN" "2"
						( Origin gPackager )
					)
					( objectStatus "C25W42.2" )
				)
			)
			( gate "@baseboard_fab2_lib.baseboard_fab2(sch_1):page150_i79"
				( attribute "CDS_LIB" "w_hdl"
					( Origin gPackager )
				)
				( attribute "CDS_LMAN_SYM_OUTLINE" "-50,25,50,-25"
					( Origin gPackager )
				)
				( attribute "LOCATION" "C25W31"
					( Origin gFrontEnd )
				)
				( attribute "PACK_TYPE" "SMD-BCG"
					( Origin gFrontEnd )
				)
				( attribute "PART_NUMBER" "78.10421.2FL"
					( Origin gFrontEnd )
				)
				( attribute "PHYS_PAGE" "150"
					( Origin gFrontEnd )
				)
				( attribute "ROT" "0"
					( Origin gFrontEnd )
				)
				( attribute "VALUE" "SCD1U16V2KX-3GP"
					( Origin gFrontEnd )
				)
				( attribute "VER" "1"
					( Origin gFrontEnd )
				)
				( attribute "XY" "(-5700,3700)"
					( Origin gFrontEnd )
				)
				( attribute "CHIPS_PART_NAME" "SCD1U16V2KX-3GP"
					( Origin gPackager )
				)
				( attribute "CDS_PART_NAME" "SCD1U16V2KX-3GP_SMD-BCG-SCD1U1A"
					( Origin gPackager )
				)
				( attribute "CDS_LOCATION" "C25W31"
					( Origin gPackager )
				)
				( attribute "CDS_SEC" "1"
					( Origin gPackager )
				)
				( attribute "SEC" "1"
					( Origin gPackager )
				)
				( objectStatus "C25W31" )
				( pin "\1\"
					( attribute "PN" "1"
						( Origin gPackager )
					)
					( objectStatus "C25W31.1" )
				)
				( pin "\2\"
					( attribute "PN" "2"
						( Origin gPackager )
					)
					( objectStatus "C25W31.2" )
				)
			)
			( gate "@baseboard_fab2_lib.baseboard_fab2(sch_1):page150_i78"
				( attribute "BOM_COST" "SM_CONTROLLER"
					( Origin gFrontEnd )
				)
				( attribute "CDS_LIB" "mstr_discrete"
					( Origin gPackager )
				)
				( attribute "LOCATION" "C25W32"
					( Origin gFrontEnd )
				)
				( attribute "MATERIAL" "X6S"
					( Origin gFrontEnd )
				)
				( attribute "PACK_TYPE" "0402"
					( Origin gFrontEnd )
				)
				( attribute "PART_NUMBER" "D97712-004"
					( Origin gFrontEnd )
				)
				( attribute "PHYS_PAGE" "150"
					( Origin gFrontEnd )
				)
				( attribute "ROOM" "BMC"
					( Origin gFrontEnd )
				)
				( attribute "ROT" "0"
					( Origin gFrontEnd )
				)
				( attribute "TOLERANCE" "10%"
					( Origin gFrontEnd )
				)
				( attribute "VALUE" "1.0UF"
					( Origin gFrontEnd )
				)
				( attribute "VER" "1"
					( Origin gFrontEnd )
				)
				( attribute "VOLTAGE" "6.3V"
					( Units "uVoltage" "V" 1.000000)
					( Origin gFrontEnd )
				)
				( attribute "XY" "(-5250,3725)"
					( Origin gFrontEnd )
				)
				( attribute "CHIPS_PART_NAME" "CAP"
					( Origin gPackager )
				)
				( attribute "CDS_PART_NAME" "CAP_0402-1.0UF,6.3V,10%,X6S,D9A"
					( Origin gPackager )
				)
				( attribute "CDS_LOCATION" "C25W32"
					( Origin gPackager )
				)
				( attribute "CDS_SEC" "1"
					( Origin gPackager )
				)
				( attribute "SEC" "1"
					( Origin gPackager )
				)
				( objectStatus "C25W32" )
				( pin "a"
					( attribute "PN" "1"
						( Origin gPackager )
					)
					( objectStatus "C25W32.1" )
				)
				( pin "b"
					( attribute "PN" "2"
						( Origin gPackager )
					)
					( objectStatus "C25W32.2" )
				)
			)
			( gate "@baseboard_fab2_lib.baseboard_fab2(sch_1):page149_i194"
				( attribute "CDS_LIB" "w_hdl"
					( Origin gPackager )
				)
				( attribute "CDS_LMAN_SYM_OUTLINE" "-50,75,50,-75"
					( Origin gPackager )
				)
				( attribute "LOCATION" "R25W35"
					( Origin gFrontEnd )
				)
				( attribute "PACK_TYPE" "RCL_GP"
					( Origin gFrontEnd )
				)
				( attribute "PART_NUMBER" "64.12005.6DL"
					( Origin gFrontEnd )
				)
				( attribute "PHYS_PAGE" "149"
					( Origin gFrontEnd )
				)
				( attribute "ROT" "1"
					( Origin gFrontEnd )
				)
				( attribute "VALUE" "120R2F-GP"
					( Origin gFrontEnd )
				)
				( attribute "VER" "1"
					( Origin gFrontEnd )
				)
				( attribute "XY" "(-6150,3900)"
					( Origin gFrontEnd )
				)
				( attribute "CHIPS_PART_NAME" "120R2F-GP"
					( Origin gPackager )
				)
				( attribute "CDS_PART_NAME" "120R2F-GP_RCL_GP-120R2F-GP,64.A"
					( Origin gPackager )
				)
				( attribute "CDS_LOCATION" "R25W35"
					( Origin gPackager )
				)
				( attribute "CDS_SEC" "1"
					( Origin gPackager )
				)
				( attribute "SEC" "1"
					( Origin gPackager )
				)
				( objectStatus "R25W35" )
				( pin "\1\"
					( attribute "PN" "1"
						( Origin gPackager )
					)
					( objectStatus "R25W35.1" )
				)
				( pin "\2\"
					( attribute "PN" "2"
						( Origin gPackager )
					)
					( objectStatus "R25W35.2" )
				)
			)
			( gate "@baseboard_fab2_lib.baseboard_fab2(sch_1):page145_i46"
				( attribute "BOM_COST" "SM_CONTROLLER"
					( Origin gFrontEnd )
				)
				( attribute "CDS_LIB" "mstr_discrete"
					( Origin gPackager )
				)
				( attribute "CDS_LOCATION" "R25W67"
					( Origin gPackager )
				)
				( attribute "CDS_SEC" "1"
					( Origin gPackager )
				)
				( attribute "LOCATION" "R25W67"
					( Origin gFrontEnd )
				)
				( attribute "MATERIAL" "EMPTY"
					( Origin gFrontEnd )
				)
				( attribute "PACK_TYPE" "0402"
					( Origin gFrontEnd )
				)
				( attribute "PART_NUMBER" "G21796-016"
					( Origin gFrontEnd )
				)
				( attribute "PHYS_PAGE" "145"
					( Origin gFrontEnd )
				)
				( attribute "ROOM" "BMC"
					( Origin gFrontEnd )
				)
				( attribute "ROT" "0"
					( Origin gFrontEnd )
				)
				( attribute "SEC" "1"
					( Origin gFrontEnd )
				)
				( attribute "SEC_TYPE" "0402"
					( Origin gFrontEnd )
				)
				( attribute "TOLERANCE" "1%"
					( Origin gFrontEnd )
				)
				( attribute "VALUE" "10.0K"
					( Origin gFrontEnd )
				)
				( attribute "VER" "1"
					( Origin gFrontEnd )
				)
				( attribute "WATTAGE" "1/16W"
					( Origin gFrontEnd )
				)
				( attribute "XY" "(-1325,-3200)"
					( Origin gFrontEnd )
				)
				( attribute "CHIPS_PART_NAME" "RES"
					( Origin gPackager )
				)
				( attribute "CDS_PART_NAME" "RES_0402-10.0K,1%,1/16W,EMPTY,A"
					( Origin gPackager )
				)
				( objectStatus "R25W67" )
				( pin "a"
					( attribute "PN" "1"
						( Origin gPackager )
					)
					( objectStatus "R25W67.1" )
				)
				( pin "b"
					( attribute "PN" "2"
						( Origin gPackager )
					)
					( objectStatus "R25W67.2" )
				)
			)
			( gate "@baseboard_fab2_lib.baseboard_fab2(sch_1):page145_i45"
				( attribute "BOM_COST" "SM_CONTROLLER"
					( Origin gFrontEnd )
				)
				( attribute "CDS_LIB" "dev_discrete"
					( Origin gPackager )
				)
				( attribute "CDS_LOCATION" "C25W20"
					( Origin gPackager )
				)
				( attribute "CDS_SEC" "1"
					( Origin gPackager )
				)
				( attribute "LOCATION" "C25W20"
					( Origin gFrontEnd )
				)
				( attribute "MATERIAL" "EMPTY"
					( Origin gFrontEnd )
				)
				( attribute "PACK_TYPE" "0402V"
					( Origin gFrontEnd )
				)
				( attribute "PART_NUMBER" "A36096-030"
					( Origin gFrontEnd )
				)
				( attribute "PHYS_PAGE" "145"
					( Origin gFrontEnd )
				)
				( attribute "ROOM" "BMC"
					( Origin gFrontEnd )
				)
				( attribute "ROT" "0"
					( Origin gFrontEnd )
				)
				( attribute "SEC" "1"
					( Origin gFrontEnd )
				)
				( attribute "SEC_TYPE" "0402V"
					( Origin gFrontEnd )
				)
				( attribute "TOLERANCE" "10%"
					( Origin gFrontEnd )
				)
				( attribute "VALUE" "0.1UF"
					( Origin gFrontEnd )
				)
				( attribute "VER" "2"
					( Origin gFrontEnd )
				)
				( attribute "VOLTAGE" "16V"
					( Units "uVoltage" "V" 1.000000)
					( Origin gFrontEnd )
				)
				( attribute "XY" "(-1650,-3400)"
					( Origin gFrontEnd )
				)
				( attribute "CHIPS_PART_NAME" "CAP_A"
					( Origin gPackager )
				)
				( attribute "CDS_PART_NAME" "CAP_A_0402V-0.1UF,16V,10%,EMPTA"
					( Origin gPackager )
				)
				( objectStatus "C25W20" )
				( pin "a"
					( attribute "PN" "1"
						( Origin gPackager )
					)
					( objectStatus "C25W20.1" )
				)
				( pin "b"
					( attribute "PN" "2"
						( Origin gPackager )
					)
					( objectStatus "C25W20.2" )
				)
			)
			( gate "@baseboard_fab2_lib.baseboard_fab2(sch_1):page145_i44"
				( attribute "BOM_COST" "SM_CONTROLLER"
					( Origin gFrontEnd )
				)
				( attribute "CDS_LIB" "dev_discrete"
					( Origin gPackager )
				)
				( attribute "CDS_LOCATION" "C25W21"
					( Origin gPackager )
				)
				( attribute "CDS_SEC" "1"
					( Origin gPackager )
				)
				( attribute "LOCATION" "C25W21"
					( Origin gFrontEnd )
				)
				( attribute "MATERIAL" "EMPTY"
					( Origin gFrontEnd )
				)
				( attribute "PACK_TYPE" "0402V"
					( Origin gFrontEnd )
				)
				( attribute "PART_NUMBER" "A36096-030"
					( Origin gFrontEnd )
				)
				( attribute "PHYS_PAGE" "145"
					( Origin gFrontEnd )
				)
				( attribute "ROOM" "BMC"
					( Origin gFrontEnd )
				)
				( attribute "ROT" "0"
					( Origin gFrontEnd )
				)
				( attribute "SEC" "1"
					( Origin gFrontEnd )
				)
				( attribute "SEC_TYPE" "0402V"
					( Origin gFrontEnd )
				)
				( attribute "TOLERANCE" "10%"
					( Origin gFrontEnd )
				)
				( attribute "VALUE" "0.1UF"
					( Origin gFrontEnd )
				)
				( attribute "VER" "2"
					( Origin gFrontEnd )
				)
				( attribute "VOLTAGE" "16V"
					( Units "uVoltage" "V" 1.000000)
					( Origin gFrontEnd )
				)
				( attribute "XY" "(-1275,-3700)"
					( Origin gFrontEnd )
				)
				( attribute "CHIPS_PART_NAME" "CAP_A"
					( Origin gPackager )
				)
				( attribute "CDS_PART_NAME" "CAP_A_0402V-0.1UF,16V,10%,EMPTA"
					( Origin gPackager )
				)
				( objectStatus "C25W21" )
				( pin "a"
					( attribute "PN" "1"
						( Origin gPackager )
					)
					( objectStatus "C25W21.1" )
				)
				( pin "b"
					( attribute "PN" "2"
						( Origin gPackager )
					)
					( objectStatus "C25W21.2" )
				)
			)
			( gate "@baseboard_fab2_lib.baseboard_fab2(sch_1):page145_i38"
				( attribute "BOM_COST" "SM_CONTROLLER"
					( Origin gFrontEnd )
				)
				( attribute "CDS_LIB" "mstr_discrete"
					( Origin gPackager )
				)
				( attribute "CDS_LOCATION" "R25W65"
					( Origin gPackager )
				)
				( attribute "CDS_SEC" "1"
					( Origin gPackager )
				)
				( attribute "LOCATION" "R25W65"
					( Origin gFrontEnd )
				)
				( attribute "MATERIAL" "CHIP"
					( Origin gFrontEnd )
				)
				( attribute "PACK_TYPE" "0402"
					( Origin gFrontEnd )
				)
				( attribute "PART_NUMBER" "G21796-010"
					( Origin gFrontEnd )
				)
				( attribute "PHYS_PAGE" "145"
					( Origin gFrontEnd )
				)
				( attribute "ROOM" "BMC"
					( Origin gFrontEnd )
				)
				( attribute "ROT" "0"
					( Origin gFrontEnd )
				)
				( attribute "SEC" "1"
					( Origin gFrontEnd )
				)
				( attribute "SEC_TYPE" "0402"
					( Origin gFrontEnd )
				)
				( attribute "TOLERANCE" "1%"
					( Origin gFrontEnd )
				)
				( attribute "VALUE" "100.0K"
					( Origin gFrontEnd )
				)
				( attribute "VER" "2"
					( Origin gFrontEnd )
				)
				( attribute "WATTAGE" "1/16W"
					( Origin gFrontEnd )
				)
				( attribute "XY" "(-6200,-4325)"
					( Origin gFrontEnd )
				)
				( attribute "CHIPS_PART_NAME" "RES"
					( Origin gPackager )
				)
				( attribute "CDS_PART_NAME" "RES_0402-100.0K,1%,1/16W,CHIP,A"
					( Origin gPackager )
				)
				( objectStatus "R25W65" )
				( pin "a"
					( attribute "PN" "1"
						( Origin gPackager )
					)
					( objectStatus "R25W65.1" )
				)
				( pin "b"
					( attribute "PN" "2"
						( Origin gPackager )
					)
					( objectStatus "R25W65.2" )
				)
			)
			( gate "@baseboard_fab2_lib.baseboard_fab2(sch_1):page145_i36"
				( attribute "BOM_COST" "SM_CONTROLLER"
					( Origin gFrontEnd )
				)
				( attribute "CDS_LIB" "mstr_discrete"
					( Origin gPackager )
				)
				( attribute "CDS_LOCATION" "R25W64"
					( Origin gPackager )
				)
				( attribute "CDS_SEC" "1"
					( Origin gPackager )
				)
				( attribute "LOCATION" "R25W64"
					( Origin gFrontEnd )
				)
				( attribute "MATERIAL" "CHIP"
					( Origin gFrontEnd )
				)
				( attribute "PACK_TYPE" "0402"
					( Origin gFrontEnd )
				)
				( attribute "PART_NUMBER" "G21796-010"
					( Origin gFrontEnd )
				)
				( attribute "PHYS_PAGE" "145"
					( Origin gFrontEnd )
				)
				( attribute "ROOM" "BMC"
					( Origin gFrontEnd )
				)
				( attribute "ROT" "0"
					( Origin gFrontEnd )
				)
				( attribute "SEC" "1"
					( Origin gFrontEnd )
				)
				( attribute "SEC_TYPE" "0402"
					( Origin gFrontEnd )
				)
				( attribute "TOLERANCE" "1%"
					( Origin gFrontEnd )
				)
				( attribute "VALUE" "100.0K"
					( Origin gFrontEnd )
				)
				( attribute "VER" "2"
					( Origin gFrontEnd )
				)
				( attribute "WATTAGE" "1/16W"
					( Origin gFrontEnd )
				)
				( attribute "XY" "(-5950,-4325)"
					( Origin gFrontEnd )
				)
				( attribute "CHIPS_PART_NAME" "RES"
					( Origin gPackager )
				)
				( attribute "CDS_PART_NAME" "RES_0402-100.0K,1%,1/16W,CHIP,A"
					( Origin gPackager )
				)
				( objectStatus "R25W64" )
				( pin "a"
					( attribute "PN" "1"
						( Origin gPackager )
					)
					( objectStatus "R25W64.1" )
				)
				( pin "b"
					( attribute "PN" "2"
						( Origin gPackager )
					)
					( objectStatus "R25W64.2" )
				)
			)
			( gate "@baseboard_fab2_lib.baseboard_fab2(sch_1):page149_i193"
				( attribute "CDS_LIB" "w_hdl"
					( Origin gPackager )
				)
				( attribute "CDS_LMAN_SYM_OUTLINE" "-50,75,50,-75"
					( Origin gPackager )
				)
				( attribute "LOCATION" "R25W34"
					( Origin gFrontEnd )
				)
				( attribute "PACK_TYPE" "RCL_GP"
					( Origin gFrontEnd )
				)
				( attribute "PART_NUMBER" "64.12005.6DL"
					( Origin gFrontEnd )
				)
				( attribute "PHYS_PAGE" "149"
					( Origin gFrontEnd )
				)
				( attribute "ROT" "1"
					( Origin gFrontEnd )
				)
				( attribute "VALUE" "120R2F-GP"
					( Origin gFrontEnd )
				)
				( attribute "VER" "1"
					( Origin gFrontEnd )
				)
				( attribute "XY" "(-6150,3950)"
					( Origin gFrontEnd )
				)
				( attribute "CHIPS_PART_NAME" "120R2F-GP"
					( Origin gPackager )
				)
				( attribute "CDS_PART_NAME" "120R2F-GP_RCL_GP-120R2F-GP,64.A"
					( Origin gPackager )
				)
				( attribute "CDS_LOCATION" "R25W34"
					( Origin gPackager )
				)
				( attribute "CDS_SEC" "1"
					( Origin gPackager )
				)
				( attribute "SEC" "1"
					( Origin gPackager )
				)
				( objectStatus "R25W34" )
				( pin "\1\"
					( attribute "PN" "1"
						( Origin gPackager )
					)
					( objectStatus "R25W34.1" )
				)
				( pin "\2\"
					( attribute "PN" "2"
						( Origin gPackager )
					)
					( objectStatus "R25W34.2" )
				)
			)
			( gate "@baseboard_fab2_lib.baseboard_fab2(sch_1):page149_i192"
				( attribute "CDS_LIB" "w_hdl"
					( Origin gPackager )
				)
				( attribute "CDS_LMAN_SYM_OUTLINE" "-50,75,50,-75"
					( Origin gPackager )
				)
				( attribute "LOCATION" "R25W33"
					( Origin gFrontEnd )
				)
				( attribute "PACK_TYPE" "RCL_GP"
					( Origin gFrontEnd )
				)
				( attribute "PART_NUMBER" "64.12005.6DL"
					( Origin gFrontEnd )
				)
				( attribute "PHYS_PAGE" "149"
					( Origin gFrontEnd )
				)
				( attribute "ROT" "1"
					( Origin gFrontEnd )
				)
				( attribute "VALUE" "120R2F-GP"
					( Origin gFrontEnd )
				)
				( attribute "VER" "1"
					( Origin gFrontEnd )
				)
				( attribute "XY" "(-6150,4000)"
					( Origin gFrontEnd )
				)
				( attribute "CHIPS_PART_NAME" "120R2F-GP"
					( Origin gPackager )
				)
				( attribute "CDS_PART_NAME" "120R2F-GP_RCL_GP-120R2F-GP,64.A"
					( Origin gPackager )
				)
				( attribute "CDS_LOCATION" "R25W33"
					( Origin gPackager )
				)
				( attribute "CDS_SEC" "1"
					( Origin gPackager )
				)
				( attribute "SEC" "1"
					( Origin gPackager )
				)
				( objectStatus "R25W33" )
				( pin "\1\"
					( attribute "PN" "1"
						( Origin gPackager )
					)
					( objectStatus "R25W33.1" )
				)
				( pin "\2\"
					( attribute "PN" "2"
						( Origin gPackager )
					)
					( objectStatus "R25W33.2" )
				)
			)
			( gate "@baseboard_fab2_lib.baseboard_fab2(sch_1):page149_i191"
				( attribute "CDS_LIB" "w_hdl"
					( Origin gPackager )
				)
				( attribute "CDS_LMAN_SYM_OUTLINE" "-50,75,50,-75"
					( Origin gPackager )
				)
				( attribute "LOCATION" "R25W32"
					( Origin gFrontEnd )
				)
				( attribute "PACK_TYPE" "RCL_GP"
					( Origin gFrontEnd )
				)
				( attribute "PART_NUMBER" "64.12005.6DL"
					( Origin gFrontEnd )
				)
				( attribute "PHYS_PAGE" "149"
					( Origin gFrontEnd )
				)
				( attribute "ROT" "1"
					( Origin gFrontEnd )
				)
				( attribute "VALUE" "120R2F-GP"
					( Origin gFrontEnd )
				)
				( attribute "VER" "1"
					( Origin gFrontEnd )
				)
				( attribute "XY" "(-6150,4050)"
					( Origin gFrontEnd )
				)
				( attribute "CHIPS_PART_NAME" "120R2F-GP"
					( Origin gPackager )
				)
				( attribute "CDS_PART_NAME" "120R2F-GP_RCL_GP-120R2F-GP,64.A"
					( Origin gPackager )
				)
				( attribute "CDS_LOCATION" "R25W32"
					( Origin gPackager )
				)
				( attribute "CDS_SEC" "1"
					( Origin gPackager )
				)
				( attribute "SEC" "1"
					( Origin gPackager )
				)
				( objectStatus "R25W32" )
				( pin "\1\"
					( attribute "PN" "1"
						( Origin gPackager )
					)
					( objectStatus "R25W32.1" )
				)
				( pin "\2\"
					( attribute "PN" "2"
						( Origin gPackager )
					)
					( objectStatus "R25W32.2" )
				)
			)
			( gate "@baseboard_fab2_lib.baseboard_fab2(sch_1):page145_i15"
				( attribute "BOM_COST" "SM_CONTROLLER"
					( Origin gFrontEnd )
				)
				( attribute "CDS_LIB" "dev_discrete"
					( Origin gPackager )
				)
				( attribute "CDS_LOCATION" "C9F23"
					( Origin gPackager )
				)
				( attribute "CDS_SEC" "1"
					( Origin gPackager )
				)
				( attribute "LOCATION" "C9F23"
					( Origin gFrontEnd )
				)
				( attribute "MATERIAL" "X7R"
					( Origin gFrontEnd )
				)
				( attribute "PACK_TYPE" "0402V"
					( Origin gFrontEnd )
				)
				( attribute "PART_NUMBER" "A36096-030"
					( Origin gFrontEnd )
				)
				( attribute "PHYS_PAGE" "145"
					( Origin gFrontEnd )
				)
				( attribute "ROOM" "BMC"
					( Origin gFrontEnd )
				)
				( attribute "ROT" "0"
					( Origin gFrontEnd )
				)
				( attribute "SEC" "1"
					( Origin gFrontEnd )
				)
				( attribute "SEC_TYPE" "0402V"
					( Origin gFrontEnd )
				)
				( attribute "TOLERANCE" "10%"
					( Origin gFrontEnd )
				)
				( attribute "VALUE" "0.1UF"
					( Origin gFrontEnd )
				)
				( attribute "VER" "1"
					( Origin gFrontEnd )
				)
				( attribute "VOLTAGE" "16V"
					( Units "uVoltage" "V" 1.000000)
					( Origin gFrontEnd )
				)
				( attribute "XY" "(-7500,-450)"
					( Origin gFrontEnd )
				)
				( attribute "CHIPS_PART_NAME" "CAP_A"
					( Origin gPackager )
				)
				( attribute "CDS_PART_NAME" "CAP_A_0402V-0.1UF,16V,10%,X7R,A"
					( Origin gPackager )
				)
				( objectStatus "C9F23" )
				( pin "a"
					( attribute "PN" "1"
						( Origin gPackager )
					)
					( objectStatus "C9F23.1" )
				)
				( pin "b"
					( attribute "PN" "2"
						( Origin gPackager )
					)
					( objectStatus "C9F23.2" )
				)
			)
			( gate "@baseboard_fab2_lib.baseboard_fab2(sch_1):page145_i20"
				( attribute "BOM_COST" "SM_CONTROLLER"
					( Origin gFrontEnd )
				)
				( attribute "CDS_LIB" "mstr_discrete"
					( Origin gPackager )
				)
				( attribute "CDS_LOCATION" "R9F33"
					( Origin gPackager )
				)
				( attribute "CDS_SEC" "1"
					( Origin gPackager )
				)
				( attribute "LOCATION" "R9F33"
					( Origin gFrontEnd )
				)
				( attribute "MATERIAL" "CHIP"
					( Origin gFrontEnd )
				)
				( attribute "PACK_TYPE" "0402"
					( Origin gFrontEnd )
				)
				( attribute "PART_NUMBER" "G21497-005"
					( Origin gFrontEnd )
				)
				( attribute "PHYS_PAGE" "145"
					( Origin gFrontEnd )
				)
				( attribute "ROOM" "BMC"
					( Origin gFrontEnd )
				)
				( attribute "ROT" "0"
					( Origin gFrontEnd )
				)
				( attribute "SEC" "1"
					( Origin gFrontEnd )
				)
				( attribute "SEC_TYPE" "0402"
					( Origin gFrontEnd )
				)
				( attribute "TOLERANCE" "5%"
					( Origin gFrontEnd )
				)
				( attribute "VALUE" "0.0"
					( Origin gFrontEnd )
				)
				( attribute "VER" "1"
					( Origin gFrontEnd )
				)
				( attribute "WATTAGE" "1/16W"
					( Origin gFrontEnd )
				)
				( attribute "XY" "(-5925,-3250)"
					( Origin gFrontEnd )
				)
				( attribute "CHIPS_PART_NAME" "RES"
					( Origin gPackager )
				)
				( attribute "CDS_PART_NAME" "RES_0402-0.0,5%,1/16W,CHIP,G21A"
					( Origin gPackager )
				)
				( objectStatus "R9F33" )
				( pin "a"
					( attribute "PN" "1"
						( Origin gPackager )
					)
					( objectStatus "R9F33.1" )
				)
				( pin "b"
					( attribute "PN" "2"
						( Origin gPackager )
					)
					( objectStatus "R9F33.2" )
				)
			)
			( gate "@baseboard_fab2_lib.baseboard_fab2(sch_1):page149_i14"
				( attribute "BOM_COST" "SM_MEM"
					( Origin gFrontEnd )
				)
				( attribute "CDS_LIB" "mstr_discrete"
					( Origin gPackager )
				)
				( attribute "CDS_LOCATION" "R9F34"
					( Origin gPackager )
				)
				( attribute "CDS_SEC" "1"
					( Origin gPackager )
				)
				( attribute "LOCATION" "R9F34"
					( Origin gFrontEnd )
				)
				( attribute "MATERIAL" "CHIP"
					( Origin gFrontEnd )
				)
				( attribute "PACK_TYPE" "0402"
					( Origin gFrontEnd )
				)
				( attribute "PART_NUMBER" "G21796-074"
					( Origin gFrontEnd )
				)
				( attribute "PHYS_PAGE" "149"
					( Origin gFrontEnd )
				)
				( attribute "ROOM" "BMC_MEMORY"
					( Origin gFrontEnd )
				)
				( attribute "ROT" "0"
					( Origin gFrontEnd )
				)
				( attribute "SEC" "1"
					( Origin gFrontEnd )
				)
				( attribute "SEC_TYPE" "0402"
					( Origin gFrontEnd )
				)
				( attribute "TOLERANCE" "1%"
					( Origin gFrontEnd )
				)
				( attribute "VALUE" "33.2"
					( Origin gFrontEnd )
				)
				( attribute "VER" "1"
					( Origin gFrontEnd )
				)
				( attribute "WATTAGE" "1/16W"
					( Origin gFrontEnd )
				)
				( attribute "XY" "(-1375,4600)"
					( Origin gFrontEnd )
				)
				( attribute "CHIPS_PART_NAME" "RES"
					( Origin gPackager )
				)
				( attribute "CDS_PART_NAME" "RES_0402-33.2,1%,1/16W,CHIP,G2A"
					( Origin gPackager )
				)
				( objectStatus "R9F34" )
				( pin "a"
					( attribute "PN" "1"
						( Origin gPackager )
					)
					( objectStatus "R9F34.1" )
				)
				( pin "b"
					( attribute "PN" "2"
						( Origin gPackager )
					)
					( objectStatus "R9F34.2" )
				)
			)
			( gate "@baseboard_fab2_lib.baseboard_fab2(sch_1):page146_i51"
				( attribute "BOM_COST" "SM_CONTROLLER"
					( Origin gFrontEnd )
				)
				( attribute "CDS_LIB" "mstr_discrete"
					( Origin gPackager )
				)
				( attribute "CDS_LOCATION" "R1U52"
					( Origin gPackager )
				)
				( attribute "CDS_SEC" "1"
					( Origin gPackager )
				)
				( attribute "LOCATION" "R1U52"
					( Origin gFrontEnd )
				)
				( attribute "MATERIAL" "CHIP"
					( Origin gFrontEnd )
				)
				( attribute "PACK_TYPE" "0402"
					( Origin gFrontEnd )
				)
				( attribute "PART_NUMBER" "G21796-003"
					( Origin gFrontEnd )
				)
				( attribute "PHYS_PAGE" "146"
					( Origin gFrontEnd )
				)
				( attribute "ROOM" "BMC"
					( Origin gFrontEnd )
				)
				( attribute "ROT" "0"
					( Origin gFrontEnd )
				)
				( attribute "SEC" "1"
					( Origin gPackager )
				)
				( attribute "TOLERANCE" "1%"
					( Origin gFrontEnd )
				)
				( attribute "VALUE" "1.5K"
					( Origin gFrontEnd )
				)
				( attribute "VER" "2"
					( Origin gFrontEnd )
				)
				( attribute "WATTAGE" "1/16W"
					( Origin gFrontEnd )
				)
				( attribute "XY" "(-1750,4725)"
					( Origin gFrontEnd )
				)
				( attribute "CHIPS_PART_NAME" "RES"
					( Origin gPackager )
				)
				( attribute "CDS_PART_NAME" "RES_0402-1.5K,1%,1/16W,CHIP,G2A"
					( Origin gPackager )
				)
				( objectStatus "R1U52" )
				( pin "a"
					( attribute "PN" "1"
						( Origin gPackager )
					)
					( objectStatus "R1U52.1" )
				)
				( pin "b"
					( attribute "PN" "2"
						( Origin gPackager )
					)
					( objectStatus "R1U52.2" )
				)
			)
			( gate "@baseboard_fab2_lib.baseboard_fab2(sch_1):page144_i73"
				( attribute "BOM_COST" "SM_CONTROLLER"
					( Origin gFrontEnd )
				)
				( attribute "CDS_LIB" "mstr_discrete"
					( Origin gPackager )
				)
				( attribute "CDS_LOCATION" "R25W58"
					( Origin gPackager )
				)
				( attribute "CDS_SEC" "1"
					( Origin gPackager )
				)
				( attribute "LOCATION" "R25W58"
					( Origin gFrontEnd )
				)
				( attribute "MATERIAL" "CHIP"
					( Origin gFrontEnd )
				)
				( attribute "PACK_TYPE" "0402"
					( Origin gFrontEnd )
				)
				( attribute "PART_NUMBER" "G21796-344"
					( Origin gFrontEnd )
				)
				( attribute "PHYS_PAGE" "144"
					( Origin gFrontEnd )
				)
				( attribute "ROOM" "BMC"
					( Origin gFrontEnd )
				)
				( attribute "ROT" "0"
					( Origin gFrontEnd )
				)
				( attribute "SEC" "1"
					( Origin gFrontEnd )
				)
				( attribute "SEC_TYPE" "0402"
					( Origin gFrontEnd )
				)
				( attribute "TOLERANCE" "1%"
					( Origin gFrontEnd )
				)
				( attribute "VALUE" "2.7K"
					( Origin gFrontEnd )
				)
				( attribute "VER" "2"
					( Origin gFrontEnd )
				)
				( attribute "WATTAGE" "1/16W"
					( Origin gFrontEnd )
				)
				( attribute "XY" "(-1600,-3550)"
					( Origin gFrontEnd )
				)
				( attribute "CHIPS_PART_NAME" "RES"
					( Origin gPackager )
				)
				( attribute "CDS_PART_NAME" "RES_0402-2.7K,1%,1/16W,CHIP,G2A"
					( Origin gPackager )
				)
				( objectStatus "R25W58" )
				( pin "a"
					( attribute "PN" "1"
						( Origin gPackager )
					)
					( objectStatus "R25W58.1" )
				)
				( pin "b"
					( attribute "PN" "2"
						( Origin gPackager )
					)
					( objectStatus "R25W58.2" )
				)
			)
			( gate "@baseboard_fab2_lib.baseboard_fab2(sch_1):page147_i36"
				( attribute "BOM_COST" "SM_CONTROLLER"
					( Origin gFrontEnd )
				)
				( attribute "CDS_LIB" "mstr_discrete"
					( Origin gPackager )
				)
				( attribute "CDS_LOCATION" "C25W7"
					( Origin gPackager )
				)
				( attribute "CDS_SEC" "1"
					( Origin gPackager )
				)
				( attribute "LOCATION" "C25W7"
					( Origin gFrontEnd )
				)
				( attribute "MATERIAL" "EMPTY"
					( Origin gFrontEnd )
				)
				( attribute "PACK_TYPE" "0402"
					( Origin gFrontEnd )
				)
				( attribute "PART_NUMBER" "A36096-030"
					( Origin gFrontEnd )
				)
				( attribute "PHYS_PAGE" "147"
					( Origin gFrontEnd )
				)
				( attribute "ROOM" "BMC"
					( Origin gFrontEnd )
				)
				( attribute "ROT" "1"
					( Origin gFrontEnd )
				)
				( attribute "SEC" "1"
					( Origin gPackager )
				)
				( attribute "TOLERANCE" "10%"
					( Origin gFrontEnd )
				)
				( attribute "VALUE" "0.1UF"
					( Origin gFrontEnd )
				)
				( attribute "VER" "1"
					( Origin gFrontEnd )
				)
				( attribute "VOLTAGE" "16V"
					( Units "uVoltage" "V" 1.000000)
					( Origin gFrontEnd )
				)
				( attribute "XY" "(2000,2300)"
					( Origin gFrontEnd )
				)
				( attribute "CHIPS_PART_NAME" "CAP"
					( Origin gPackager )
				)
				( attribute "CDS_PART_NAME" "CAP_0402-0.1UF,16V,10%,EMPTY,AA"
					( Origin gPackager )
				)
				( objectStatus "C25W7" )
				( pin "a"
					( attribute "PN" "1"
						( Origin gPackager )
					)
					( objectStatus "C25W7.1" )
				)
				( pin "b"
					( attribute "PN" "2"
						( Origin gPackager )
					)
					( objectStatus "C25W7.2" )
				)
			)
			( gate "@baseboard_fab2_lib.baseboard_fab2(sch_1):page145_i30"
				( attribute "BOM_COST" "SM_CONTROLLER"
					( Origin gFrontEnd )
				)
				( attribute "CDS_LIB" "mstr_discrete"
					( Origin gPackager )
				)
				( attribute "CDS_LOCATION" "R25W61"
					( Origin gPackager )
				)
				( attribute "CDS_SEC" "1"
					( Origin gPackager )
				)
				( attribute "LOCATION" "R25W61"
					( Origin gFrontEnd )
				)
				( attribute "MATERIAL" "CHIP"
					( Origin gFrontEnd )
				)
				( attribute "PACK_TYPE" "0402"
					( Origin gFrontEnd )
				)
				( attribute "PART_NUMBER" "G21796-010"
					( Origin gFrontEnd )
				)
				( attribute "PHYS_PAGE" "145"
					( Origin gFrontEnd )
				)
				( attribute "ROOM" "BMC"
					( Origin gFrontEnd )
				)
				( attribute "ROT" "0"
					( Origin gFrontEnd )
				)
				( attribute "SEC" "1"
					( Origin gFrontEnd )
				)
				( attribute "SEC_TYPE" "0402"
					( Origin gFrontEnd )
				)
				( attribute "TOLERANCE" "1%"
					( Origin gFrontEnd )
				)
				( attribute "VALUE" "100.0K"
					( Origin gFrontEnd )
				)
				( attribute "VER" "2"
					( Origin gFrontEnd )
				)
				( attribute "WATTAGE" "1/16W"
					( Origin gFrontEnd )
				)
				( attribute "XY" "(-5450,-4350)"
					( Origin gFrontEnd )
				)
				( attribute "CHIPS_PART_NAME" "RES"
					( Origin gPackager )
				)
				( attribute "CDS_PART_NAME" "RES_0402-100.0K,1%,1/16W,CHIP,A"
					( Origin gPackager )
				)
				( objectStatus "R25W61" )
				( pin "a"
					( attribute "PN" "1"
						( Origin gPackager )
					)
					( objectStatus "R25W61.1" )
				)
				( pin "b"
					( attribute "PN" "2"
						( Origin gPackager )
					)
					( objectStatus "R25W61.2" )
				)
			)
			( gate "@baseboard_fab2_lib.baseboard_fab2(sch_1):page145_i31"
				( attribute "BOM_COST" "SM_CONTROLLER"
					( Origin gFrontEnd )
				)
				( attribute "CDS_LIB" "mstr_discrete"
					( Origin gPackager )
				)
				( attribute "CDS_LOCATION" "R25W62"
					( Origin gPackager )
				)
				( attribute "CDS_SEC" "1"
					( Origin gPackager )
				)
				( attribute "LOCATION" "R25W62"
					( Origin gFrontEnd )
				)
				( attribute "MATERIAL" "CHIP"
					( Origin gFrontEnd )
				)
				( attribute "PACK_TYPE" "0402"
					( Origin gFrontEnd )
				)
				( attribute "PART_NUMBER" "G21796-010"
					( Origin gFrontEnd )
				)
				( attribute "PHYS_PAGE" "145"
					( Origin gFrontEnd )
				)
				( attribute "ROOM" "BMC"
					( Origin gFrontEnd )
				)
				( attribute "ROT" "0"
					( Origin gFrontEnd )
				)
				( attribute "SEC" "1"
					( Origin gFrontEnd )
				)
				( attribute "SEC_TYPE" "0402"
					( Origin gFrontEnd )
				)
				( attribute "TOLERANCE" "1%"
					( Origin gFrontEnd )
				)
				( attribute "VALUE" "100.0K"
					( Origin gFrontEnd )
				)
				( attribute "VER" "2"
					( Origin gFrontEnd )
				)
				( attribute "WATTAGE" "1/16W"
					( Origin gFrontEnd )
				)
				( attribute "XY" "(-5200,-4350)"
					( Origin gFrontEnd )
				)
				( attribute "CHIPS_PART_NAME" "RES"
					( Origin gPackager )
				)
				( attribute "CDS_PART_NAME" "RES_0402-100.0K,1%,1/16W,CHIP,A"
					( Origin gPackager )
				)
				( objectStatus "R25W62" )
				( pin "a"
					( attribute "PN" "1"
						( Origin gPackager )
					)
					( objectStatus "R25W62.1" )
				)
				( pin "b"
					( attribute "PN" "2"
						( Origin gPackager )
					)
					( objectStatus "R25W62.2" )
				)
			)
			( gate "@baseboard_fab2_lib.baseboard_fab2(sch_1):page151_i69"
				( attribute "CHIPS_PART_NAME" "TTL1G07_A"
					( Origin gPackager )
				)
			)
			( gate "@baseboard_fab2_lib.baseboard_fab2(sch_1):page146_i197"
				( attribute "CHIPS_PART_NAME" "TTL1G07_A"
					( Origin gPackager )
				)
			)
			( gate "@baseboard_fab2_lib.baseboard_fab2(sch_1):page150_i43"
				( attribute "CDS_LIB" "w_hdl"
					( Origin gPackager )
				)
				( attribute "CDS_LMAN_SYM_OUTLINE" "-50,25,50,-25"
					( Origin gPackager )
				)
				( attribute "LOCATION" "C25W30"
					( Origin gFrontEnd )
				)
				( attribute "PACK_TYPE" "SMD-BCG"
					( Origin gFrontEnd )
				)
				( attribute "PART_NUMBER" "78.47523.5BL"
					( Origin gFrontEnd )
				)
				( attribute "PHYS_PAGE" "150"
					( Origin gFrontEnd )
				)
				( attribute "ROT" "0"
					( Origin gFrontEnd )
				)
				( attribute "VALUE" "SC4D7U10V3KX-GP"
					( Origin gFrontEnd )
				)
				( attribute "VER" "1"
					( Origin gFrontEnd )
				)
				( attribute "XY" "(-3675,4975)"
					( Origin gFrontEnd )
				)
				( attribute "CHIPS_PART_NAME" "SC4D7U10V3KX-GP"
					( Origin gPackager )
				)
				( attribute "CDS_PART_NAME" "SC4D7U10V3KX-GP_SMD-BCG-SC4D7UA"
					( Origin gPackager )
				)
				( attribute "CDS_LOCATION" "C25W30"
					( Origin gPackager )
				)
				( attribute "CDS_SEC" "1"
					( Origin gPackager )
				)
				( attribute "SEC" "1"
					( Origin gPackager )
				)
				( objectStatus "C25W30" )
				( pin "\1\"
					( attribute "PN" "1"
						( Origin gPackager )
					)
					( objectStatus "C25W30.1" )
				)
				( pin "\2\"
					( attribute "PN" "2"
						( Origin gPackager )
					)
					( objectStatus "C25W30.2" )
				)
			)
			( gate "@baseboard_fab2_lib.baseboard_fab2(sch_1):page150_i39"
				( attribute "CDS_LIB" "w_hdl"
					( Origin gPackager )
				)
				( attribute "CDS_LMAN_SYM_OUTLINE" "-50,100,50,-100"
					( Origin gPackager )
				)
				( attribute "LOCATION" "FB2T7"
					( Origin gFrontEnd )
				)
				( attribute "PACK_TYPE" "DISCRET-G9"
					( Origin gFrontEnd )
				)
				( attribute "PART_NUMBER" "68.00230.231"
					( Origin gFrontEnd )
				)
				( attribute "PHYS_PAGE" "150"
					( Origin gFrontEnd )
				)
				( attribute "ROT" "1"
					( Origin gFrontEnd )
				)
				( attribute "VALUE" "HCB1608KF-800T30-GP"
					( Origin gFrontEnd )
				)
				( attribute "VER" "1"
					( Origin gFrontEnd )
				)
				( attribute "XY" "(-1900,3875)"
					( Origin gFrontEnd )
				)
				( attribute "CHIPS_PART_NAME" "HCB1608KF-800T30-GP"
					( Origin gPackager )
				)
				( attribute "CDS_PART_NAME" "HCB1608KF-800T30-GP_DISCRET-G9A"
					( Origin gPackager )
				)
				( attribute "CDS_LOCATION" "FB2T7"
					( Origin gPackager )
				)
				( attribute "CDS_SEC" "1"
					( Origin gPackager )
				)
				( attribute "SEC" "1"
					( Origin gPackager )
				)
				( objectStatus "FB2T7" )
				( pin "\1\"
					( attribute "PN" "1"
						( Origin gPackager )
					)
					( objectStatus "FB2T7.1" )
				)
				( pin "\2\"
					( attribute "PN" "2"
						( Origin gPackager )
					)
					( objectStatus "FB2T7.2" )
				)
			)
			( gate "@baseboard_fab2_lib.baseboard_fab2(sch_1):page150_i38"
				( attribute "BOM_COST" "SM_CONTROLLER"
					( Origin gFrontEnd )
				)
				( attribute "CDS_LIB" "mstr_discrete"
					( Origin gPackager )
				)
				( attribute "LOCATION" "C25W48"
					( Origin gFrontEnd )
				)
				( attribute "MATERIAL" "X6S"
					( Origin gFrontEnd )
				)
				( attribute "PACK_TYPE" "0402"
					( Origin gFrontEnd )
				)
				( attribute "PART_NUMBER" "D97712-004"
					( Origin gFrontEnd )
				)
				( attribute "PHYS_PAGE" "150"
					( Origin gFrontEnd )
				)
				( attribute "ROOM" "BMC"
					( Origin gFrontEnd )
				)
				( attribute "ROT" "0"
					( Origin gFrontEnd )
				)
				( attribute "TOLERANCE" "10%"
					( Origin gFrontEnd )
				)
				( attribute "VALUE" "1.0UF"
					( Origin gFrontEnd )
				)
				( attribute "VER" "1"
					( Origin gFrontEnd )
				)
				( attribute "VOLTAGE" "6.3V"
					( Units "uVoltage" "V" 1.000000)
					( Origin gFrontEnd )
				)
				( attribute "XY" "(-1900,2550)"
					( Origin gFrontEnd )
				)
				( attribute "CHIPS_PART_NAME" "CAP"
					( Origin gPackager )
				)
				( attribute "CDS_PART_NAME" "CAP_0402-1.0UF,6.3V,10%,X6S,D9A"
					( Origin gPackager )
				)
				( attribute "CDS_LOCATION" "C25W48"
					( Origin gPackager )
				)
				( attribute "CDS_SEC" "1"
					( Origin gPackager )
				)
				( attribute "SEC" "1"
					( Origin gPackager )
				)
				( objectStatus "C25W48" )
				( pin "a"
					( attribute "PN" "1"
						( Origin gPackager )
					)
					( objectStatus "C25W48.1" )
				)
				( pin "b"
					( attribute "PN" "2"
						( Origin gPackager )
					)
					( objectStatus "C25W48.2" )
				)
			)
			( gate "@baseboard_fab2_lib.baseboard_fab2(sch_1):page150_i36"
				( attribute "CDS_LIB" "w_hdl"
					( Origin gPackager )
				)
				( attribute "CDS_LMAN_SYM_OUTLINE" "-50,25,50,-25"
					( Origin gPackager )
				)
				( attribute "LOCATION" "C25W49"
					( Origin gFrontEnd )
				)
				( attribute "PACK_TYPE" "SMD-BCG"
					( Origin gFrontEnd )
				)
				( attribute "PART_NUMBER" "78.10421.2FL"
					( Origin gFrontEnd )
				)
				( attribute "PHYS_PAGE" "150"
					( Origin gFrontEnd )
				)
				( attribute "ROT" "0"
					( Origin gFrontEnd )
				)
				( attribute "VALUE" "SCD1U16V2KX-3GP"
					( Origin gFrontEnd )
				)
				( attribute "VER" "1"
					( Origin gFrontEnd )
				)
				( attribute "XY" "(-1350,2575)"
					( Origin gFrontEnd )
				)
				( attribute "CHIPS_PART_NAME" "SCD1U16V2KX-3GP"
					( Origin gPackager )
				)
				( attribute "CDS_PART_NAME" "SCD1U16V2KX-3GP_SMD-BCG-SCD1U1A"
					( Origin gPackager )
				)
				( attribute "CDS_LOCATION" "C25W49"
					( Origin gPackager )
				)
				( attribute "CDS_SEC" "1"
					( Origin gPackager )
				)
				( attribute "SEC" "1"
					( Origin gPackager )
				)
				( objectStatus "C25W49" )
				( pin "\1\"
					( attribute "PN" "1"
						( Origin gPackager )
					)
					( objectStatus "C25W49.1" )
				)
				( pin "\2\"
					( attribute "PN" "2"
						( Origin gPackager )
					)
					( objectStatus "C25W49.2" )
				)
			)
			( gate "@baseboard_fab2_lib.baseboard_fab2(sch_1):page150_i35"
				( attribute "BOM_COST" "SM_CONTROLLER"
					( Origin gFrontEnd )
				)
				( attribute "CDS_LIB" "mstr_discrete"
					( Origin gPackager )
				)
				( attribute "LOCATION" "C25W37"
					( Origin gFrontEnd )
				)
				( attribute "MATERIAL" "X6S"
					( Origin gFrontEnd )
				)
				( attribute "PACK_TYPE" "0402"
					( Origin gFrontEnd )
				)
				( attribute "PART_NUMBER" "D97712-004"
					( Origin gFrontEnd )
				)
				( attribute "PHYS_PAGE" "150"
					( Origin gFrontEnd )
				)
				( attribute "ROOM" "BMC"
					( Origin gFrontEnd )
				)
				( attribute "ROT" "0"
					( Origin gFrontEnd )
				)
				( attribute "TOLERANCE" "10%"
					( Origin gFrontEnd )
				)
				( attribute "VALUE" "1.0UF"
					( Origin gFrontEnd )
				)
				( attribute "VER" "1"
					( Origin gFrontEnd )
				)
				( attribute "VOLTAGE" "6.3V"
					( Units "uVoltage" "V" 1.000000)
					( Origin gFrontEnd )
				)
				( attribute "XY" "(-1450,3525)"
					( Origin gFrontEnd )
				)
				( attribute "CHIPS_PART_NAME" "CAP"
					( Origin gPackager )
				)
				( attribute "CDS_PART_NAME" "CAP_0402-1.0UF,6.3V,10%,X6S,D9A"
					( Origin gPackager )
				)
				( attribute "CDS_LOCATION" "C25W37"
					( Origin gPackager )
				)
				( attribute "CDS_SEC" "1"
					( Origin gPackager )
				)
				( attribute "SEC" "1"
					( Origin gPackager )
				)
				( objectStatus "C25W37" )
				( pin "a"
					( attribute "PN" "1"
						( Origin gPackager )
					)
					( objectStatus "C25W37.1" )
				)
				( pin "b"
					( attribute "PN" "2"
						( Origin gPackager )
					)
					( objectStatus "C25W37.2" )
				)
			)
			( gate "@baseboard_fab2_lib.baseboard_fab2(sch_1):page150_i33"
				( attribute "BOM_COST" "SM_CONTROLLER"
					( Origin gFrontEnd )
				)
				( attribute "CDS_LIB" "mstr_discrete"
					( Origin gPackager )
				)
				( attribute "LOCATION" "C25W66"
					( Origin gFrontEnd )
				)
				( attribute "MATERIAL" "X6S"
					( Origin gFrontEnd )
				)
				( attribute "PACK_TYPE" "0402"
					( Origin gFrontEnd )
				)
				( attribute "PART_NUMBER" "D97712-004"
					( Origin gFrontEnd )
				)
				( attribute "PHYS_PAGE" "150"
					( Origin gFrontEnd )
				)
				( attribute "ROOM" "BMC"
					( Origin gFrontEnd )
				)
				( attribute "ROT" "0"
					( Origin gFrontEnd )
				)
				( attribute "TOLERANCE" "10%"
					( Origin gFrontEnd )
				)
				( attribute "VALUE" "1.0UF"
					( Origin gFrontEnd )
				)
				( attribute "VER" "1"
					( Origin gFrontEnd )
				)
				( attribute "VOLTAGE" "6.3V"
					( Units "uVoltage" "V" 1.000000)
					( Origin gFrontEnd )
				)
				( attribute "XY" "(-2075,4725)"
					( Origin gFrontEnd )
				)
				( attribute "CHIPS_PART_NAME" "CAP"
					( Origin gPackager )
				)
				( attribute "CDS_PART_NAME" "CAP_0402-1.0UF,6.3V,10%,X6S,D9A"
					( Origin gPackager )
				)
				( attribute "CDS_LOCATION" "C25W66"
					( Origin gPackager )
				)
				( attribute "CDS_SEC" "1"
					( Origin gPackager )
				)
				( attribute "SEC" "1"
					( Origin gPackager )
				)
				( objectStatus "C25W66" )
				( pin "a"
					( attribute "PN" "1"
						( Origin gPackager )
					)
					( objectStatus "C25W66.1" )
				)
				( pin "b"
					( attribute "PN" "2"
						( Origin gPackager )
					)
					( objectStatus "C25W66.2" )
				)
			)
			( gate "@baseboard_fab2_lib.baseboard_fab2(sch_1):page150_i32"
				( attribute "CDS_LIB" "w_hdl"
					( Origin gPackager )
				)
				( attribute "CDS_LMAN_SYM_OUTLINE" "-50,100,50,-100"
					( Origin gPackager )
				)
				( attribute "LOCATION" "FB2T1"
					( Origin gFrontEnd )
				)
				( attribute "PACK_TYPE" "DISCRET-G9"
					( Origin gFrontEnd )
				)
				( attribute "PART_NUMBER" "68.00230.231"
					( Origin gFrontEnd )
				)
				( attribute "PHYS_PAGE" "150"
					( Origin gFrontEnd )
				)
				( attribute "ROT" "1"
					( Origin gFrontEnd )
				)
				( attribute "VALUE" "HCB1608KF-800T30-GP"
					( Origin gFrontEnd )
				)
				( attribute "VER" "1"
					( Origin gFrontEnd )
				)
				( attribute "XY" "(-2725,5075)"
					( Origin gFrontEnd )
				)
				( attribute "CHIPS_PART_NAME" "HCB1608KF-800T30-GP"
					( Origin gPackager )
				)
				( attribute "CDS_PART_NAME" "HCB1608KF-800T30-GP_DISCRET-G9A"
					( Origin gPackager )
				)
				( attribute "CDS_LOCATION" "FB2T1"
					( Origin gPackager )
				)
				( attribute "CDS_SEC" "1"
					( Origin gPackager )
				)
				( attribute "SEC" "1"
					( Origin gPackager )
				)
				( objectStatus "FB2T1" )
				( pin "\1\"
					( attribute "PN" "1"
						( Origin gPackager )
					)
					( objectStatus "FB2T1.1" )
				)
				( pin "\2\"
					( attribute "PN" "2"
						( Origin gPackager )
					)
					( objectStatus "FB2T1.2" )
				)
			)
			( gate "@baseboard_fab2_lib.baseboard_fab2(sch_1):page151_i9"
				( attribute "BOM_COST" "SM_CONTROLLER"
					( Origin gFrontEnd )
				)
				( attribute "CDS_LIB" "mstr_discrete"
					( Origin gPackager )
				)
				( attribute "CDS_LOCATION" "R25W94"
					( Origin gPackager )
				)
				( attribute "CDS_SEC" "1"
					( Origin gPackager )
				)
				( attribute "LOCATION" "R25W94"
					( Origin gFrontEnd )
				)
				( attribute "MATERIAL" "CHIP"
					( Origin gFrontEnd )
				)
				( attribute "PACK_TYPE" "0402"
					( Origin gFrontEnd )
				)
				( attribute "PART_NUMBER" "G21796-072"
					( Origin gFrontEnd )
				)
				( attribute "PHYS_PAGE" "151"
					( Origin gFrontEnd )
				)
				( attribute "ROOM" "BMC"
					( Origin gFrontEnd )
				)
				( attribute "ROT" "0"
					( Origin gFrontEnd )
				)
				( attribute "SEC" "1"
					( Origin gFrontEnd )
				)
				( attribute "SEC_TYPE" "0402"
					( Origin gFrontEnd )
				)
				( attribute "TOLERANCE" "1%"
					( Origin gFrontEnd )
				)
				( attribute "VALUE" "4.75K"
					( Origin gFrontEnd )
				)
				( attribute "VER" "1"
					( Origin gFrontEnd )
				)
				( attribute "WATTAGE" "1/16W"
					( Origin gFrontEnd )
				)
				( attribute "XY" "(-6900,4675)"
					( Origin gFrontEnd )
				)
				( attribute "CHIPS_PART_NAME" "RES"
					( Origin gPackager )
				)
				( attribute "CDS_PART_NAME" "RES_0402-4.75K,1%,1/16W,CHIP,GA"
					( Origin gPackager )
				)
				( objectStatus "R25W94" )
				( pin "a"
					( attribute "PN" "1"
						( Origin gPackager )
					)
					( objectStatus "R25W94.1" )
				)
				( pin "b"
					( attribute "PN" "2"
						( Origin gPackager )
					)
					( objectStatus "R25W94.2" )
				)
			)
			( gate "@baseboard_fab2_lib.baseboard_fab2(sch_1):page150_i31"
				( attribute "BOM_COST" "SM_CONTROLLER"
					( Origin gFrontEnd )
				)
				( attribute "CDS_LIB" "mstr_discrete"
					( Origin gPackager )
				)
				( attribute "LOCATION" "C25W67"
					( Origin gFrontEnd )
				)
				( attribute "MATERIAL" "X6S"
					( Origin gFrontEnd )
				)
				( attribute "PACK_TYPE" "0402"
					( Origin gFrontEnd )
				)
				( attribute "PART_NUMBER" "D97712-004"
					( Origin gFrontEnd )
				)
				( attribute "PHYS_PAGE" "150"
					( Origin gFrontEnd )
				)
				( attribute "ROOM" "BMC"
					( Origin gFrontEnd )
				)
				( attribute "ROT" "0"
					( Origin gFrontEnd )
				)
				( attribute "TOLERANCE" "10%"
					( Origin gFrontEnd )
				)
				( attribute "VALUE" "1.0UF"
					( Origin gFrontEnd )
				)
				( attribute "VER" "1"
					( Origin gFrontEnd )
				)
				( attribute "VOLTAGE" "6.3V"
					( Units "uVoltage" "V" 1.000000)
					( Origin gFrontEnd )
				)
				( attribute "XY" "(-1825,4725)"
					( Origin gFrontEnd )
				)
				( attribute "CHIPS_PART_NAME" "CAP"
					( Origin gPackager )
				)
				( attribute "CDS_PART_NAME" "CAP_0402-1.0UF,6.3V,10%,X6S,D9A"
					( Origin gPackager )
				)
				( attribute "CDS_LOCATION" "C25W67"
					( Origin gPackager )
				)
				( attribute "CDS_SEC" "1"
					( Origin gPackager )
				)
				( attribute "SEC" "1"
					( Origin gPackager )
				)
				( objectStatus "C25W67" )
				( pin "a"
					( attribute "PN" "1"
						( Origin gPackager )
					)
					( objectStatus "C25W67.1" )
				)
				( pin "b"
					( attribute "PN" "2"
						( Origin gPackager )
					)
					( objectStatus "C25W67.2" )
				)
			)
			( gate "@baseboard_fab2_lib.baseboard_fab2(sch_1):page150_i30"
				( attribute "CDS_LIB" "w_hdl"
					( Origin gPackager )
				)
				( attribute "CDS_LMAN_SYM_OUTLINE" "-50,25,50,-25"
					( Origin gPackager )
				)
				( attribute "LOCATION" "C25W68"
					( Origin gFrontEnd )
				)
				( attribute "PACK_TYPE" "SMD-BCG"
					( Origin gFrontEnd )
				)
				( attribute "PART_NUMBER" "78.10421.2FL"
					( Origin gFrontEnd )
				)
				( attribute "PHYS_PAGE" "150"
					( Origin gFrontEnd )
				)
				( attribute "ROT" "0"
					( Origin gFrontEnd )
				)
				( attribute "VALUE" "SCD1U16V2KX-3GP"
					( Origin gFrontEnd )
				)
				( attribute "VER" "1"
					( Origin gFrontEnd )
				)
				( attribute "XY" "(-1525,4750)"
					( Origin gFrontEnd )
				)
				( attribute "CHIPS_PART_NAME" "SCD1U16V2KX-3GP"
					( Origin gPackager )
				)
				( attribute "CDS_PART_NAME" "SCD1U16V2KX-3GP_SMD-BCG-SCD1U1A"
					( Origin gPackager )
				)
				( attribute "CDS_LOCATION" "C25W68"
					( Origin gPackager )
				)
				( attribute "CDS_SEC" "1"
					( Origin gPackager )
				)
				( attribute "SEC" "1"
					( Origin gPackager )
				)
				( objectStatus "C25W68" )
				( pin "\1\"
					( attribute "PN" "1"
						( Origin gPackager )
					)
					( objectStatus "C25W68.1" )
				)
				( pin "\2\"
					( attribute "PN" "2"
						( Origin gPackager )
					)
					( objectStatus "C25W68.2" )
				)
			)
			( gate "@baseboard_fab2_lib.baseboard_fab2(sch_1):page151_i10"
				( attribute "BOM_COST" "SM_CONTROLLER"
					( Origin gFrontEnd )
				)
				( attribute "CDS_LIB" "mstr_discrete"
					( Origin gPackager )
				)
				( attribute "LOCATION" "R25W96"
					( Origin gFrontEnd )
				)
				( attribute "MATERIAL" "CHIP"
					( Origin gFrontEnd )
				)
				( attribute "PACK_TYPE" "0402"
					( Origin gFrontEnd )
				)
				( attribute "PART_NUMBER" "G21796-072"
					( Origin gFrontEnd )
				)
				( attribute "PHYS_PAGE" "151"
					( Origin gFrontEnd )
				)
				( attribute "ROOM" "BMC"
					( Origin gFrontEnd )
				)
				( attribute "ROT" "0"
					( Origin gFrontEnd )
				)
				( attribute "TOLERANCE" "1%"
					( Origin gFrontEnd )
				)
				( attribute "VALUE" "4.75K"
					( Origin gFrontEnd )
				)
				( attribute "VER" "1"
					( Origin gFrontEnd )
				)
				( attribute "WATTAGE" "1/16W"
					( Origin gFrontEnd )
				)
				( attribute "XY" "(-6900,4425)"
					( Origin gFrontEnd )
				)
				( attribute "CHIPS_PART_NAME" "RES"
					( Origin gPackager )
				)
				( attribute "CDS_PART_NAME" "RES_0402-4.75K,1%,1/16W,CHIP,GA"
					( Origin gPackager )
				)
				( attribute "CDS_LOCATION" "R25W96"
					( Origin gPackager )
				)
				( attribute "CDS_SEC" "1"
					( Origin gPackager )
				)
				( attribute "SEC" "1"
					( Origin gPackager )
				)
				( objectStatus "R25W96" )
				( pin "a"
					( attribute "PN" "1"
						( Origin gPackager )
					)
					( objectStatus "R25W96.1" )
				)
				( pin "b"
					( attribute "PN" "2"
						( Origin gPackager )
					)
					( objectStatus "R25W96.2" )
				)
			)
			( gate "@baseboard_fab2_lib.baseboard_fab2(sch_1):page150_i28"
				( attribute "CDS_LIB" "w_hdl"
					( Origin gPackager )
				)
				( attribute "CDS_LMAN_SYM_OUTLINE" "-50,25,50,-25"
					( Origin gPackager )
				)
				( attribute "LOCATION" "C25W69"
					( Origin gFrontEnd )
				)
				( attribute "PACK_TYPE" "SMD-BCG"
					( Origin gFrontEnd )
				)
				( attribute "PART_NUMBER" "78.47523.5BL"
					( Origin gFrontEnd )
				)
				( attribute "PHYS_PAGE" "150"
					( Origin gFrontEnd )
				)
				( attribute "ROT" "0"
					( Origin gFrontEnd )
				)
				( attribute "VALUE" "SC4D7U10V3KX-GP"
					( Origin gFrontEnd )
				)
				( attribute "VER" "1"
					( Origin gFrontEnd )
				)
				( attribute "XY" "(-1125,4750)"
					( Origin gFrontEnd )
				)
				( attribute "CHIPS_PART_NAME" "SC4D7U10V3KX-GP"
					( Origin gPackager )
				)
				( attribute "CDS_PART_NAME" "SC4D7U10V3KX-GP_SMD-BCG-SC4D7UA"
					( Origin gPackager )
				)
				( attribute "CDS_LOCATION" "C25W69"
					( Origin gPackager )
				)
				( attribute "CDS_SEC" "1"
					( Origin gPackager )
				)
				( attribute "SEC" "1"
					( Origin gPackager )
				)
				( objectStatus "C25W69" )
				( pin "\1\"
					( attribute "PN" "1"
						( Origin gPackager )
					)
					( objectStatus "C25W69.1" )
				)
				( pin "\2\"
					( attribute "PN" "2"
						( Origin gPackager )
					)
					( objectStatus "C25W69.2" )
				)
			)
			( gate "@baseboard_fab2_lib.baseboard_fab2(sch_1):page150_i26"
				( attribute "CDS_LIB" "w_hdl"
					( Origin gPackager )
				)
				( attribute "CDS_LMAN_SYM_OUTLINE" "-50,100,50,-100"
					( Origin gPackager )
				)
				( attribute "LOCATION" "FB2T6"
					( Origin gFrontEnd )
				)
				( attribute "PACK_TYPE" "DISCRET-G9"
					( Origin gFrontEnd )
				)
				( attribute "PART_NUMBER" "68.00230.231"
					( Origin gFrontEnd )
				)
				( attribute "PHYS_PAGE" "150"
					( Origin gFrontEnd )
				)
				( attribute "ROT" "1"
					( Origin gFrontEnd )
				)
				( attribute "VALUE" "HCB1608KF-800T30-GP"
					( Origin gFrontEnd )
				)
				( attribute "VER" "1"
					( Origin gFrontEnd )
				)
				( attribute "XY" "(-850,1775)"
					( Origin gFrontEnd )
				)
				( attribute "CHIPS_PART_NAME" "HCB1608KF-800T30-GP"
					( Origin gPackager )
				)
				( attribute "CDS_PART_NAME" "HCB1608KF-800T30-GP_DISCRET-G9A"
					( Origin gPackager )
				)
				( attribute "CDS_LOCATION" "FB2T6"
					( Origin gPackager )
				)
				( attribute "CDS_SEC" "1"
					( Origin gPackager )
				)
				( attribute "SEC" "1"
					( Origin gPackager )
				)
				( objectStatus "FB2T6" )
				( pin "\1\"
					( attribute "PN" "1"
						( Origin gPackager )
					)
					( objectStatus "FB2T6.1" )
				)
				( pin "\2\"
					( attribute "PN" "2"
						( Origin gPackager )
					)
					( objectStatus "FB2T6.2" )
				)
			)
			( gate "@baseboard_fab2_lib.baseboard_fab2(sch_1):page150_i25"
				( attribute "BOM_COST" "SM_CONTROLLER"
					( Origin gFrontEnd )
				)
				( attribute "CDS_LIB" "mstr_discrete"
					( Origin gPackager )
				)
				( attribute "LOCATION" "C25W63"
					( Origin gFrontEnd )
				)
				( attribute "MATERIAL" "X6S"
					( Origin gFrontEnd )
				)
				( attribute "PACK_TYPE" "0402"
					( Origin gFrontEnd )
				)
				( attribute "PART_NUMBER" "D97712-004"
					( Origin gFrontEnd )
				)
				( attribute "PHYS_PAGE" "150"
					( Origin gFrontEnd )
				)
				( attribute "ROOM" "BMC"
					( Origin gFrontEnd )
				)
				( attribute "ROT" "0"
					( Origin gFrontEnd )
				)
				( attribute "TOLERANCE" "10%"
					( Origin gFrontEnd )
				)
				( attribute "VALUE" "1.0UF"
					( Origin gFrontEnd )
				)
				( attribute "VER" "1"
					( Origin gFrontEnd )
				)
				( attribute "VOLTAGE" "6.3V"
					( Units "uVoltage" "V" 1.000000)
					( Origin gFrontEnd )
				)
				( attribute "XY" "(-300,1425)"
					( Origin gFrontEnd )
				)
				( attribute "CHIPS_PART_NAME" "CAP"
					( Origin gPackager )
				)
				( attribute "CDS_PART_NAME" "CAP_0402-1.0UF,6.3V,10%,X6S,D9A"
					( Origin gPackager )
				)
				( attribute "CDS_LOCATION" "C25W63"
					( Origin gPackager )
				)
				( attribute "CDS_SEC" "1"
					( Origin gPackager )
				)
				( attribute "SEC" "1"
					( Origin gPackager )
				)
				( objectStatus "C25W63" )
				( pin "a"
					( attribute "PN" "1"
						( Origin gPackager )
					)
					( objectStatus "C25W63.1" )
				)
				( pin "b"
					( attribute "PN" "2"
						( Origin gPackager )
					)
					( objectStatus "C25W63.2" )
				)
			)
			( gate "@baseboard_fab2_lib.baseboard_fab2(sch_1):page150_i24"
				( attribute "CDS_LIB" "w_hdl"
					( Origin gPackager )
				)
				( attribute "CDS_LMAN_SYM_OUTLINE" "-50,25,50,-25"
					( Origin gPackager )
				)
				( attribute "LOCATION" "C25W64"
					( Origin gFrontEnd )
				)
				( attribute "PACK_TYPE" "SMD-BCG"
					( Origin gFrontEnd )
				)
				( attribute "PART_NUMBER" "78.10421.2FL"
					( Origin gFrontEnd )
				)
				( attribute "PHYS_PAGE" "150"
					( Origin gFrontEnd )
				)
				( attribute "ROT" "0"
					( Origin gFrontEnd )
				)
				( attribute "VALUE" "SCD1U16V2KX-3GP"
					( Origin gFrontEnd )
				)
				( attribute "VER" "1"
					( Origin gFrontEnd )
				)
				( attribute "XY" "(250,1450)"
					( Origin gFrontEnd )
				)
				( attribute "CHIPS_PART_NAME" "SCD1U16V2KX-3GP"
					( Origin gPackager )
				)
				( attribute "CDS_PART_NAME" "SCD1U16V2KX-3GP_SMD-BCG-SCD1U1A"
					( Origin gPackager )
				)
				( attribute "CDS_LOCATION" "C25W64"
					( Origin gPackager )
				)
				( attribute "CDS_SEC" "1"
					( Origin gPackager )
				)
				( attribute "SEC" "1"
					( Origin gPackager )
				)
				( objectStatus "C25W64" )
				( pin "\1\"
					( attribute "PN" "1"
						( Origin gPackager )
					)
					( objectStatus "C25W64.1" )
				)
				( pin "\2\"
					( attribute "PN" "2"
						( Origin gPackager )
					)
					( objectStatus "C25W64.2" )
				)
			)
			( gate "@baseboard_fab2_lib.baseboard_fab2(sch_1):page150_i21"
				( attribute "CDS_LIB" "w_hdl"
					( Origin gPackager )
				)
				( attribute "CDS_LMAN_SYM_OUTLINE" "-50,25,50,-25"
					( Origin gPackager )
				)
				( attribute "LOCATION" "C25W50"
					( Origin gFrontEnd )
				)
				( attribute "PACK_TYPE" "SMD-BCG"
					( Origin gFrontEnd )
				)
				( attribute "PART_NUMBER" "78.47523.5BL"
					( Origin gFrontEnd )
				)
				( attribute "PHYS_PAGE" "150"
					( Origin gFrontEnd )
				)
				( attribute "ROT" "0"
					( Origin gFrontEnd )
				)
				( attribute "VALUE" "SC4D7U10V3KX-GP"
					( Origin gFrontEnd )
				)
				( attribute "VER" "1"
					( Origin gFrontEnd )
				)
				( attribute "XY" "(-950,2575)"
					( Origin gFrontEnd )
				)
				( attribute "CHIPS_PART_NAME" "SC4D7U10V3KX-GP"
					( Origin gPackager )
				)
				( attribute "CDS_PART_NAME" "SC4D7U10V3KX-GP_SMD-BCG-SC4D7UA"
					( Origin gPackager )
				)
				( attribute "CDS_LOCATION" "C25W50"
					( Origin gPackager )
				)
				( attribute "CDS_SEC" "1"
					( Origin gPackager )
				)
				( attribute "SEC" "1"
					( Origin gPackager )
				)
				( objectStatus "C25W50" )
				( pin "\1\"
					( attribute "PN" "1"
						( Origin gPackager )
					)
					( objectStatus "C25W50.1" )
				)
				( pin "\2\"
					( attribute "PN" "2"
						( Origin gPackager )
					)
					( objectStatus "C25W50.2" )
				)
			)
			( gate "@baseboard_fab2_lib.baseboard_fab2(sch_1):page150_i19"
				( attribute "BOM_COST" "SM_CONTROLLER"
					( Origin gFrontEnd )
				)
				( attribute "CDS_LIB" "mstr_discrete"
					( Origin gPackager )
				)
				( attribute "LOCATION" "C25W51"
					( Origin gFrontEnd )
				)
				( attribute "MATERIAL" "X6S"
					( Origin gFrontEnd )
				)
				( attribute "PACK_TYPE" "0402"
					( Origin gFrontEnd )
				)
				( attribute "PART_NUMBER" "D97712-004"
					( Origin gFrontEnd )
				)
				( attribute "PHYS_PAGE" "150"
					( Origin gFrontEnd )
				)
				( attribute "ROOM" "BMC"
					( Origin gFrontEnd )
				)
				( attribute "ROT" "0"
					( Origin gFrontEnd )
				)
				( attribute "TOLERANCE" "10%"
					( Origin gFrontEnd )
				)
				( attribute "VALUE" "1.0UF"
					( Origin gFrontEnd )
				)
				( attribute "VER" "1"
					( Origin gFrontEnd )
				)
				( attribute "VOLTAGE" "6.3V"
					( Units "uVoltage" "V" 1.000000)
					( Origin gFrontEnd )
				)
				( attribute "XY" "(-275,2475)"
					( Origin gFrontEnd )
				)
				( attribute "CHIPS_PART_NAME" "CAP"
					( Origin gPackager )
				)
				( attribute "CDS_PART_NAME" "CAP_0402-1.0UF,6.3V,10%,X6S,D9A"
					( Origin gPackager )
				)
				( attribute "CDS_LOCATION" "C25W51"
					( Origin gPackager )
				)
				( attribute "CDS_SEC" "1"
					( Origin gPackager )
				)
				( attribute "SEC" "1"
					( Origin gPackager )
				)
				( objectStatus "C25W51" )
				( pin "a"
					( attribute "PN" "1"
						( Origin gPackager )
					)
					( objectStatus "C25W51.1" )
				)
				( pin "b"
					( attribute "PN" "2"
						( Origin gPackager )
					)
					( objectStatus "C25W51.2" )
				)
			)
			( gate "@baseboard_fab2_lib.baseboard_fab2(sch_1):page150_i18"
				( attribute "CDS_LIB" "w_hdl"
					( Origin gPackager )
				)
				( attribute "CDS_LMAN_SYM_OUTLINE" "-50,25,50,-25"
					( Origin gPackager )
				)
				( attribute "LOCATION" "C25W38"
					( Origin gFrontEnd )
				)
				( attribute "PACK_TYPE" "SMD-BCG"
					( Origin gFrontEnd )
				)
				( attribute "PART_NUMBER" "78.10421.2FL"
					( Origin gFrontEnd )
				)
				( attribute "PHYS_PAGE" "150"
					( Origin gFrontEnd )
				)
				( attribute "ROT" "0"
					( Origin gFrontEnd )
				)
				( attribute "VALUE" "SCD1U16V2KX-3GP"
					( Origin gFrontEnd )
				)
				( attribute "VER" "1"
					( Origin gFrontEnd )
				)
				( attribute "XY" "(-900,3550)"
					( Origin gFrontEnd )
				)
				( attribute "CHIPS_PART_NAME" "SCD1U16V2KX-3GP"
					( Origin gPackager )
				)
				( attribute "CDS_PART_NAME" "SCD1U16V2KX-3GP_SMD-BCG-SCD1U1A"
					( Origin gPackager )
				)
				( attribute "CDS_LOCATION" "C25W38"
					( Origin gPackager )
				)
				( attribute "CDS_SEC" "1"
					( Origin gPackager )
				)
				( attribute "SEC" "1"
					( Origin gPackager )
				)
				( objectStatus "C25W38" )
				( pin "\1\"
					( attribute "PN" "1"
						( Origin gPackager )
					)
					( objectStatus "C25W38.1" )
				)
				( pin "\2\"
					( attribute "PN" "2"
						( Origin gPackager )
					)
					( objectStatus "C25W38.2" )
				)
			)
			( gate "@baseboard_fab2_lib.baseboard_fab2(sch_1):page150_i17"
				( attribute "CDS_LIB" "w_hdl"
					( Origin gPackager )
				)
				( attribute "CDS_LMAN_SYM_OUTLINE" "-50,25,50,-25"
					( Origin gPackager )
				)
				( attribute "LOCATION" "C25W39"
					( Origin gFrontEnd )
				)
				( attribute "PACK_TYPE" "SMD-BCG"
					( Origin gFrontEnd )
				)
				( attribute "PART_NUMBER" "78.47523.5BL"
					( Origin gFrontEnd )
				)
				( attribute "PHYS_PAGE" "150"
					( Origin gFrontEnd )
				)
				( attribute "ROT" "0"
					( Origin gFrontEnd )
				)
				( attribute "VALUE" "SC4D7U10V3KX-GP"
					( Origin gFrontEnd )
				)
				( attribute "VER" "1"
					( Origin gFrontEnd )
				)
				( attribute "XY" "(-500,3550)"
					( Origin gFrontEnd )
				)
				( attribute "CHIPS_PART_NAME" "SC4D7U10V3KX-GP"
					( Origin gPackager )
				)
				( attribute "CDS_PART_NAME" "SC4D7U10V3KX-GP_SMD-BCG-SC4D7UA"
					( Origin gPackager )
				)
				( attribute "CDS_LOCATION" "C25W39"
					( Origin gPackager )
				)
				( attribute "CDS_SEC" "1"
					( Origin gPackager )
				)
				( attribute "SEC" "1"
					( Origin gPackager )
				)
				( objectStatus "C25W39" )
				( pin "\1\"
					( attribute "PN" "1"
						( Origin gPackager )
					)
					( objectStatus "C25W39.1" )
				)
				( pin "\2\"
					( attribute "PN" "2"
						( Origin gPackager )
					)
					( objectStatus "C25W39.2" )
				)
			)
			( gate "@baseboard_fab2_lib.baseboard_fab2(sch_1):page150_i14"
				( attribute "BOM_COST" "SM_CONTROLLER"
					( Origin gFrontEnd )
				)
				( attribute "CDS_LIB" "mstr_discrete"
					( Origin gPackager )
				)
				( attribute "LOCATION" "C25W52"
					( Origin gFrontEnd )
				)
				( attribute "MATERIAL" "X6S"
					( Origin gFrontEnd )
				)
				( attribute "PACK_TYPE" "0402"
					( Origin gFrontEnd )
				)
				( attribute "PART_NUMBER" "D97712-004"
					( Origin gFrontEnd )
				)
				( attribute "PHYS_PAGE" "150"
					( Origin gFrontEnd )
				)
				( attribute "ROOM" "BMC"
					( Origin gFrontEnd )
				)
				( attribute "ROT" "0"
					( Origin gFrontEnd )
				)
				( attribute "TOLERANCE" "10%"
					( Origin gFrontEnd )
				)
				( attribute "VALUE" "1.0UF"
					( Origin gFrontEnd )
				)
				( attribute "VER" "1"
					( Origin gFrontEnd )
				)
				( attribute "VOLTAGE" "6.3V"
					( Units "uVoltage" "V" 1.000000)
					( Origin gFrontEnd )
				)
				( attribute "XY" "(25,2475)"
					( Origin gFrontEnd )
				)
				( attribute "CHIPS_PART_NAME" "CAP"
					( Origin gPackager )
				)
				( attribute "CDS_PART_NAME" "CAP_0402-1.0UF,6.3V,10%,X6S,D9A"
					( Origin gPackager )
				)
				( attribute "CDS_LOCATION" "C25W52"
					( Origin gPackager )
				)
				( attribute "CDS_SEC" "1"
					( Origin gPackager )
				)
				( attribute "SEC" "1"
					( Origin gPackager )
				)
				( objectStatus "C25W52" )
				( pin "a"
					( attribute "PN" "1"
						( Origin gPackager )
					)
					( objectStatus "C25W52.1" )
				)
				( pin "b"
					( attribute "PN" "2"
						( Origin gPackager )
					)
					( objectStatus "C25W52.2" )
				)
			)
			( gate "@baseboard_fab2_lib.baseboard_fab2(sch_1):page150_i13"
				( attribute "BOM_COST" "SM_CONTROLLER"
					( Origin gFrontEnd )
				)
				( attribute "CDS_LIB" "mstr_discrete"
					( Origin gPackager )
				)
				( attribute "LOCATION" "C25W53"
					( Origin gFrontEnd )
				)
				( attribute "MATERIAL" "X6S"
					( Origin gFrontEnd )
				)
				( attribute "PACK_TYPE" "0402"
					( Origin gFrontEnd )
				)
				( attribute "PART_NUMBER" "D97712-004"
					( Origin gFrontEnd )
				)
				( attribute "PHYS_PAGE" "150"
					( Origin gFrontEnd )
				)
				( attribute "ROOM" "BMC"
					( Origin gFrontEnd )
				)
				( attribute "ROT" "0"
					( Origin gFrontEnd )
				)
				( attribute "TOLERANCE" "10%"
					( Origin gFrontEnd )
				)
				( attribute "VALUE" "1.0UF"
					( Origin gFrontEnd )
				)
				( attribute "VER" "1"
					( Origin gFrontEnd )
				)
				( attribute "VOLTAGE" "6.3V"
					( Units "uVoltage" "V" 1.000000)
					( Origin gFrontEnd )
				)
				( attribute "XY" "(275,2475)"
					( Origin gFrontEnd )
				)
				( attribute "CHIPS_PART_NAME" "CAP"
					( Origin gPackager )
				)
				( attribute "CDS_PART_NAME" "CAP_0402-1.0UF,6.3V,10%,X6S,D9A"
					( Origin gPackager )
				)
				( attribute "CDS_LOCATION" "C25W53"
					( Origin gPackager )
				)
				( attribute "CDS_SEC" "1"
					( Origin gPackager )
				)
				( attribute "SEC" "1"
					( Origin gPackager )
				)
				( objectStatus "C25W53" )
				( pin "a"
					( attribute "PN" "1"
						( Origin gPackager )
					)
					( objectStatus "C25W53.1" )
				)
				( pin "b"
					( attribute "PN" "2"
						( Origin gPackager )
					)
					( objectStatus "C25W53.2" )
				)
			)
			( gate "@baseboard_fab2_lib.baseboard_fab2(sch_1):page150_i12"
				( attribute "BOM_COST" "SM_CONTROLLER"
					( Origin gFrontEnd )
				)
				( attribute "CDS_LIB" "mstr_discrete"
					( Origin gPackager )
				)
				( attribute "LOCATION" "C25W54"
					( Origin gFrontEnd )
				)
				( attribute "MATERIAL" "X6S"
					( Origin gFrontEnd )
				)
				( attribute "PACK_TYPE" "0402"
					( Origin gFrontEnd )
				)
				( attribute "PART_NUMBER" "D97712-004"
					( Origin gFrontEnd )
				)
				( attribute "PHYS_PAGE" "150"
					( Origin gFrontEnd )
				)
				( attribute "ROOM" "BMC"
					( Origin gFrontEnd )
				)
				( attribute "ROT" "0"
					( Origin gFrontEnd )
				)
				( attribute "TOLERANCE" "10%"
					( Origin gFrontEnd )
				)
				( attribute "VALUE" "1.0UF"
					( Origin gFrontEnd )
				)
				( attribute "VER" "1"
					( Origin gFrontEnd )
				)
				( attribute "VOLTAGE" "6.3V"
					( Units "uVoltage" "V" 1.000000)
					( Origin gFrontEnd )
				)
				( attribute "XY" "(525,2475)"
					( Origin gFrontEnd )
				)
				( attribute "CHIPS_PART_NAME" "CAP"
					( Origin gPackager )
				)
				( attribute "CDS_PART_NAME" "CAP_0402-1.0UF,6.3V,10%,X6S,D9A"
					( Origin gPackager )
				)
				( attribute "CDS_LOCATION" "C25W54"
					( Origin gPackager )
				)
				( attribute "CDS_SEC" "1"
					( Origin gPackager )
				)
				( attribute "SEC" "1"
					( Origin gPackager )
				)
				( objectStatus "C25W54" )
				( pin "a"
					( attribute "PN" "1"
						( Origin gPackager )
					)
					( objectStatus "C25W54.1" )
				)
				( pin "b"
					( attribute "PN" "2"
						( Origin gPackager )
					)
					( objectStatus "C25W54.2" )
				)
			)
			( gate "@baseboard_fab2_lib.baseboard_fab2(sch_1):page150_i10"
				( attribute "CDS_LIB" "w_hdl"
					( Origin gPackager )
				)
				( attribute "CDS_LMAN_SYM_OUTLINE" "-50,25,50,-25"
					( Origin gPackager )
				)
				( attribute "LOCATION" "C25W55"
					( Origin gFrontEnd )
				)
				( attribute "PACK_TYPE" "SMD-BCG"
					( Origin gFrontEnd )
				)
				( attribute "PART_NUMBER" "78.10421.2FL"
					( Origin gFrontEnd )
				)
				( attribute "PHYS_PAGE" "150"
					( Origin gFrontEnd )
				)
				( attribute "ROT" "0"
					( Origin gFrontEnd )
				)
				( attribute "VALUE" "SCD1U16V2KX-3GP"
					( Origin gFrontEnd )
				)
				( attribute "VER" "1"
					( Origin gFrontEnd )
				)
				( attribute "XY" "(775,2500)"
					( Origin gFrontEnd )
				)
				( attribute "CHIPS_PART_NAME" "SCD1U16V2KX-3GP"
					( Origin gPackager )
				)
				( attribute "CDS_PART_NAME" "SCD1U16V2KX-3GP_SMD-BCG-SCD1U1A"
					( Origin gPackager )
				)
				( attribute "CDS_LOCATION" "C25W55"
					( Origin gPackager )
				)
				( attribute "CDS_SEC" "1"
					( Origin gPackager )
				)
				( attribute "SEC" "1"
					( Origin gPackager )
				)
				( objectStatus "C25W55" )
				( pin "\1\"
					( attribute "PN" "1"
						( Origin gPackager )
					)
					( objectStatus "C25W55.1" )
				)
				( pin "\2\"
					( attribute "PN" "2"
						( Origin gPackager )
					)
					( objectStatus "C25W55.2" )
				)
			)
			( gate "@baseboard_fab2_lib.baseboard_fab2(sch_1):page150_i7"
				( attribute "CDS_LIB" "w_hdl"
					( Origin gPackager )
				)
				( attribute "CDS_LMAN_SYM_OUTLINE" "-50,75,50,-75"
					( Origin gPackager )
				)
				( attribute "LOCATION" "R25W120"
					( Origin gFrontEnd )
				)
				( attribute "PACK_TYPE" "RCL_GP"
					( Origin gFrontEnd )
				)
				( attribute "PART_NUMBER" "63.00000.00L"
					( Origin gFrontEnd )
				)
				( attribute "PHYS_PAGE" "150"
					( Origin gFrontEnd )
				)
				( attribute "ROT" "1"
					( Origin gFrontEnd )
				)
				( attribute "VALUE" "0R3J-0-U-GP"
					( Origin gFrontEnd )
				)
				( attribute "VER" "1"
					( Origin gFrontEnd )
				)
				( attribute "XY" "(-100,5075)"
					( Origin gFrontEnd )
				)
				( attribute "CHIPS_PART_NAME" "0R3J-0-U-GP"
					( Origin gPackager )
				)
				( attribute "CDS_PART_NAME" "0R3J-0-U-GP_RCL_GP-0R3J-0-U-GPA"
					( Origin gPackager )
				)
				( attribute "CDS_LOCATION" "R25W120"
					( Origin gPackager )
				)
				( attribute "CDS_SEC" "1"
					( Origin gPackager )
				)
				( attribute "SEC" "1"
					( Origin gPackager )
				)
				( objectStatus "R25W120" )
				( pin "\1\"
					( attribute "PN" "1"
						( Origin gPackager )
					)
					( objectStatus "R25W120.1" )
				)
				( pin "\2\"
					( attribute "PN" "2"
						( Origin gPackager )
					)
					( objectStatus "R25W120.2" )
				)
			)
			( gate "@baseboard_fab2_lib.baseboard_fab2(sch_1):page150_i6"
				( attribute "CDS_LIB" "w_hdl"
					( Origin gPackager )
				)
				( attribute "CDS_LMAN_SYM_OUTLINE" "-50,25,50,-25"
					( Origin gPackager )
				)
				( attribute "LOCATION" "C25W70"
					( Origin gFrontEnd )
				)
				( attribute "PACK_TYPE" "SMD-BCG"
					( Origin gFrontEnd )
				)
				( attribute "PART_NUMBER" "78.47523.5BL"
					( Origin gFrontEnd )
				)
				( attribute "PHYS_PAGE" "150"
					( Origin gFrontEnd )
				)
				( attribute "ROT" "0"
					( Origin gFrontEnd )
				)
				( attribute "VALUE" "SC4D7U10V3KX-GP"
					( Origin gFrontEnd )
				)
				( attribute "VER" "1"
					( Origin gFrontEnd )
				)
				( attribute "XY" "(75,4875)"
					( Origin gFrontEnd )
				)
				( attribute "CHIPS_PART_NAME" "SC4D7U10V3KX-GP"
					( Origin gPackager )
				)
				( attribute "CDS_PART_NAME" "SC4D7U10V3KX-GP_SMD-BCG-SC4D7UA"
					( Origin gPackager )
				)
				( attribute "CDS_LOCATION" "C25W70"
					( Origin gPackager )
				)
				( attribute "CDS_SEC" "1"
					( Origin gPackager )
				)
				( attribute "SEC" "1"
					( Origin gPackager )
				)
				( objectStatus "C25W70" )
				( pin "\1\"
					( attribute "PN" "1"
						( Origin gPackager )
					)
					( objectStatus "C25W70.1" )
				)
				( pin "\2\"
					( attribute "PN" "2"
						( Origin gPackager )
					)
					( objectStatus "C25W70.2" )
				)
			)
			( gate "@baseboard_fab2_lib.baseboard_fab2(sch_1):page151_i48"
				( attribute "BOM_COST" "NT_GBE_BASE"
					( Origin gFrontEnd )
				)
				( attribute "CDS_LIB" "mstr_discrete"
					( Origin gPackager )
				)
				( attribute "CDS_LOCATION" "R25W116"
					( Origin gPackager )
				)
				( attribute "CDS_SEC" "1"
					( Origin gPackager )
				)
				( attribute "LOCATION" "R25W116"
					( Origin gFrontEnd )
				)
				( attribute "MATERIAL" "CHIP"
					( Origin gFrontEnd )
				)
				( attribute "PACK_TYPE" "0402"
					( Origin gFrontEnd )
				)
				( attribute "PART_NUMBER" "G21796-027"
					( Origin gFrontEnd )
				)
				( attribute "PHYS_PAGE" "151"
					( Origin gFrontEnd )
				)
				( attribute "ROOM" "NIC_SPRV"
					( Origin gFrontEnd )
				)
				( attribute "ROT" "1"
					( Origin gFrontEnd )
				)
				( attribute "SEC" "1"
					( Origin gFrontEnd )
				)
				( attribute "SEC_TYPE" "0402"
					( Origin gFrontEnd )
				)
				( attribute "TOLERANCE" "1%"
					( Origin gFrontEnd )
				)
				( attribute "VALUE" "3.32K"
					( Origin gFrontEnd )
				)
				( attribute "VER" "2"
					( Origin gFrontEnd )
				)
				( attribute "WATTAGE" "1/16W"
					( Origin gFrontEnd )
				)
				( attribute "XY" "(-6825,225)"
					( Origin gFrontEnd )
				)
				( attribute "CHIPS_PART_NAME" "RES"
					( Origin gPackager )
				)
				( attribute "CDS_PART_NAME" "RES_0402-3.32K,1%,1/16W,CHIP,GA"
					( Origin gPackager )
				)
				( objectStatus "R25W116" )
				( pin "a"
					( attribute "PN" "1"
						( Origin gPackager )
					)
					( objectStatus "R25W116.1" )
				)
				( pin "b"
					( attribute "PN" "2"
						( Origin gPackager )
					)
					( objectStatus "R25W116.2" )
				)
			)
			( gate "@baseboard_fab2_lib.baseboard_fab2(sch_1):page151_i47"
				( attribute "BOM_COST" "SM_CONTROLLER"
					( Origin gFrontEnd )
				)
				( attribute "CDS_LIB" "mstr_discrete"
					( Origin gPackager )
				)
				( attribute "LOCATION" "R25W115"
					( Origin gFrontEnd )
				)
				( attribute "MATERIAL" "CHIP"
					( Origin gFrontEnd )
				)
				( attribute "PACK_TYPE" "0402"
					( Origin gFrontEnd )
				)
				( attribute "PART_NUMBER" "G21796-072"
					( Origin gFrontEnd )
				)
				( attribute "PHYS_PAGE" "151"
					( Origin gFrontEnd )
				)
				( attribute "ROOM" "BMC"
					( Origin gFrontEnd )
				)
				( attribute "ROT" "0"
					( Origin gFrontEnd )
				)
				( attribute "TOLERANCE" "1%"
					( Origin gFrontEnd )
				)
				( attribute "VALUE" "4.75K"
					( Origin gFrontEnd )
				)
				( attribute "VER" "1"
					( Origin gFrontEnd )
				)
				( attribute "WATTAGE" "1/16W"
					( Origin gFrontEnd )
				)
				( attribute "XY" "(-6875,475)"
					( Origin gFrontEnd )
				)
				( attribute "CHIPS_PART_NAME" "RES"
					( Origin gPackager )
				)
				( attribute "CDS_PART_NAME" "RES_0402-4.75K,1%,1/16W,CHIP,GA"
					( Origin gPackager )
				)
				( attribute "CDS_LOCATION" "R25W115"
					( Origin gPackager )
				)
				( attribute "CDS_SEC" "1"
					( Origin gPackager )
				)
				( attribute "SEC" "1"
					( Origin gPackager )
				)
				( objectStatus "R25W115" )
				( pin "a"
					( attribute "PN" "1"
						( Origin gPackager )
					)
					( objectStatus "R25W115.1" )
				)
				( pin "b"
					( attribute "PN" "2"
						( Origin gPackager )
					)
					( objectStatus "R25W115.2" )
				)
			)
			( gate "@baseboard_fab2_lib.baseboard_fab2(sch_1):page151_i46"
				( attribute "BOM_COST" "SM_CONTROLLER"
					( Origin gFrontEnd )
				)
				( attribute "CDS_LIB" "mstr_discrete"
					( Origin gPackager )
				)
				( attribute "CDS_LOCATION" "R25W114"
					( Origin gPackager )
				)
				( attribute "CDS_SEC" "1"
					( Origin gPackager )
				)
				( attribute "LOCATION" "R25W114"
					( Origin gFrontEnd )
				)
				( attribute "MATERIAL" "EMPTY"
					( Origin gFrontEnd )
				)
				( attribute "PACK_TYPE" "0402"
					( Origin gFrontEnd )
				)
				( attribute "PART_NUMBER" "G21796-072"
					( Origin gFrontEnd )
				)
				( attribute "PHYS_PAGE" "151"
					( Origin gFrontEnd )
				)
				( attribute "ROOM" "BMC"
					( Origin gFrontEnd )
				)
				( attribute "ROT" "0"
					( Origin gFrontEnd )
				)
				( attribute "SEC" "1"
					( Origin gPackager )
				)
				( attribute "TOLERANCE" "1%"
					( Origin gFrontEnd )
				)
				( attribute "VALUE" "4.75K"
					( Origin gFrontEnd )
				)
				( attribute "VER" "1"
					( Origin gFrontEnd )
				)
				( attribute "WATTAGE" "1/16W"
					( Origin gFrontEnd )
				)
				( attribute "XY" "(-6900,725)"
					( Origin gFrontEnd )
				)
				( attribute "CHIPS_PART_NAME" "RES"
					( Origin gPackager )
				)
				( attribute "CDS_PART_NAME" "RES_0402-4.75K,1%,1/16W,EMPTY,A"
					( Origin gPackager )
				)
				( objectStatus "R25W114" )
				( pin "a"
					( attribute "PN" "1"
						( Origin gPackager )
					)
					( objectStatus "R25W114.1" )
				)
				( pin "b"
					( attribute "PN" "2"
						( Origin gPackager )
					)
					( objectStatus "R25W114.2" )
				)
			)
			( gate "@baseboard_fab2_lib.baseboard_fab2(sch_1):page151_i45"
				( attribute "BOM_COST" "SM_CONTROLLER"
					( Origin gFrontEnd )
				)
				( attribute "CDS_LIB" "mstr_discrete"
					( Origin gPackager )
				)
				( attribute "CDS_LOCATION" "R25W113"
					( Origin gPackager )
				)
				( attribute "CDS_SEC" "1"
					( Origin gPackager )
				)
				( attribute "LOCATION" "R25W113"
					( Origin gFrontEnd )
				)
				( attribute "MATERIAL" "EMPTY"
					( Origin gFrontEnd )
				)
				( attribute "PACK_TYPE" "0402"
					( Origin gFrontEnd )
				)
				( attribute "PART_NUMBER" "G21796-072"
					( Origin gFrontEnd )
				)
				( attribute "PHYS_PAGE" "151"
					( Origin gFrontEnd )
				)
				( attribute "ROOM" "BMC"
					( Origin gFrontEnd )
				)
				( attribute "ROT" "0"
					( Origin gFrontEnd )
				)
				( attribute "SEC" "1"
					( Origin gPackager )
				)
				( attribute "TOLERANCE" "1%"
					( Origin gFrontEnd )
				)
				( attribute "VALUE" "4.75K"
					( Origin gFrontEnd )
				)
				( attribute "VER" "1"
					( Origin gFrontEnd )
				)
				( attribute "WATTAGE" "1/16W"
					( Origin gFrontEnd )
				)
				( attribute "XY" "(-6900,950)"
					( Origin gFrontEnd )
				)
				( attribute "CHIPS_PART_NAME" "RES"
					( Origin gPackager )
				)
				( attribute "CDS_PART_NAME" "RES_0402-4.75K,1%,1/16W,EMPTY,A"
					( Origin gPackager )
				)
				( objectStatus "R25W113" )
				( pin "a"
					( attribute "PN" "1"
						( Origin gPackager )
					)
					( objectStatus "R25W113.1" )
				)
				( pin "b"
					( attribute "PN" "2"
						( Origin gPackager )
					)
					( objectStatus "R25W113.2" )
				)
			)
			( gate "@baseboard_fab2_lib.baseboard_fab2(sch_1):page151_i44"
				( attribute "BOM_COST" "SM_CONTROLLER"
					( Origin gFrontEnd )
				)
				( attribute "CDS_LIB" "mstr_discrete"
					( Origin gPackager )
				)
				( attribute "CDS_LOCATION" "R25W112"
					( Origin gPackager )
				)
				( attribute "CDS_SEC" "1"
					( Origin gPackager )
				)
				( attribute "LOCATION" "R25W112"
					( Origin gFrontEnd )
				)
				( attribute "MATERIAL" "EMPTY"
					( Origin gFrontEnd )
				)
				( attribute "PACK_TYPE" "0402"
					( Origin gFrontEnd )
				)
				( attribute "PART_NUMBER" "G21796-072"
					( Origin gFrontEnd )
				)
				( attribute "PHYS_PAGE" "151"
					( Origin gFrontEnd )
				)
				( attribute "ROOM" "BMC"
					( Origin gFrontEnd )
				)
				( attribute "ROT" "0"
					( Origin gFrontEnd )
				)
				( attribute "SEC" "1"
					( Origin gPackager )
				)
				( attribute "TOLERANCE" "1%"
					( Origin gFrontEnd )
				)
				( attribute "VALUE" "4.75K"
					( Origin gFrontEnd )
				)
				( attribute "VER" "1"
					( Origin gFrontEnd )
				)
				( attribute "WATTAGE" "1/16W"
					( Origin gFrontEnd )
				)
				( attribute "XY" "(-6900,1175)"
					( Origin gFrontEnd )
				)
				( attribute "CHIPS_PART_NAME" "RES"
					( Origin gPackager )
				)
				( attribute "CDS_PART_NAME" "RES_0402-4.75K,1%,1/16W,EMPTY,A"
					( Origin gPackager )
				)
				( objectStatus "R25W112" )
				( pin "a"
					( attribute "PN" "1"
						( Origin gPackager )
					)
					( objectStatus "R25W112.1" )
				)
				( pin "b"
					( attribute "PN" "2"
						( Origin gPackager )
					)
					( objectStatus "R25W112.2" )
				)
			)
			( gate "@baseboard_fab2_lib.baseboard_fab2(sch_1):page151_i43"
				( attribute "BOM_COST" "SM_CONTROLLER"
					( Origin gFrontEnd )
				)
				( attribute "CDS_LIB" "mstr_discrete"
					( Origin gPackager )
				)
				( attribute "CDS_LOCATION" "R25W111"
					( Origin gPackager )
				)
				( attribute "CDS_SEC" "1"
					( Origin gPackager )
				)
				( attribute "LOCATION" "R25W111"
					( Origin gFrontEnd )
				)
				( attribute "MATERIAL" "EMPTY"
					( Origin gFrontEnd )
				)
				( attribute "PACK_TYPE" "0402"
					( Origin gFrontEnd )
				)
				( attribute "PART_NUMBER" "G21796-072"
					( Origin gFrontEnd )
				)
				( attribute "PHYS_PAGE" "151"
					( Origin gFrontEnd )
				)
				( attribute "ROOM" "BMC"
					( Origin gFrontEnd )
				)
				( attribute "ROT" "0"
					( Origin gFrontEnd )
				)
				( attribute "SEC" "1"
					( Origin gPackager )
				)
				( attribute "TOLERANCE" "1%"
					( Origin gFrontEnd )
				)
				( attribute "VALUE" "4.75K"
					( Origin gFrontEnd )
				)
				( attribute "VER" "1"
					( Origin gFrontEnd )
				)
				( attribute "WATTAGE" "1/16W"
					( Origin gFrontEnd )
				)
				( attribute "XY" "(-6900,1400)"
					( Origin gFrontEnd )
				)
				( attribute "CHIPS_PART_NAME" "RES"
					( Origin gPackager )
				)
				( attribute "CDS_PART_NAME" "RES_0402-4.75K,1%,1/16W,EMPTY,A"
					( Origin gPackager )
				)
				( objectStatus "R25W111" )
				( pin "a"
					( attribute "PN" "1"
						( Origin gPackager )
					)
					( objectStatus "R25W111.1" )
				)
				( pin "b"
					( attribute "PN" "2"
						( Origin gPackager )
					)
					( objectStatus "R25W111.2" )
				)
			)
			( gate "@baseboard_fab2_lib.baseboard_fab2(sch_1):page151_i36"
				( attribute "BOM_COST" "SM_CONTROLLER"
					( Origin gFrontEnd )
				)
				( attribute "CDS_LIB" "mstr_discrete"
					( Origin gPackager )
				)
				( attribute "LOCATION" "R25W110"
					( Origin gFrontEnd )
				)
				( attribute "MATERIAL" "CHIP"
					( Origin gFrontEnd )
				)
				( attribute "PACK_TYPE" "0402"
					( Origin gFrontEnd )
				)
				( attribute "PART_NUMBER" "G21796-072"
					( Origin gFrontEnd )
				)
				( attribute "PHYS_PAGE" "151"
					( Origin gFrontEnd )
				)
				( attribute "ROOM" "BMC"
					( Origin gFrontEnd )
				)
				( attribute "ROT" "0"
					( Origin gFrontEnd )
				)
				( attribute "TOLERANCE" "1%"
					( Origin gFrontEnd )
				)
				( attribute "VALUE" "4.75K"
					( Origin gFrontEnd )
				)
				( attribute "VER" "1"
					( Origin gFrontEnd )
				)
				( attribute "WATTAGE" "1/16W"
					( Origin gFrontEnd )
				)
				( attribute "XY" "(-6850,1675)"
					( Origin gFrontEnd )
				)
				( attribute "CHIPS_PART_NAME" "RES"
					( Origin gPackager )
				)
				( attribute "CDS_PART_NAME" "RES_0402-4.75K,1%,1/16W,CHIP,GA"
					( Origin gPackager )
				)
				( attribute "CDS_LOCATION" "R25W110"
					( Origin gPackager )
				)
				( attribute "CDS_SEC" "1"
					( Origin gPackager )
				)
				( attribute "SEC" "1"
					( Origin gPackager )
				)
				( objectStatus "R25W110" )
				( pin "a"
					( attribute "PN" "1"
						( Origin gPackager )
					)
					( objectStatus "R25W110.1" )
				)
				( pin "b"
					( attribute "PN" "2"
						( Origin gPackager )
					)
					( objectStatus "R25W110.2" )
				)
			)
			( gate "@baseboard_fab2_lib.baseboard_fab2(sch_1):page151_i35"
				( attribute "BOM_COST" "SM_CONTROLLER"
					( Origin gFrontEnd )
				)
				( attribute "CDS_LIB" "mstr_discrete"
					( Origin gPackager )
				)
				( attribute "CDS_LOCATION" "R25W109"
					( Origin gPackager )
				)
				( attribute "CDS_SEC" "1"
					( Origin gPackager )
				)
				( attribute "LOCATION" "R25W109"
					( Origin gFrontEnd )
				)
				( attribute "MATERIAL" "EMPTY"
					( Origin gFrontEnd )
				)
				( attribute "PACK_TYPE" "0402"
					( Origin gFrontEnd )
				)
				( attribute "PART_NUMBER" "G21796-072"
					( Origin gFrontEnd )
				)
				( attribute "PHYS_PAGE" "151"
					( Origin gFrontEnd )
				)
				( attribute "ROOM" "BMC"
					( Origin gFrontEnd )
				)
				( attribute "ROT" "0"
					( Origin gFrontEnd )
				)
				( attribute "SEC" "1"
					( Origin gPackager )
				)
				( attribute "TOLERANCE" "1%"
					( Origin gFrontEnd )
				)
				( attribute "VALUE" "4.75K"
					( Origin gFrontEnd )
				)
				( attribute "VER" "1"
					( Origin gFrontEnd )
				)
				( attribute "WATTAGE" "1/16W"
					( Origin gFrontEnd )
				)
				( attribute "XY" "(-6875,1850)"
					( Origin gFrontEnd )
				)
				( attribute "CHIPS_PART_NAME" "RES"
					( Origin gPackager )
				)
				( attribute "CDS_PART_NAME" "RES_0402-4.75K,1%,1/16W,EMPTY,A"
					( Origin gPackager )
				)
				( objectStatus "R25W109" )
				( pin "a"
					( attribute "PN" "1"
						( Origin gPackager )
					)
					( objectStatus "R25W109.1" )
				)
				( pin "b"
					( attribute "PN" "2"
						( Origin gPackager )
					)
					( objectStatus "R25W109.2" )
				)
			)
			( gate "@baseboard_fab2_lib.baseboard_fab2(sch_1):page151_i34"
				( attribute "BOM_COST" "SM_CONTROLLER"
					( Origin gFrontEnd )
				)
				( attribute "CDS_LIB" "mstr_discrete"
					( Origin gPackager )
				)
				( attribute "LOCATION" "R25W108"
					( Origin gFrontEnd )
				)
				( attribute "MATERIAL" "CHIP"
					( Origin gFrontEnd )
				)
				( attribute "PACK_TYPE" "0402"
					( Origin gFrontEnd )
				)
				( attribute "PART_NUMBER" "G21796-072"
					( Origin gFrontEnd )
				)
				( attribute "PHYS_PAGE" "151"
					( Origin gFrontEnd )
				)
				( attribute "ROOM" "BMC"
					( Origin gFrontEnd )
				)
				( attribute "ROT" "0"
					( Origin gFrontEnd )
				)
				( attribute "TOLERANCE" "1%"
					( Origin gFrontEnd )
				)
				( attribute "VALUE" "4.75K"
					( Origin gFrontEnd )
				)
				( attribute "VER" "1"
					( Origin gFrontEnd )
				)
				( attribute "WATTAGE" "1/16W"
					( Origin gFrontEnd )
				)
				( attribute "XY" "(-6875,2075)"
					( Origin gFrontEnd )
				)
				( attribute "CHIPS_PART_NAME" "RES"
					( Origin gPackager )
				)
				( attribute "CDS_PART_NAME" "RES_0402-4.75K,1%,1/16W,CHIP,GA"
					( Origin gPackager )
				)
				( attribute "CDS_LOCATION" "R25W108"
					( Origin gPackager )
				)
				( attribute "CDS_SEC" "1"
					( Origin gPackager )
				)
				( attribute "SEC" "1"
					( Origin gPackager )
				)
				( objectStatus "R25W108" )
				( pin "a"
					( attribute "PN" "1"
						( Origin gPackager )
					)
					( objectStatus "R25W108.1" )
				)
				( pin "b"
					( attribute "PN" "2"
						( Origin gPackager )
					)
					( objectStatus "R25W108.2" )
				)
			)
			( gate "@baseboard_fab2_lib.baseboard_fab2(sch_1):page151_i33"
				( attribute "BOM_COST" "SM_CONTROLLER"
					( Origin gFrontEnd )
				)
				( attribute "CDS_LIB" "mstr_discrete"
					( Origin gPackager )
				)
				( attribute "CDS_LOCATION" "R25W107"
					( Origin gPackager )
				)
				( attribute "CDS_SEC" "1"
					( Origin gPackager )
				)
				( attribute "LOCATION" "R25W107"
					( Origin gFrontEnd )
				)
				( attribute "MATERIAL" "EMPTY"
					( Origin gFrontEnd )
				)
				( attribute "PACK_TYPE" "0402"
					( Origin gFrontEnd )
				)
				( attribute "PART_NUMBER" "G21796-072"
					( Origin gFrontEnd )
				)
				( attribute "PHYS_PAGE" "151"
					( Origin gFrontEnd )
				)
				( attribute "ROOM" "BMC"
					( Origin gFrontEnd )
				)
				( attribute "ROT" "0"
					( Origin gFrontEnd )
				)
				( attribute "SEC" "1"
					( Origin gPackager )
				)
				( attribute "TOLERANCE" "1%"
					( Origin gFrontEnd )
				)
				( attribute "VALUE" "4.75K"
					( Origin gFrontEnd )
				)
				( attribute "VER" "1"
					( Origin gFrontEnd )
				)
				( attribute "WATTAGE" "1/16W"
					( Origin gFrontEnd )
				)
				( attribute "XY" "(-6900,2275)"
					( Origin gFrontEnd )
				)
				( attribute "CHIPS_PART_NAME" "RES"
					( Origin gPackager )
				)
				( attribute "CDS_PART_NAME" "RES_0402-4.75K,1%,1/16W,EMPTY,A"
					( Origin gPackager )
				)
				( objectStatus "R25W107" )
				( pin "a"
					( attribute "PN" "1"
						( Origin gPackager )
					)
					( objectStatus "R25W107.1" )
				)
				( pin "b"
					( attribute "PN" "2"
						( Origin gPackager )
					)
					( objectStatus "R25W107.2" )
				)
			)
			( gate "@baseboard_fab2_lib.baseboard_fab2(sch_1):page151_i32"
				( attribute "BOM_COST" "SM_CONTROLLER"
					( Origin gFrontEnd )
				)
				( attribute "CDS_LIB" "mstr_discrete"
					( Origin gPackager )
				)
				( attribute "CDS_LOCATION" "R25W106"
					( Origin gPackager )
				)
				( attribute "CDS_SEC" "1"
					( Origin gPackager )
				)
				( attribute "LOCATION" "R25W106"
					( Origin gFrontEnd )
				)
				( attribute "MATERIAL" "EMPTY"
					( Origin gFrontEnd )
				)
				( attribute "PACK_TYPE" "0402"
					( Origin gFrontEnd )
				)
				( attribute "PART_NUMBER" "G21796-072"
					( Origin gFrontEnd )
				)
				( attribute "PHYS_PAGE" "151"
					( Origin gFrontEnd )
				)
				( attribute "ROOM" "BMC"
					( Origin gFrontEnd )
				)
				( attribute "ROT" "0"
					( Origin gFrontEnd )
				)
				( attribute "SEC" "1"
					( Origin gPackager )
				)
				( attribute "TOLERANCE" "1%"
					( Origin gFrontEnd )
				)
				( attribute "VALUE" "4.75K"
					( Origin gFrontEnd )
				)
				( attribute "VER" "1"
					( Origin gFrontEnd )
				)
				( attribute "WATTAGE" "1/16W"
					( Origin gFrontEnd )
				)
				( attribute "XY" "(-6900,2500)"
					( Origin gFrontEnd )
				)
				( attribute "CHIPS_PART_NAME" "RES"
					( Origin gPackager )
				)
				( attribute "CDS_PART_NAME" "RES_0402-4.75K,1%,1/16W,EMPTY,A"
					( Origin gPackager )
				)
				( objectStatus "R25W106" )
				( pin "a"
					( attribute "PN" "1"
						( Origin gPackager )
					)
					( objectStatus "R25W106.1" )
				)
				( pin "b"
					( attribute "PN" "2"
						( Origin gPackager )
					)
					( objectStatus "R25W106.2" )
				)
			)
			( gate "@baseboard_fab2_lib.baseboard_fab2(sch_1):page151_i31"
				( attribute "BOM_COST" "SM_CONTROLLER"
					( Origin gFrontEnd )
				)
				( attribute "CDS_LIB" "mstr_discrete"
					( Origin gPackager )
				)
				( attribute "CDS_LOCATION" "R25W105"
					( Origin gPackager )
				)
				( attribute "CDS_SEC" "1"
					( Origin gPackager )
				)
				( attribute "LOCATION" "R25W105"
					( Origin gFrontEnd )
				)
				( attribute "MATERIAL" "EMPTY"
					( Origin gFrontEnd )
				)
				( attribute "PACK_TYPE" "0402"
					( Origin gFrontEnd )
				)
				( attribute "PART_NUMBER" "G21796-072"
					( Origin gFrontEnd )
				)
				( attribute "PHYS_PAGE" "151"
					( Origin gFrontEnd )
				)
				( attribute "ROOM" "BMC"
					( Origin gFrontEnd )
				)
				( attribute "ROT" "0"
					( Origin gFrontEnd )
				)
				( attribute "SEC" "1"
					( Origin gPackager )
				)
				( attribute "TOLERANCE" "1%"
					( Origin gFrontEnd )
				)
				( attribute "VALUE" "4.75K"
					( Origin gFrontEnd )
				)
				( attribute "VER" "1"
					( Origin gFrontEnd )
				)
				( attribute "WATTAGE" "1/16W"
					( Origin gFrontEnd )
				)
				( attribute "XY" "(-6900,2725)"
					( Origin gFrontEnd )
				)
				( attribute "CHIPS_PART_NAME" "RES"
					( Origin gPackager )
				)
				( attribute "CDS_PART_NAME" "RES_0402-4.75K,1%,1/16W,EMPTY,A"
					( Origin gPackager )
				)
				( objectStatus "R25W105" )
				( pin "a"
					( attribute "PN" "1"
						( Origin gPackager )
					)
					( objectStatus "R25W105.1" )
				)
				( pin "b"
					( attribute "PN" "2"
						( Origin gPackager )
					)
					( objectStatus "R25W105.2" )
				)
			)
			( gate "@baseboard_fab2_lib.baseboard_fab2(sch_1):page151_i30"
				( attribute "BOM_COST" "SM_CONTROLLER"
					( Origin gFrontEnd )
				)
				( attribute "CDS_LIB" "mstr_discrete"
					( Origin gPackager )
				)
				( attribute "CDS_LOCATION" "R25W104"
					( Origin gPackager )
				)
				( attribute "CDS_SEC" "1"
					( Origin gPackager )
				)
				( attribute "LOCATION" "R25W104"
					( Origin gFrontEnd )
				)
				( attribute "MATERIAL" "EMPTY"
					( Origin gFrontEnd )
				)
				( attribute "PACK_TYPE" "0402"
					( Origin gFrontEnd )
				)
				( attribute "PART_NUMBER" "G21796-072"
					( Origin gFrontEnd )
				)
				( attribute "PHYS_PAGE" "151"
					( Origin gFrontEnd )
				)
				( attribute "ROOM" "BMC"
					( Origin gFrontEnd )
				)
				( attribute "ROT" "0"
					( Origin gFrontEnd )
				)
				( attribute "SEC" "1"
					( Origin gPackager )
				)
				( attribute "TOLERANCE" "1%"
					( Origin gFrontEnd )
				)
				( attribute "VALUE" "4.75K"
					( Origin gFrontEnd )
				)
				( attribute "VER" "1"
					( Origin gFrontEnd )
				)
				( attribute "WATTAGE" "1/16W"
					( Origin gFrontEnd )
				)
				( attribute "XY" "(-6900,2950)"
					( Origin gFrontEnd )
				)
				( attribute "CHIPS_PART_NAME" "RES"
					( Origin gPackager )
				)
				( attribute "CDS_PART_NAME" "RES_0402-4.75K,1%,1/16W,EMPTY,A"
					( Origin gPackager )
				)
				( objectStatus "R25W104" )
				( pin "a"
					( attribute "PN" "1"
						( Origin gPackager )
					)
					( objectStatus "R25W104.1" )
				)
				( pin "b"
					( attribute "PN" "2"
						( Origin gPackager )
					)
					( objectStatus "R25W104.2" )
				)
			)
			( gate "@baseboard_fab2_lib.baseboard_fab2(sch_1):page151_i29"
				( attribute "BOM_COST" "SM_CONTROLLER"
					( Origin gFrontEnd )
				)
				( attribute "CDS_LIB" "mstr_discrete"
					( Origin gPackager )
				)
				( attribute "CDS_LOCATION" "R25W103"
					( Origin gPackager )
				)
				( attribute "CDS_SEC" "1"
					( Origin gPackager )
				)
				( attribute "LOCATION" "R25W103"
					( Origin gFrontEnd )
				)
				( attribute "MATERIAL" "EMPTY"
					( Origin gFrontEnd )
				)
				( attribute "PACK_TYPE" "0402"
					( Origin gFrontEnd )
				)
				( attribute "PART_NUMBER" "G21796-072"
					( Origin gFrontEnd )
				)
				( attribute "PHYS_PAGE" "151"
					( Origin gFrontEnd )
				)
				( attribute "ROOM" "BMC"
					( Origin gFrontEnd )
				)
				( attribute "ROT" "0"
					( Origin gFrontEnd )
				)
				( attribute "SEC" "1"
					( Origin gPackager )
				)
				( attribute "TOLERANCE" "1%"
					( Origin gFrontEnd )
				)
				( attribute "VALUE" "4.75K"
					( Origin gFrontEnd )
				)
				( attribute "VER" "1"
					( Origin gFrontEnd )
				)
				( attribute "WATTAGE" "1/16W"
					( Origin gFrontEnd )
				)
				( attribute "XY" "(-6900,3175)"
					( Origin gFrontEnd )
				)
				( attribute "CHIPS_PART_NAME" "RES"
					( Origin gPackager )
				)
				( attribute "CDS_PART_NAME" "RES_0402-4.75K,1%,1/16W,EMPTY,A"
					( Origin gPackager )
				)
				( objectStatus "R25W103" )
				( pin "a"
					( attribute "PN" "1"
						( Origin gPackager )
					)
					( objectStatus "R25W103.1" )
				)
				( pin "b"
					( attribute "PN" "2"
						( Origin gPackager )
					)
					( objectStatus "R25W103.2" )
				)
			)
			( gate "@baseboard_fab2_lib.baseboard_fab2(sch_1):page151_i28"
				( attribute "BOM_COST" "SM_CONTROLLER"
					( Origin gFrontEnd )
				)
				( attribute "CDS_LIB" "mstr_discrete"
					( Origin gPackager )
				)
				( attribute "LOCATION" "R25W102"
					( Origin gFrontEnd )
				)
				( attribute "MATERIAL" "CHIP"
					( Origin gFrontEnd )
				)
				( attribute "PACK_TYPE" "0402"
					( Origin gFrontEnd )
				)
				( attribute "PART_NUMBER" "G21796-072"
					( Origin gFrontEnd )
				)
				( attribute "PHYS_PAGE" "151"
					( Origin gFrontEnd )
				)
				( attribute "ROOM" "BMC"
					( Origin gFrontEnd )
				)
				( attribute "ROT" "0"
					( Origin gFrontEnd )
				)
				( attribute "TOLERANCE" "1%"
					( Origin gFrontEnd )
				)
				( attribute "VALUE" "4.75K"
					( Origin gFrontEnd )
				)
				( attribute "VER" "1"
					( Origin gFrontEnd )
				)
				( attribute "WATTAGE" "1/16W"
					( Origin gFrontEnd )
				)
				( attribute "XY" "(-6900,3325)"
					( Origin gFrontEnd )
				)
				( attribute "CHIPS_PART_NAME" "RES"
					( Origin gPackager )
				)
				( attribute "CDS_PART_NAME" "RES_0402-4.75K,1%,1/16W,CHIP,GA"
					( Origin gPackager )
				)
				( attribute "CDS_LOCATION" "R25W102"
					( Origin gPackager )
				)
				( attribute "CDS_SEC" "1"
					( Origin gPackager )
				)
				( attribute "SEC" "1"
					( Origin gPackager )
				)
				( objectStatus "R25W102" )
				( pin "a"
					( attribute "PN" "1"
						( Origin gPackager )
					)
					( objectStatus "R25W102.1" )
				)
				( pin "b"
					( attribute "PN" "2"
						( Origin gPackager )
					)
					( objectStatus "R25W102.2" )
				)
			)
			( gate "@baseboard_fab2_lib.baseboard_fab2(sch_1):page151_i27"
				( attribute "BOM_COST" "SM_CONTROLLER"
					( Origin gFrontEnd )
				)
				( attribute "CDS_LIB" "mstr_discrete"
					( Origin gPackager )
				)
				( attribute "CDS_LOCATION" "R25W101"
					( Origin gPackager )
				)
				( attribute "CDS_SEC" "1"
					( Origin gPackager )
				)
				( attribute "LOCATION" "R25W101"
					( Origin gFrontEnd )
				)
				( attribute "MATERIAL" "EMPTY"
					( Origin gFrontEnd )
				)
				( attribute "PACK_TYPE" "0402"
					( Origin gFrontEnd )
				)
				( attribute "PART_NUMBER" "G21796-072"
					( Origin gFrontEnd )
				)
				( attribute "PHYS_PAGE" "151"
					( Origin gFrontEnd )
				)
				( attribute "ROOM" "BMC"
					( Origin gFrontEnd )
				)
				( attribute "ROT" "0"
					( Origin gFrontEnd )
				)
				( attribute "SEC" "1"
					( Origin gPackager )
				)
				( attribute "TOLERANCE" "1%"
					( Origin gFrontEnd )
				)
				( attribute "VALUE" "4.75K"
					( Origin gFrontEnd )
				)
				( attribute "VER" "1"
					( Origin gFrontEnd )
				)
				( attribute "WATTAGE" "1/16W"
					( Origin gFrontEnd )
				)
				( attribute "XY" "(-6900,3475)"
					( Origin gFrontEnd )
				)
				( attribute "CHIPS_PART_NAME" "RES"
					( Origin gPackager )
				)
				( attribute "CDS_PART_NAME" "RES_0402-4.75K,1%,1/16W,EMPTY,A"
					( Origin gPackager )
				)
				( objectStatus "R25W101" )
				( pin "a"
					( attribute "PN" "1"
						( Origin gPackager )
					)
					( objectStatus "R25W101.1" )
				)
				( pin "b"
					( attribute "PN" "2"
						( Origin gPackager )
					)
					( objectStatus "R25W101.2" )
				)
			)
			( gate "@baseboard_fab2_lib.baseboard_fab2(sch_1):page151_i14"
				( attribute "BOM_COST" "SM_CONTROLLER"
					( Origin gFrontEnd )
				)
				( attribute "CDS_LIB" "mstr_discrete"
					( Origin gPackager )
				)
				( attribute "CDS_LOCATION" "R25W99"
					( Origin gPackager )
				)
				( attribute "CDS_SEC" "1"
					( Origin gPackager )
				)
				( attribute "LOCATION" "R25W99"
					( Origin gFrontEnd )
				)
				( attribute "MATERIAL" "EMPTY"
					( Origin gFrontEnd )
				)
				( attribute "PACK_TYPE" "0402"
					( Origin gFrontEnd )
				)
				( attribute "PART_NUMBER" "G21796-072"
					( Origin gFrontEnd )
				)
				( attribute "PHYS_PAGE" "151"
					( Origin gFrontEnd )
				)
				( attribute "ROOM" "BMC"
					( Origin gFrontEnd )
				)
				( attribute "ROT" "0"
					( Origin gFrontEnd )
				)
				( attribute "SEC" "1"
					( Origin gPackager )
				)
				( attribute "TOLERANCE" "1%"
					( Origin gFrontEnd )
				)
				( attribute "VALUE" "4.75K"
					( Origin gFrontEnd )
				)
				( attribute "VER" "1"
					( Origin gFrontEnd )
				)
				( attribute "WATTAGE" "1/16W"
					( Origin gFrontEnd )
				)
				( attribute "XY" "(-6925,3825)"
					( Origin gFrontEnd )
				)
				( attribute "CHIPS_PART_NAME" "RES"
					( Origin gPackager )
				)
				( attribute "CDS_PART_NAME" "RES_0402-4.75K,1%,1/16W,EMPTY,A"
					( Origin gPackager )
				)
				( objectStatus "R25W99" )
				( pin "a"
					( attribute "PN" "1"
						( Origin gPackager )
					)
					( objectStatus "R25W99.1" )
				)
				( pin "b"
					( attribute "PN" "2"
						( Origin gPackager )
					)
					( objectStatus "R25W99.2" )
				)
			)
			( gate "@baseboard_fab2_lib.baseboard_fab2(sch_1):page150_i89"
				( attribute "CDS_LIB" "w_hdl"
					( Origin gPackager )
				)
				( attribute "CDS_LMAN_SYM_OUTLINE" "-50,100,50,-100"
					( Origin gPackager )
				)
				( attribute "LOCATION" "FB2T5"
					( Origin gFrontEnd )
				)
				( attribute "PACK_TYPE" "DISCRET-G9"
					( Origin gFrontEnd )
				)
				( attribute "PART_NUMBER" "68.00230.231"
					( Origin gFrontEnd )
				)
				( attribute "PHYS_PAGE" "150"
					( Origin gFrontEnd )
				)
				( attribute "ROT" "1"
					( Origin gFrontEnd )
				)
				( attribute "VALUE" "HCB1608KF-800T30-GP"
					( Origin gFrontEnd )
				)
				( attribute "VER" "1"
					( Origin gFrontEnd )
				)
				( attribute "XY" "(-6250,1725)"
					( Origin gFrontEnd )
				)
				( attribute "CHIPS_PART_NAME" "HCB1608KF-800T30-GP"
					( Origin gPackager )
				)
				( attribute "CDS_PART_NAME" "HCB1608KF-800T30-GP_DISCRET-G9A"
					( Origin gPackager )
				)
				( attribute "CDS_LOCATION" "FB2T5"
					( Origin gPackager )
				)
				( attribute "CDS_SEC" "1"
					( Origin gPackager )
				)
				( attribute "SEC" "1"
					( Origin gPackager )
				)
				( objectStatus "FB2T5" )
				( pin "\1\"
					( attribute "PN" "1"
						( Origin gPackager )
					)
					( objectStatus "FB2T5.1" )
				)
				( pin "\2\"
					( attribute "PN" "2"
						( Origin gPackager )
					)
					( objectStatus "FB2T5.2" )
				)
			)
			( gate "@baseboard_fab2_lib.baseboard_fab2(sch_1):page150_i87"
				( attribute "BOM_COST" "SM_CONTROLLER"
					( Origin gFrontEnd )
				)
				( attribute "CDS_LIB" "mstr_discrete"
					( Origin gPackager )
				)
				( attribute "LOCATION" "C25W56"
					( Origin gFrontEnd )
				)
				( attribute "MATERIAL" "X6S"
					( Origin gFrontEnd )
				)
				( attribute "PACK_TYPE" "0402"
					( Origin gFrontEnd )
				)
				( attribute "PART_NUMBER" "D97712-004"
					( Origin gFrontEnd )
				)
				( attribute "PHYS_PAGE" "150"
					( Origin gFrontEnd )
				)
				( attribute "ROOM" "BMC"
					( Origin gFrontEnd )
				)
				( attribute "ROT" "0"
					( Origin gFrontEnd )
				)
				( attribute "TOLERANCE" "10%"
					( Origin gFrontEnd )
				)
				( attribute "VALUE" "1.0UF"
					( Origin gFrontEnd )
				)
				( attribute "VER" "1"
					( Origin gFrontEnd )
				)
				( attribute "VOLTAGE" "6.3V"
					( Units "uVoltage" "V" 1.000000)
					( Origin gFrontEnd )
				)
				( attribute "XY" "(-5725,1375)"
					( Origin gFrontEnd )
				)
				( attribute "CHIPS_PART_NAME" "CAP"
					( Origin gPackager )
				)
				( attribute "CDS_PART_NAME" "CAP_0402-1.0UF,6.3V,10%,X6S,D9A"
					( Origin gPackager )
				)
				( attribute "CDS_LOCATION" "C25W56"
					( Origin gPackager )
				)
				( attribute "CDS_SEC" "1"
					( Origin gPackager )
				)
				( attribute "SEC" "1"
					( Origin gPackager )
				)
				( objectStatus "C25W56" )
				( pin "a"
					( attribute "PN" "1"
						( Origin gPackager )
					)
					( objectStatus "C25W56.1" )
				)
				( pin "b"
					( attribute "PN" "2"
						( Origin gPackager )
					)
					( objectStatus "C25W56.2" )
				)
			)
			( gate "@baseboard_fab2_lib.baseboard_fab2(sch_1):page150_i86"
				( attribute "BOM_COST" "SM_CONTROLLER"
					( Origin gFrontEnd )
				)
				( attribute "CDS_LIB" "mstr_discrete"
					( Origin gPackager )
				)
				( attribute "LOCATION" "C25W57"
					( Origin gFrontEnd )
				)
				( attribute "MATERIAL" "X6S"
					( Origin gFrontEnd )
				)
				( attribute "PACK_TYPE" "0402"
					( Origin gFrontEnd )
				)
				( attribute "PART_NUMBER" "D97712-004"
					( Origin gFrontEnd )
				)
				( attribute "PHYS_PAGE" "150"
					( Origin gFrontEnd )
				)
				( attribute "ROOM" "BMC"
					( Origin gFrontEnd )
				)
				( attribute "ROT" "0"
					( Origin gFrontEnd )
				)
				( attribute "TOLERANCE" "10%"
					( Origin gFrontEnd )
				)
				( attribute "VALUE" "1.0UF"
					( Origin gFrontEnd )
				)
				( attribute "VER" "1"
					( Origin gFrontEnd )
				)
				( attribute "VOLTAGE" "6.3V"
					( Units "uVoltage" "V" 1.000000)
					( Origin gFrontEnd )
				)
				( attribute "XY" "(-5475,1375)"
					( Origin gFrontEnd )
				)
				( attribute "CHIPS_PART_NAME" "CAP"
					( Origin gPackager )
				)
				( attribute "CDS_PART_NAME" "CAP_0402-1.0UF,6.3V,10%,X6S,D9A"
					( Origin gPackager )
				)
				( attribute "CDS_LOCATION" "C25W57"
					( Origin gPackager )
				)
				( attribute "CDS_SEC" "1"
					( Origin gPackager )
				)
				( attribute "SEC" "1"
					( Origin gPackager )
				)
				( objectStatus "C25W57" )
				( pin "a"
					( attribute "PN" "1"
						( Origin gPackager )
					)
					( objectStatus "C25W57.1" )
				)
				( pin "b"
					( attribute "PN" "2"
						( Origin gPackager )
					)
					( objectStatus "C25W57.2" )
				)
			)
			( gate "@baseboard_fab2_lib.baseboard_fab2(sch_1):page150_i85"
				( attribute "CDS_LIB" "w_hdl"
					( Origin gPackager )
				)
				( attribute "CDS_LMAN_SYM_OUTLINE" "-50,25,50,-25"
					( Origin gPackager )
				)
				( attribute "LOCATION" "C25W58"
					( Origin gFrontEnd )
				)
				( attribute "PACK_TYPE" "SMD-BCG"
					( Origin gFrontEnd )
				)
				( attribute "PART_NUMBER" "78.10421.2FL"
					( Origin gFrontEnd )
				)
				( attribute "PHYS_PAGE" "150"
					( Origin gFrontEnd )
				)
				( attribute "ROT" "0"
					( Origin gFrontEnd )
				)
				( attribute "VALUE" "SCD1U16V2KX-3GP"
					( Origin gFrontEnd )
				)
				( attribute "VER" "1"
					( Origin gFrontEnd )
				)
				( attribute "XY" "(-5175,1400)"
					( Origin gFrontEnd )
				)
				( attribute "CHIPS_PART_NAME" "SCD1U16V2KX-3GP"
					( Origin gPackager )
				)
				( attribute "CDS_PART_NAME" "SCD1U16V2KX-3GP_SMD-BCG-SCD1U1A"
					( Origin gPackager )
				)
				( attribute "CDS_LOCATION" "C25W58"
					( Origin gPackager )
				)
				( attribute "CDS_SEC" "1"
					( Origin gPackager )
				)
				( attribute "SEC" "1"
					( Origin gPackager )
				)
				( objectStatus "C25W58" )
				( pin "\1\"
					( attribute "PN" "1"
						( Origin gPackager )
					)
					( objectStatus "C25W58.1" )
				)
				( pin "\2\"
					( attribute "PN" "2"
						( Origin gPackager )
					)
					( objectStatus "C25W58.2" )
				)
			)
			( gate "@baseboard_fab2_lib.baseboard_fab2(sch_1):page150_i84"
				( attribute "CDS_LIB" "w_hdl"
					( Origin gPackager )
				)
				( attribute "CDS_LMAN_SYM_OUTLINE" "-50,100,50,-100"
					( Origin gPackager )
				)
				( attribute "LOCATION" "FB2T4"
					( Origin gFrontEnd )
				)
				( attribute "PACK_TYPE" "DISCRET-G9"
					( Origin gFrontEnd )
				)
				( attribute "PART_NUMBER" "68.00230.231"
					( Origin gFrontEnd )
				)
				( attribute "PHYS_PAGE" "150"
					( Origin gFrontEnd )
				)
				( attribute "ROT" "1"
					( Origin gFrontEnd )
				)
				( attribute "VALUE" "HCB1608KF-800T30-GP"
					( Origin gFrontEnd )
				)
				( attribute "VER" "1"
					( Origin gFrontEnd )
				)
				( attribute "XY" "(-6275,2775)"
					( Origin gFrontEnd )
				)
				( attribute "CHIPS_PART_NAME" "HCB1608KF-800T30-GP"
					( Origin gPackager )
				)
				( attribute "CDS_PART_NAME" "HCB1608KF-800T30-GP_DISCRET-G9A"
					( Origin gPackager )
				)
				( attribute "CDS_LOCATION" "FB2T4"
					( Origin gPackager )
				)
				( attribute "CDS_SEC" "1"
					( Origin gPackager )
				)
				( attribute "SEC" "1"
					( Origin gPackager )
				)
				( objectStatus "FB2T4" )
				( pin "\1\"
					( attribute "PN" "1"
						( Origin gPackager )
					)
					( objectStatus "FB2T4.1" )
				)
				( pin "\2\"
					( attribute "PN" "2"
						( Origin gPackager )
					)
					( objectStatus "FB2T4.2" )
				)
			)
			( gate "@baseboard_fab2_lib.baseboard_fab2(sch_1):page155_i196"
				( attribute "BOM_COST" "DEBUG"
					( Origin gFrontEnd )
				)
				( attribute "CDS_LIB" "mstr_discrete"
					( Origin gPackager )
				)
				( attribute "LOCATION" "R6W19"
					( Origin gFrontEnd )
				)
				( attribute "MATERIAL" "CHIP"
					( Origin gFrontEnd )
				)
				( attribute "PACK_TYPE" "0402"
					( Origin gFrontEnd )
				)
				( attribute "PART_NUMBER" "G21497-005"
					( Origin gFrontEnd )
				)
				( attribute "PHYS_PAGE" "155"
					( Origin gFrontEnd )
				)
				( attribute "ROOM" "BMC_DEBUG_HEADER"
					( Origin gFrontEnd )
				)
				( attribute "ROT" "0"
					( Origin gFrontEnd )
				)
				( attribute "TOLERANCE" "5%"
					( Origin gFrontEnd )
				)
				( attribute "VALUE" "0.0"
					( Origin gFrontEnd )
				)
				( attribute "VER" "1"
					( Origin gFrontEnd )
				)
				( attribute "WATTAGE" "1/16W"
					( Origin gFrontEnd )
				)
				( attribute "XY" "(-2400,1775)"
					( Origin gFrontEnd )
				)
				( attribute "CHIPS_PART_NAME" "RES"
					( Origin gPackager )
				)
				( attribute "CDS_PART_NAME" "RES_0402-0.0,5%,1/16W,CHIP,G21A"
					( Origin gPackager )
				)
				( attribute "STATUS" "NOPOP"
					( Origin gFrontEnd )
				)
				( attribute "CDS_LOCATION" "R6W19"
					( Origin gPackager )
				)
				( attribute "CDS_SEC" "1"
					( Origin gPackager )
				)
				( attribute "SEC" "1"
					( Origin gPackager )
				)
				( objectStatus "R6W19" )
				( pin "a"
					( attribute "PN" "1"
						( Origin gPackager )
					)
					( objectStatus "R6W19.1" )
				)
				( pin "b"
					( attribute "PN" "2"
						( Origin gPackager )
					)
					( objectStatus "R6W19.2" )
				)
			)
			( gate "@baseboard_fab2_lib.baseboard_fab2(sch_1):page146_i68"
				( attribute "BOM_COST" "SM_CONTROLLER"
					( Origin gFrontEnd )
				)
				( attribute "CDS_LIB" "mstr_discrete"
					( Origin gPackager )
				)
				( attribute "CDS_LOCATION" "R25W82"
					( Origin gPackager )
				)
				( attribute "LOCATION" "R25W82"
					( Origin gFrontEnd )
				)
				( attribute "MATERIAL" "CHIP"
					( Origin gFrontEnd )
				)
				( attribute "PACK_TYPE" "0402"
					( Origin gFrontEnd )
				)
				( attribute "PART_NUMBER" "G21796-074"
					( Origin gFrontEnd )
				)
				( attribute "PHYS_PAGE" "146"
					( Origin gFrontEnd )
				)
				( attribute "ROOM" "BMC"
					( Origin gFrontEnd )
				)
				( attribute "ROT" "0"
					( Origin gFrontEnd )
				)
				( attribute "SEC" "1"
					( Origin gFrontEnd )
				)
				( attribute "SEC_TYPE" "0402"
					( Origin gFrontEnd )
				)
				( attribute "TOLERANCE" "1%"
					( Origin gFrontEnd )
				)
				( attribute "VALUE" "33.2"
					( Origin gFrontEnd )
				)
				( attribute "VER" "1"
					( Origin gFrontEnd )
				)
				( attribute "WATTAGE" "1/16W"
					( Origin gFrontEnd )
				)
				( attribute "XY" "(-6300,2500)"
					( Origin gFrontEnd )
				)
				( attribute "CHIPS_PART_NAME" "RES"
					( Origin gPackager )
				)
				( attribute "CDS_PART_NAME" "RES_0402-33.2,1%,1/16W,CHIP,G2A"
					( Origin gPackager )
				)
				( attribute "CDS_SEC" "1"
					( Origin gPackager )
				)
				( objectStatus "R25W82" )
				( pin "a"
					( attribute "PN" "1"
						( Origin gPackager )
					)
					( objectStatus "R25W82.1" )
				)
				( pin "b"
					( attribute "PN" "2"
						( Origin gPackager )
					)
					( objectStatus "R25W82.2" )
				)
			)
			( gate "@baseboard_fab2_lib.baseboard_fab2(sch_1):page149_i1"
				( attribute "CDS_LIB" "w_hdl"
					( Origin gPackager )
				)
				( attribute "CDS_LMAN_SYM_OUTLINE" "-325,1525,325,-1525"
					( Origin gPackager )
				)
				( attribute "LOCATION" "U25W5"
					( Origin gFrontEnd )
				)
				( attribute "PACK_TYPE" "MEMORY-G2"
					( Origin gFrontEnd )
				)
				( attribute "PART_NUMBER" "072.00546.0A0U"
					( Origin gFrontEnd )
				)
				( attribute "PHYS_PAGE" "149"
					( Origin gFrontEnd )
				)
				( attribute "ROT" "0"
					( Origin gFrontEnd )
				)
				( attribute "VALUE" "H5AN4G6NAFR-TFC-GP"
					( Origin gFrontEnd )
				)
				( attribute "VER" "1"
					( Origin gFrontEnd )
				)
				( attribute "XY" "(-1850,2625)"
					( Origin gFrontEnd )
				)
				( attribute "CHIPS_PART_NAME" "H5AN4G6NAFR-TFC-GP"
					( Origin gPackager )
				)
				( attribute "CDS_PART_NAME" "H5AN4G6NAFR-TFC-GP_MEMORY-G2-HA"
					( Origin gPackager )
				)
				( attribute "CDS_LOCATION" "U25W5"
					( Origin gPackager )
				)
				( attribute "CDS_SEC" "1"
					( Origin gPackager )
				)
				( attribute "SEC" "1"
					( Origin gPackager )
				)
				( objectStatus "U25W5" )
				( pin "a0"
					( attribute "PN" "P3"
						( Origin gPackager )
					)
					( objectStatus "U25W5.P3" )
				)
				( pin "a1"
					( attribute "PN" "P7"
						( Origin gPackager )
					)
					( objectStatus "U25W5.P7" )
				)
				( pin "a2"
					( attribute "PN" "R3"
						( Origin gPackager )
					)
					( objectStatus "U25W5.R3" )
				)
				( pin "a3"
					( attribute "PN" "N7"
						( Origin gPackager )
					)
					( objectStatus "U25W5.N7" )
				)
				( pin "a4"
					( attribute "PN" "N3"
						( Origin gPackager )
					)
					( objectStatus "U25W5.N3" )
				)
				( pin "a5"
					( attribute "PN" "P8"
						( Origin gPackager )
					)
					( objectStatus "U25W5.P8" )
				)
				( pin "a6"
					( attribute "PN" "P2"
						( Origin gPackager )
					)
					( objectStatus "U25W5.P2" )
				)
				( pin "a7"
					( attribute "PN" "R8"
						( Origin gPackager )
					)
					( objectStatus "U25W5.R8" )
				)
				( pin "a8"
					( attribute "PN" "R2"
						( Origin gPackager )
					)
					( objectStatus "U25W5.R2" )
				)
				( pin "a9"
					( attribute "PN" "R7"
						( Origin gPackager )
					)
					( objectStatus "U25W5.R7" )
				)
				( pin "\a10/ap\"
					( attribute "PN" "M3"
						( Origin gPackager )
					)
					( objectStatus "U25W5.M3" )
				)
				( pin "a11"
					( attribute "PN" "T2"
						( Origin gPackager )
					)
					( objectStatus "U25W5.T2" )
				)
				( pin "\a12/bc#\"
					( attribute "PN" "M7"
						( Origin gPackager )
					)
					( objectStatus "U25W5.M7" )
				)
				( pin "a13"
					( attribute "PN" "T8"
						( Origin gPackager )
					)
					( objectStatus "U25W5.T8" )
				)
				( pin "\act#\"
					( attribute "PN" "L3"
						( Origin gPackager )
					)
					( objectStatus "U25W5.L3" )
				)
				( pin "\alert#\"
					( attribute "PN" "P9"
						( Origin gPackager )
					)
					( objectStatus "U25W5.P9" )
				)
				( pin "ba0"
					( attribute "PN" "N2"
						( Origin gPackager )
					)
					( objectStatus "U25W5.N2" )
				)
				( pin "ba1"
					( attribute "PN" "N8"
						( Origin gPackager )
					)
					( objectStatus "U25W5.N8" )
				)
				( pin "bg0"
					( attribute "PN" "M2"
						( Origin gPackager )
					)
					( objectStatus "U25W5.M2" )
				)
				( pin "\cas#/a15\"
					( attribute "PN" "M8"
						( Origin gPackager )
					)
					( objectStatus "U25W5.M8" )
				)
				( pin "ck_c"
					( attribute "PN" "K8"
						( Origin gPackager )
					)
					( objectStatus "U25W5.K8" )
				)
				( pin "ck_t"
					( attribute "PN" "K7"
						( Origin gPackager )
					)
					( objectStatus "U25W5.K7" )
				)
				( pin "cke"
					( attribute "PN" "K2"
						( Origin gPackager )
					)
					( objectStatus "U25W5.K2" )
				)
				( pin "\cs#\"
					( attribute "PN" "L7"
						( Origin gPackager )
					)
					( objectStatus "U25W5.L7" )
				)
				( pin "\dml#/dbil#\"
					( attribute "PN" "E7"
						( Origin gPackager )
					)
					( objectStatus "U25W5.E7" )
				)
				( pin "\dmu#/dbiu#\"
					( attribute "PN" "E2"
						( Origin gPackager )
					)
					( objectStatus "U25W5.E2" )
				)
				( pin "dql0"
					( attribute "PN" "G2"
						( Origin gPackager )
					)
					( objectStatus "U25W5.G2" )
				)
				( pin "dql1"
					( attribute "PN" "F7"
						( Origin gPackager )
					)
					( objectStatus "U25W5.F7" )
				)
				( pin "dql2"
					( attribute "PN" "H3"
						( Origin gPackager )
					)
					( objectStatus "U25W5.H3" )
				)
				( pin "dql3"
					( attribute "PN" "H7"
						( Origin gPackager )
					)
					( objectStatus "U25W5.H7" )
				)
				( pin "dql4"
					( attribute "PN" "H2"
						( Origin gPackager )
					)
					( objectStatus "U25W5.H2" )
				)
				( pin "dql5"
					( attribute "PN" "H8"
						( Origin gPackager )
					)
					( objectStatus "U25W5.H8" )
				)
				( pin "dql6"
					( attribute "PN" "J3"
						( Origin gPackager )
					)
					( objectStatus "U25W5.J3" )
				)
				( pin "dql7"
					( attribute "PN" "J7"
						( Origin gPackager )
					)
					( objectStatus "U25W5.J7" )
				)
				( pin "dqsl_c"
					( attribute "PN" "F3"
						( Origin gPackager )
					)
					( objectStatus "U25W5.F3" )
				)
				( pin "dqsl_t"
					( attribute "PN" "G3"
						( Origin gPackager )
					)
					( objectStatus "U25W5.G3" )
				)
				( pin "dqsu_c"
					( attribute "PN" "A7"
						( Origin gPackager )
					)
					( objectStatus "U25W5.A7" )
				)
				( pin "dqsu_t"
					( attribute "PN" "B7"
						( Origin gPackager )
					)
					( objectStatus "U25W5.B7" )
				)
				( pin "dqu0"
					( attribute "PN" "A3"
						( Origin gPackager )
					)
					( objectStatus "U25W5.A3" )
				)
				( pin "dqu1"
					( attribute "PN" "B8"
						( Origin gPackager )
					)
					( objectStatus "U25W5.B8" )
				)
				( pin "dqu2"
					( attribute "PN" "C3"
						( Origin gPackager )
					)
					( objectStatus "U25W5.C3" )
				)
				( pin "dqu3"
					( attribute "PN" "C7"
						( Origin gPackager )
					)
					( objectStatus "U25W5.C7" )
				)
				( pin "dqu4"
					( attribute "PN" "C2"
						( Origin gPackager )
					)
					( objectStatus "U25W5.C2" )
				)
				( pin "dqu5"
					( attribute "PN" "C8"
						( Origin gPackager )
					)
					( objectStatus "U25W5.C8" )
				)
				( pin "dqu6"
					( attribute "PN" "D3"
						( Origin gPackager )
					)
					( objectStatus "U25W5.D3" )
				)
				( pin "dqu7"
					( attribute "PN" "D7"
						( Origin gPackager )
					)
					( objectStatus "U25W5.D7" )
				)
				( pin "\nc#t7\"
					( attribute "PN" "T7"
						( Origin gPackager )
					)
					( objectStatus "U25W5.T7" )
				)
				( pin "odt"
					( attribute "PN" "K3"
						( Origin gPackager )
					)
					( objectStatus "U25W5.K3" )
				)
				( pin "par"
					( attribute "PN" "T3"
						( Origin gPackager )
					)
					( objectStatus "U25W5.T3" )
				)
				( pin "\ras#/a16\"
					( attribute "PN" "L8"
						( Origin gPackager )
					)
					( objectStatus "U25W5.L8" )
				)
				( pin "\reset#\"
					( attribute "PN" "P1"
						( Origin gPackager )
					)
					( objectStatus "U25W5.P1" )
				)
				( pin "ten"
					( attribute "PN" "N9"
						( Origin gPackager )
					)
					( objectStatus "U25W5.N9" )
				)
				( pin "vdd(0)"
					( attribute "PN" "B3"
						( Origin gPackager )
					)
					( objectStatus "U25W5.B3" )
				)
				( pin "vdd(1)"
					( attribute "PN" "B9"
						( Origin gPackager )
					)
					( objectStatus "U25W5.B9" )
				)
				( pin "vdd(2)"
					( attribute "PN" "D1"
						( Origin gPackager )
					)
					( objectStatus "U25W5.D1" )
				)
				( pin "vdd(3)"
					( attribute "PN" "G7"
						( Origin gPackager )
					)
					( objectStatus "U25W5.G7" )
				)
				( pin "vdd(4)"
					( attribute "PN" "J1"
						( Origin gPackager )
					)
					( objectStatus "U25W5.J1" )
				)
				( pin "vdd(5)"
					( attribute "PN" "J9"
						( Origin gPackager )
					)
					( objectStatus "U25W5.J9" )
				)
				( pin "vdd(6)"
					( attribute "PN" "L1"
						( Origin gPackager )
					)
					( objectStatus "U25W5.L1" )
				)
				( pin "vdd(7)"
					( attribute "PN" "L9"
						( Origin gPackager )
					)
					( objectStatus "U25W5.L9" )
				)
				( pin "vdd(8)"
					( attribute "PN" "R1"
						( Origin gPackager )
					)
					( objectStatus "U25W5.R1" )
				)
				( pin "vdd(9)"
					( attribute "PN" "T9"
						( Origin gPackager )
					)
					( objectStatus "U25W5.T9" )
				)
				( pin "vddq(0)"
					( attribute "PN" "A1"
						( Origin gPackager )
					)
					( objectStatus "U25W5.A1" )
				)
				( pin "vddq(1)"
					( attribute "PN" "A9"
						( Origin gPackager )
					)
					( objectStatus "U25W5.A9" )
				)
				( pin "vddq(2)"
					( attribute "PN" "C1"
						( Origin gPackager )
					)
					( objectStatus "U25W5.C1" )
				)
				( pin "vddq(3)"
					( attribute "PN" "D9"
						( Origin gPackager )
					)
					( objectStatus "U25W5.D9" )
				)
				( pin "vddq(4)"
					( attribute "PN" "F2"
						( Origin gPackager )
					)
					( objectStatus "U25W5.F2" )
				)
				( pin "vddq(5)"
					( attribute "PN" "F8"
						( Origin gPackager )
					)
					( objectStatus "U25W5.F8" )
				)
				( pin "vddq(6)"
					( attribute "PN" "G1"
						( Origin gPackager )
					)
					( objectStatus "U25W5.G1" )
				)
				( pin "vddq(7)"
					( attribute "PN" "G9"
						( Origin gPackager )
					)
					( objectStatus "U25W5.G9" )
				)
				( pin "vddq(8)"
					( attribute "PN" "J2"
						( Origin gPackager )
					)
					( objectStatus "U25W5.J2" )
				)
				( pin "vddq(9)"
					( attribute "PN" "J8"
						( Origin gPackager )
					)
					( objectStatus "U25W5.J8" )
				)
				( pin "vpp(0)"
					( attribute "PN" "B1"
						( Origin gPackager )
					)
					( objectStatus "U25W5.B1" )
				)
				( pin "vpp(1)"
					( attribute "PN" "R9"
						( Origin gPackager )
					)
					( objectStatus "U25W5.R9" )
				)
				( pin "vrefca"
					( attribute "PN" "M1"
						( Origin gPackager )
					)
					( objectStatus "U25W5.M1" )
				)
				( pin "vss(0)"
					( attribute "PN" "B2"
						( Origin gPackager )
					)
					( objectStatus "U25W5.B2" )
				)
				( pin "vss(1)"
					( attribute "PN" "E1"
						( Origin gPackager )
					)
					( objectStatus "U25W5.E1" )
				)
				( pin "vss(2)"
					( attribute "PN" "E9"
						( Origin gPackager )
					)
					( objectStatus "U25W5.E9" )
				)
				( pin "vss(3)"
					( attribute "PN" "G8"
						( Origin gPackager )
					)
					( objectStatus "U25W5.G8" )
				)
				( pin "vss(4)"
					( attribute "PN" "K1"
						( Origin gPackager )
					)
					( objectStatus "U25W5.K1" )
				)
				( pin "vss(5)"
					( attribute "PN" "K9"
						( Origin gPackager )
					)
					( objectStatus "U25W5.K9" )
				)
				( pin "vss(6)"
					( attribute "PN" "M9"
						( Origin gPackager )
					)
					( objectStatus "U25W5.M9" )
				)
				( pin "vss(7)"
					( attribute "PN" "N1"
						( Origin gPackager )
					)
					( objectStatus "U25W5.N1" )
				)
				( pin "vss(8)"
					( attribute "PN" "T1"
						( Origin gPackager )
					)
					( objectStatus "U25W5.T1" )
				)
				( pin "vssq(0)"
					( attribute "PN" "A2"
						( Origin gPackager )
					)
					( objectStatus "U25W5.A2" )
				)
				( pin "vssq(1)"
					( attribute "PN" "A8"
						( Origin gPackager )
					)
					( objectStatus "U25W5.A8" )
				)
				( pin "vssq(2)"
					( attribute "PN" "C9"
						( Origin gPackager )
					)
					( objectStatus "U25W5.C9" )
				)
				( pin "vssq(3)"
					( attribute "PN" "D2"
						( Origin gPackager )
					)
					( objectStatus "U25W5.D2" )
				)
				( pin "vssq(4)"
					( attribute "PN" "D8"
						( Origin gPackager )
					)
					( objectStatus "U25W5.D8" )
				)
				( pin "vssq(5)"
					( attribute "PN" "E3"
						( Origin gPackager )
					)
					( objectStatus "U25W5.E3" )
				)
				( pin "vssq(6)"
					( attribute "PN" "E8"
						( Origin gPackager )
					)
					( objectStatus "U25W5.E8" )
				)
				( pin "vssq(7)"
					( attribute "PN" "F1"
						( Origin gPackager )
					)
					( objectStatus "U25W5.F1" )
				)
				( pin "vssq(8)"
					( attribute "PN" "H1"
						( Origin gPackager )
					)
					( objectStatus "U25W5.H1" )
				)
				( pin "vssq(9)"
					( attribute "PN" "H9"
						( Origin gPackager )
					)
					( objectStatus "U25W5.H9" )
				)
				( pin "\we#/a14\"
					( attribute "PN" "L2"
						( Origin gPackager )
					)
					( objectStatus "U25W5.L2" )
				)
				( pin "zq"
					( attribute "PN" "F9"
						( Origin gPackager )
					)
					( objectStatus "U25W5.F9" )
				)
			)
			( gate "@baseboard_fab2_lib.baseboard_fab2(sch_1):page239_i73"
				( attribute "CDS_LIB" "mstr_vreg"
					( Origin gPackager )
				)
				( attribute "LOCATION" "EU25F2"
					( Origin gFrontEnd )
				)
				( attribute "MATERIAL" "IC"
					( Origin gFrontEnd )
				)
				( attribute "PACK_TYPE" "DFN"
					( Origin gFrontEnd )
				)
				( attribute "PART_NUMBER" "H65765-001"
					( Origin gFrontEnd )
				)
				( attribute "PHYS_PAGE" "239"
					( Origin gFrontEnd )
				)
				( attribute "ROT" "0"
					( Origin gFrontEnd )
				)
				( attribute "VER" "1"
					( Origin gFrontEnd )
				)
				( attribute "XY" "(8425,1700)"
					( Origin gFrontEnd )
				)
				( attribute "CHIPS_PART_NAME" "RT9059"
					( Origin gPackager )
				)
				( attribute "CDS_PART_NAME" "RT9059_DFN-IC,H65765-001"
					( Origin gPackager )
				)
				( attribute "CDS_LOCATION" "EU25F2"
					( Origin gPackager )
				)
				( attribute "CDS_SEC" "1"
					( Origin gPackager )
				)
				( attribute "SEC" "1"
					( Origin gPackager )
				)
				( objectStatus "EU25F2" )
				( pin "adj_nc"
					( attribute "PN" "4"
						( Origin gPackager )
					)
					( objectStatus "EU25F2.4" )
				)
				( pin "en"
					( attribute "PN" "6"
						( Origin gPackager )
					)
					( objectStatus "EU25F2.6" )
				)
				( pin "gnd"
					( attribute "PN" "11"
						( Origin gPackager )
					)
					( objectStatus "EU25F2.11" )
				)
				( pin "pgood"
					( attribute "PN" "5"
						( Origin gPackager )
					)
					( objectStatus "EU25F2.5" )
				)
				( pin "vdd"
					( attribute "PN" "10"
						( Origin gPackager )
					)
					( objectStatus "EU25F2.10" )
				)
				( pin "vin(0)"
					( attribute "PN" "7"
						( Origin gPackager )
					)
					( objectStatus "EU25F2.7" )
				)
				( pin "vin(1)"
					( attribute "PN" "8"
						( Origin gPackager )
					)
					( objectStatus "EU25F2.8" )
				)
				( pin "vin(2)"
					( attribute "PN" "9"
						( Origin gPackager )
					)
					( objectStatus "EU25F2.9" )
				)
				( pin "vout(0)"
					( attribute "PN" "1"
						( Origin gPackager )
					)
					( objectStatus "EU25F2.1" )
				)
				( pin "vout(1)"
					( attribute "PN" "2"
						( Origin gPackager )
					)
					( objectStatus "EU25F2.2" )
				)
				( pin "vout(2)"
					( attribute "PN" "3"
						( Origin gPackager )
					)
					( objectStatus "EU25F2.3" )
				)
			)
			( gate "@baseboard_fab2_lib.baseboard_fab2(sch_1):page239_i77"
				( attribute "CDS_LIB" "mstr_discrete"
					( Origin gPackager )
				)
				( attribute "LOCATION" "R1W9"
					( Origin gFrontEnd )
				)
				( attribute "MATERIAL" "CHIP"
					( Origin gFrontEnd )
				)
				( attribute "PACK_TYPE" "0402"
					( Origin gFrontEnd )
				)
				( attribute "PART_NUMBER" "G21796-250"
					( Origin gFrontEnd )
				)
				( attribute "PHYS_PAGE" "239"
					( Origin gFrontEnd )
				)
				( attribute "ROOM" "P1V538_BMC_STBY_VR"
					( Origin gFrontEnd )
				)
				( attribute "ROT" "0"
					( Origin gFrontEnd )
				)
				( attribute "TOLERANCE" "1.0%"
					( Origin gFrontEnd )
				)
				( attribute "VALUE" "22.1"
					( Origin gFrontEnd )
				)
				( attribute "VER" "1"
					( Origin gFrontEnd )
				)
				( attribute "WATTAGE" "1/16W"
					( Origin gFrontEnd )
				)
				( attribute "XY" "(10275,2200)"
					( Origin gFrontEnd )
				)
				( attribute "CHIPS_PART_NAME" "RES"
					( Origin gPackager )
				)
				( attribute "CDS_PART_NAME" "RES_0402-22.1,1.0%,1/16W,CHIP,A"
					( Origin gPackager )
				)
				( attribute "CDS_LOCATION" "R1W9"
					( Origin gPackager )
				)
				( attribute "CDS_SEC" "1"
					( Origin gPackager )
				)
				( attribute "SEC" "1"
					( Origin gPackager )
				)
				( objectStatus "R1W9" )
				( pin "a"
					( attribute "PN" "1"
						( Origin gPackager )
					)
					( objectStatus "R1W9.1" )
				)
				( pin "b"
					( attribute "PN" "2"
						( Origin gPackager )
					)
					( objectStatus "R1W9.2" )
				)
			)
			( gate "@baseboard_fab2_lib.baseboard_fab2(sch_1):page239_i79"
				( attribute "BOM_COST" "P1V538_BMC_STBY_VR"
					( Origin gFrontEnd )
				)
				( attribute "CDS_LIB" "mstr_discrete"
					( Origin gPackager )
				)
				( attribute "LOCATION" "R9W12"
					( Origin gFrontEnd )
				)
				( attribute "MATERIAL" "CHIP"
					( Origin gFrontEnd )
				)
				( attribute "P1V5_STBY_IBMC" "<< NULL >>"
					( Origin gFrontEnd )
				)
				( attribute "P1V5_STBY_IBMC_VR" "<< NULL >>"
					( Origin gFrontEnd )
				)
				( attribute "PACK_TYPE" "0402"
					( Origin gFrontEnd )
				)
				( attribute "PART_NUMBER" "G21796-016"
					( Origin gFrontEnd )
				)
				( attribute "PHYS_PAGE" "239"
					( Origin gFrontEnd )
				)
				( attribute "ROOM" "P1V538_BMC_STBY_VR"
					( Origin gFrontEnd )
				)
				( attribute "ROT" "0"
					( Origin gFrontEnd )
				)
				( attribute "TOLERANCE" "1%"
					( Origin gFrontEnd )
				)
				( attribute "VALUE" "10.0K"
					( Origin gFrontEnd )
				)
				( attribute "VER" "2"
					( Origin gFrontEnd )
				)
				( attribute "WATTAGE" "1/16W"
					( Origin gFrontEnd )
				)
				( attribute "XY" "(9200,2450)"
					( Origin gFrontEnd )
				)
				( attribute "CHIPS_PART_NAME" "RES"
					( Origin gPackager )
				)
				( attribute "CDS_PART_NAME" "RES_0402-10.0K,1%,1/16W,CHIP,GA"
					( Origin gPackager )
				)
				( attribute "CDS_LOCATION" "R9W12"
					( Origin gPackager )
				)
				( attribute "CDS_SEC" "1"
					( Origin gPackager )
				)
				( attribute "SEC" "1"
					( Origin gPackager )
				)
				( objectStatus "R9W12" )
				( pin "a"
					( attribute "PN" "1"
						( Origin gPackager )
					)
					( objectStatus "R9W12.1" )
				)
				( pin "b"
					( attribute "PN" "2"
						( Origin gPackager )
					)
					( objectStatus "R9W12.2" )
				)
			)
			( gate "@baseboard_fab2_lib.baseboard_fab2(sch_1):page239_i81"
				( attribute "BOM_COST" "P1V538_BMC_STBY_VR"
					( Origin gFrontEnd )
				)
				( attribute "CDS_LIB" "mstr_discrete"
					( Origin gPackager )
				)
				( attribute "LOCATION" "C9W13"
					( Origin gFrontEnd )
				)
				( attribute "MATERIAL" "X6S"
					( Origin gFrontEnd )
				)
				( attribute "PACK_TYPE" "0805LF"
					( Origin gFrontEnd )
				)
				( attribute "PART_NUMBER" "C95333-002"
					( Origin gFrontEnd )
				)
				( attribute "PHYS_PAGE" "239"
					( Origin gFrontEnd )
				)
				( attribute "ROOM" "P1V538_BMC_STBY_VR"
					( Origin gFrontEnd )
				)
				( attribute "ROT" "0"
					( Origin gFrontEnd )
				)
				( attribute "TOLERANCE" "20%"
					( Origin gFrontEnd )
				)
				( attribute "VALUE" "22UF"
					( Origin gFrontEnd )
				)
				( attribute "VER" "1"
					( Origin gFrontEnd )
				)
				( attribute "VOLTAGE" "4V"
					( Units "uVoltage" "V" 1.000000)
					( Origin gFrontEnd )
				)
				( attribute "XY" "(10875,1475)"
					( Origin gFrontEnd )
				)
				( attribute "CHIPS_PART_NAME" "CAP"
					( Origin gPackager )
				)
				( attribute "CDS_PART_NAME" "CAP_0805LF-22UF,4V,20%,X6S,C95A"
					( Origin gPackager )
				)
				( attribute "CDS_LOCATION" "C9W13"
					( Origin gPackager )
				)
				( attribute "CDS_SEC" "1"
					( Origin gPackager )
				)
				( attribute "SEC" "1"
					( Origin gPackager )
				)
				( objectStatus "C9W13" )
				( pin "a"
					( attribute "PN" "1"
						( Origin gPackager )
					)
					( objectStatus "C9W13.1" )
				)
				( pin "b"
					( attribute "PN" "2"
						( Origin gPackager )
					)
					( objectStatus "C9W13.2" )
				)
			)
			( gate "@baseboard_fab2_lib.baseboard_fab2(sch_1):page239_i83"
				( attribute "BOM_COST" "P1V538_BMC_STBY_VR"
					( Origin gFrontEnd )
				)
				( attribute "CDS_LIB" "mstr_discrete"
					( Origin gPackager )
				)
				( attribute "LOCATION" "C1W15"
					( Origin gFrontEnd )
				)
				( attribute "MATERIAL" "X6S"
					( Origin gFrontEnd )
				)
				( attribute "PACK_TYPE" "0603"
					( Origin gFrontEnd )
				)
				( attribute "PART_NUMBER" "E15431-002"
					( Origin gFrontEnd )
				)
				( attribute "PHYS_PAGE" "239"
					( Origin gFrontEnd )
				)
				( attribute "ROOM" "P1V538_BMC_STBY_VR"
					( Origin gFrontEnd )
				)
				( attribute "ROT" "0"
					( Origin gFrontEnd )
				)
				( attribute "TOLERANCE" "20%"
					( Origin gFrontEnd )
				)
				( attribute "VALUE" "10UF"
					( Origin gFrontEnd )
				)
				( attribute "VER" "1"
					( Origin gFrontEnd )
				)
				( attribute "VOLTAGE" "6.3V"
					( Units "uVoltage" "V" 1.000000)
					( Origin gFrontEnd )
				)
				( attribute "XY" "(10450,1550)"
					( Origin gFrontEnd )
				)
				( attribute "CHIPS_PART_NAME" "CAP"
					( Origin gPackager )
				)
				( attribute "CDS_PART_NAME" "CAP_0603-10UF,6.3V,20%,X6S,E15A"
					( Origin gPackager )
				)
				( attribute "CDS_LOCATION" "C1W15"
					( Origin gPackager )
				)
				( attribute "CDS_SEC" "1"
					( Origin gPackager )
				)
				( attribute "SEC" "1"
					( Origin gPackager )
				)
				( objectStatus "C1W15" )
				( pin "a"
					( attribute "PN" "1"
						( Origin gPackager )
					)
					( objectStatus "C1W15.1" )
				)
				( pin "b"
					( attribute "PN" "2"
						( Origin gPackager )
					)
					( objectStatus "C1W15.2" )
				)
			)
			( gate "@baseboard_fab2_lib.baseboard_fab2(sch_1):page239_i84"
				( attribute "BOM_COST" "P1V538_BMC_STBY_VR"
					( Origin gFrontEnd )
				)
				( attribute "CDS_LIB" "mstr_discrete"
					( Origin gPackager )
				)
				( attribute "LOCATION" "C9W10"
					( Origin gFrontEnd )
				)
				( attribute "MATERIAL" "X7R"
					( Origin gFrontEnd )
				)
				( attribute "PACK_TYPE" "0402LF"
					( Origin gFrontEnd )
				)
				( attribute "PART_NUMBER" "A36096-046"
					( Origin gFrontEnd )
				)
				( attribute "PHYS_PAGE" "239"
					( Origin gFrontEnd )
				)
				( attribute "ROOM" "P1V538_BMC_STBY_VR"
					( Origin gFrontEnd )
				)
				( attribute "ROT" "0"
					( Origin gFrontEnd )
				)
				( attribute "TOLERANCE" "10%"
					( Origin gFrontEnd )
				)
				( attribute "VALUE" "1000PF"
					( Origin gFrontEnd )
				)
				( attribute "VER" "1"
					( Origin gFrontEnd )
				)
				( attribute "VOLTAGE" "50V"
					( Units "uVoltage" "V" 1.000000)
					( Origin gFrontEnd )
				)
				( attribute "XY" "(9950,2075)"
					( Origin gFrontEnd )
				)
				( attribute "CHIPS_PART_NAME" "CAP"
					( Origin gPackager )
				)
				( attribute "CDS_PART_NAME" "CAP_0402LF-1000PF,50V,10%,X7R,A"
					( Origin gPackager )
				)
				( attribute "CDS_LOCATION" "C9W10"
					( Origin gPackager )
				)
				( attribute "CDS_SEC" "1"
					( Origin gPackager )
				)
				( attribute "SEC" "1"
					( Origin gPackager )
				)
				( objectStatus "C9W10" )
				( pin "a"
					( attribute "PN" "1"
						( Origin gPackager )
					)
					( objectStatus "C9W10.1" )
				)
				( pin "b"
					( attribute "PN" "2"
						( Origin gPackager )
					)
					( objectStatus "C9W10.2" )
				)
			)
			( gate "@baseboard_fab2_lib.baseboard_fab2(sch_1):page239_i87"
				( attribute "BOM_COST" "P1V538_BMC_STBY_VR"
					( Origin gFrontEnd )
				)
				( attribute "CDS_LIB" "mstr_discrete"
					( Origin gPackager )
				)
				( attribute "LOCATION" "R9W32"
					( Origin gFrontEnd )
				)
				( attribute "MATERIAL" "CHIP"
					( Origin gFrontEnd )
				)
				( attribute "P1V5_STBY_IBMC" "<< NULL >>"
					( Origin gFrontEnd )
				)
				( attribute "P1V5_STBY_IBMC_VR" "<< NULL >>"
					( Origin gFrontEnd )
				)
				( attribute "PACK_TYPE" "0402"
					( Origin gFrontEnd )
				)
				( attribute "PART_NUMBER" "G21796-221"
					( Origin gFrontEnd )
				)
				( attribute "PHYS_PAGE" "239"
					( Origin gFrontEnd )
				)
				( attribute "ROOM" "P1V538_BMC_STBY_VR"
					( Origin gFrontEnd )
				)
				( attribute "ROT" "1"
					( Origin gFrontEnd )
				)
				( attribute "TOLERANCE" "1.0%"
					( Origin gFrontEnd )
				)
				( attribute "VALUE" "13K"
					( Origin gFrontEnd )
				)
				( attribute "VER" "1"
					( Origin gFrontEnd )
				)
				( attribute "WATTAGE" "1/16W"
					( Origin gFrontEnd )
				)
				( attribute "XY" "(9925,900)"
					( Origin gFrontEnd )
				)
				( attribute "CHIPS_PART_NAME" "RES"
					( Origin gPackager )
				)
				( attribute "CDS_PART_NAME" "RES_0402-13K,1.0%,1/16W,CHIP,GA"
					( Origin gPackager )
				)
				( attribute "CDS_LOCATION" "R9W32"
					( Origin gPackager )
				)
				( attribute "CDS_SEC" "1"
					( Origin gPackager )
				)
				( attribute "SEC" "1"
					( Origin gPackager )
				)
				( objectStatus "R9W32" )
				( pin "a"
					( attribute "PN" "1"
						( Origin gPackager )
					)
					( objectStatus "R9W32.1" )
				)
				( pin "b"
					( attribute "PN" "2"
						( Origin gPackager )
					)
					( objectStatus "R9W32.2" )
				)
			)
			( gate "@baseboard_fab2_lib.baseboard_fab2(sch_1):page239_i90"
				( attribute "CDS_LIB" "dev_discrete"
					( Origin gPackager )
				)
				( attribute "LOCATION" "C9W5"
					( Origin gFrontEnd )
				)
				( attribute "MATERIAL" "X7R"
					( Origin gFrontEnd )
				)
				( attribute "PACK_TYPE" "0402V"
					( Origin gFrontEnd )
				)
				( attribute "PART_NUMBER" "A36096-030"
					( Origin gFrontEnd )
				)
				( attribute "PHYS_PAGE" "239"
					( Origin gFrontEnd )
				)
				( attribute "ROT" "0"
					( Origin gFrontEnd )
				)
				( attribute "TOLERANCE" "10%"
					( Origin gFrontEnd )
				)
				( attribute "VALUE" "0.1UF"
					( Origin gFrontEnd )
				)
				( attribute "VER" "1"
					( Origin gFrontEnd )
				)
				( attribute "VOLTAGE" "16V"
					( Units "uVoltage" "V" 1.000000)
					( Origin gFrontEnd )
				)
				( attribute "XY" "(7050,2050)"
					( Origin gFrontEnd )
				)
				( attribute "CHIPS_PART_NAME" "CAP_A"
					( Origin gPackager )
				)
				( attribute "CDS_PART_NAME" "CAP_A_0402V-0.1UF,16V,10%,X7R,A"
					( Origin gPackager )
				)
				( attribute "CDS_LOCATION" "C9W5"
					( Origin gPackager )
				)
				( attribute "CDS_SEC" "1"
					( Origin gPackager )
				)
				( attribute "SEC" "1"
					( Origin gPackager )
				)
				( objectStatus "C9W5" )
				( pin "a"
					( attribute "PN" "1"
						( Origin gPackager )
					)
					( objectStatus "C9W5.1" )
				)
				( pin "b"
					( attribute "PN" "2"
						( Origin gPackager )
					)
					( objectStatus "C9W5.2" )
				)
			)
			( gate "@baseboard_fab2_lib.baseboard_fab2(sch_1):page239_i91"
				( attribute "BOM_COST" "P1V538_BMC_STBY_VR"
					( Origin gFrontEnd )
				)
				( attribute "CDS_LIB" "mstr_discrete"
					( Origin gPackager )
				)
				( attribute "LOCATION" "C9W6"
					( Origin gFrontEnd )
				)
				( attribute "MATERIAL" "EMPTY"
					( Origin gFrontEnd )
				)
				( attribute "PACK_TYPE" "0402LF"
					( Origin gFrontEnd )
				)
				( attribute "PART_NUMBER" "A36096-046"
					( Origin gFrontEnd )
				)
				( attribute "PHYS_PAGE" "239"
					( Origin gFrontEnd )
				)
				( attribute "ROOM" "P1V538_BMC_STBY_VR"
					( Origin gFrontEnd )
				)
				( attribute "ROT" "2"
					( Origin gFrontEnd )
				)
				( attribute "TOLERANCE" "10%"
					( Origin gFrontEnd )
				)
				( attribute "VALUE" "1000PF"
					( Origin gFrontEnd )
				)
				( attribute "VER" "1"
					( Origin gFrontEnd )
				)
				( attribute "VOLTAGE" "50V"
					( Units "uVoltage" "V" 1.000000)
					( Origin gFrontEnd )
				)
				( attribute "XY" "(6625,1225)"
					( Origin gFrontEnd )
				)
				( attribute "CHIPS_PART_NAME" "CAP"
					( Origin gPackager )
				)
				( attribute "CDS_PART_NAME" "CAP_0402LF-1000PF,50V,10%,EMPTA"
					( Origin gPackager )
				)
				( attribute "CDS_LOCATION" "C9W6"
					( Origin gPackager )
				)
				( attribute "CDS_SEC" "1"
					( Origin gPackager )
				)
				( attribute "SEC" "1"
					( Origin gPackager )
				)
				( objectStatus "C9W6" )
				( pin "a"
					( attribute "PN" "1"
						( Origin gPackager )
					)
					( objectStatus "C9W6.1" )
				)
				( pin "b"
					( attribute "PN" "2"
						( Origin gPackager )
					)
					( objectStatus "C9W6.2" )
				)
			)
			( gate "@baseboard_fab2_lib.baseboard_fab2(sch_1):page239_i92"
				( attribute "BOM_COST" "P1V538_BMC_STBY_VR"
					( Origin gFrontEnd )
				)
				( attribute "CDS_LIB" "mstr_discrete"
					( Origin gPackager )
				)
				( attribute "LOCATION" "C1W7"
					( Origin gFrontEnd )
				)
				( attribute "MATERIAL" "X6S"
					( Origin gFrontEnd )
				)
				( attribute "PACK_TYPE" "0603"
					( Origin gFrontEnd )
				)
				( attribute "PART_NUMBER" "E15431-002"
					( Origin gFrontEnd )
				)
				( attribute "PHYS_PAGE" "239"
					( Origin gFrontEnd )
				)
				( attribute "ROOM" "P1V538_BMC_STBY_VR"
					( Origin gFrontEnd )
				)
				( attribute "ROT" "0"
					( Origin gFrontEnd )
				)
				( attribute "TOLERANCE" "20%"
					( Origin gFrontEnd )
				)
				( attribute "VALUE" "10UF"
					( Origin gFrontEnd )
				)
				( attribute "VER" "1"
					( Origin gFrontEnd )
				)
				( attribute "VOLTAGE" "6.3V"
					( Units "uVoltage" "V" 1.000000)
					( Origin gFrontEnd )
				)
				( attribute "XY" "(6100,2075)"
					( Origin gFrontEnd )
				)
				( attribute "CHIPS_PART_NAME" "CAP"
					( Origin gPackager )
				)
				( attribute "CDS_PART_NAME" "CAP_0603-10UF,6.3V,20%,X6S,E15A"
					( Origin gPackager )
				)
				( attribute "CDS_LOCATION" "C1W7"
					( Origin gPackager )
				)
				( attribute "CDS_SEC" "1"
					( Origin gPackager )
				)
				( attribute "SEC" "1"
					( Origin gPackager )
				)
				( objectStatus "C1W7" )
				( pin "a"
					( attribute "PN" "1"
						( Origin gPackager )
					)
					( objectStatus "C1W7.1" )
				)
				( pin "b"
					( attribute "PN" "2"
						( Origin gPackager )
					)
					( objectStatus "C1W7.2" )
				)
			)
			( gate "@baseboard_fab2_lib.baseboard_fab2(sch_1):page143_i55"
				( attribute "BOM_COST" "SM_CONTROLLER"
					( Origin gFrontEnd )
				)
				( attribute "CDS_LIB" "mstr_discrete"
					( Origin gPackager )
				)
				( attribute "LOCATION" "C25W22"
					( Origin gFrontEnd )
				)
				( attribute "MATERIAL" "X7R"
					( Origin gFrontEnd )
				)
				( attribute "PACK_TYPE" "0402LF"
					( Origin gFrontEnd )
				)
				( attribute "PART_NUMBER" "A36096-030"
					( Origin gFrontEnd )
				)
				( attribute "PHYS_PAGE" "143"
					( Origin gFrontEnd )
				)
				( attribute "ROOM" "BMC"
					( Origin gFrontEnd )
				)
				( attribute "ROT" "3"
					( Origin gFrontEnd )
				)
				( attribute "TOLERANCE" "10%"
					( Origin gFrontEnd )
				)
				( attribute "VALUE" "0.1UF"
					( Origin gFrontEnd )
				)
				( attribute "VER" "1"
					( Origin gFrontEnd )
				)
				( attribute "VOLTAGE" "16V"
					( Units "uVoltage" "V" 1.000000)
					( Origin gFrontEnd )
				)
				( attribute "XY" "(-10500,-2200)"
					( Origin gFrontEnd )
				)
				( attribute "CHIPS_PART_NAME" "CAP"
					( Origin gPackager )
				)
				( attribute "CDS_PART_NAME" "CAP_0402LF-0.1UF,16V,10%,X7R,AA"
					( Origin gPackager )
				)
				( attribute "CDS_LOCATION" "C25W22"
					( Origin gPackager )
				)
				( attribute "CDS_SEC" "1"
					( Origin gPackager )
				)
				( attribute "SEC" "1"
					( Origin gPackager )
				)
				( objectStatus "C25W22" )
				( pin "a"
					( attribute "PN" "1"
						( Origin gPackager )
					)
					( objectStatus "C25W22.1" )
				)
				( pin "b"
					( attribute "PN" "2"
						( Origin gPackager )
					)
					( objectStatus "C25W22.2" )
				)
			)
			( gate "@baseboard_fab2_lib.baseboard_fab2(sch_1):page144_i95"
				( attribute "CDS_LIB" "w_hdl"
					( Origin gPackager )
				)
				( attribute "CDS_LMAN_SYM_OUTLINE" "-1150,1150,1150,-1150"
					( Origin gPackager )
				)
				( attribute "LOCATION" "U25W4"
					( Origin gFrontEnd )
				)
				( attribute "PACK_TYPE" "ASIC2-GB1"
					( Origin gFrontEnd )
				)
				( attribute "PART_NUMBER" "071.2520A.M001"
					( Origin gFrontEnd )
				)
				( attribute "PHYS_PAGE" "144"
					( Origin gFrontEnd )
				)
				( attribute "ROT" "0"
					( Origin gFrontEnd )
				)
				( attribute "VALUE" "AST2520A1-GP-GP"
					( Origin gFrontEnd )
				)
				( attribute "VER" "2"
					( Origin gFrontEnd )
				)
				( attribute "XY" "(-4375,-2600)"
					( Origin gFrontEnd )
				)
				( attribute "CHIPS_PART_NAME" "AST2520A1-GP-GP"
					( Origin gPackager )
				)
				( attribute "CDS_PART_NAME" "AST2520A1-GP-GP_ASIC2-GB1-AST2A"
					( Origin gPackager )
				)
				( attribute "CDS_LOCATION" "U25W4"
					( Origin gPackager )
				)
				( attribute "CDS_SEC" "2"
					( Origin gPackager )
				)
				( attribute "SEC" "2"
					( Origin gPackager )
				)
				( objectStatus "U25W4" )
				( pin "dacb"
					( attribute "PN" "J2"
						( Origin gPackager )
					)
					( objectStatus "U25W4.J2" )
				)
				( pin "dacg"
					( attribute "PN" "J3"
						( Origin gPackager )
					)
					( objectStatus "U25W4.J3" )
				)
				( pin "dacr"
					( attribute "PN" "J4"
						( Origin gPackager )
					)
					( objectStatus "U25W4.J4" )
				)
				( pin "dacrset"
					( attribute "PN" "K4"
						( Origin gPackager )
					)
					( objectStatus "U25W4.K4" )
				)
				( pin "gpioa4_timer5_scl9"
					( attribute "PN" "C14"
						( Origin gPackager )
					)
					( objectStatus "U25W4.C14" )
				)
				( pin "gpioa5_timer6_sda9"
					( attribute "PN" "A13"
						( Origin gPackager )
					)
					( objectStatus "U25W4.A13" )
				)
				( pin "gpiob0"
					( attribute "PN" "K19"
						( Origin gPackager )
					)
					( objectStatus "U25W4.K19" )
				)
				( pin "gpiob1"
					( attribute "PN" "L19"
						( Origin gPackager )
					)
					( objectStatus "U25W4.L19" )
				)
				( pin "gpiob2"
					( attribute "PN" "L18"
						( Origin gPackager )
					)
					( objectStatus "U25W4.L18" )
				)
				( pin "gpiob3"
					( attribute "PN" "K18"
						( Origin gPackager )
					)
					( objectStatus "U25W4.K18" )
				)
				( pin "gpiob4_usbcki"
					( attribute "PN" "J20"
						( Origin gPackager )
					)
					( objectStatus "U25W4.J20" )
				)
				( pin "\gpiob5_lpcpd#_lpcsmi#\"
					( attribute "PN" "H21"
						( Origin gPackager )
					)
					( objectStatus "U25W4.H21" )
				)
				( pin "\gpiob6_lpcpme#\"
					( attribute "PN" "H22"
						( Origin gPackager )
					)
					( objectStatus "U25W4.H22" )
				)
				( pin "gpiob7"
					( attribute "PN" "H20"
						( Origin gPackager )
					)
					( objectStatus "U25W4.H20" )
				)
				( pin "gpiog0_sgps1ck"
					( attribute "PN" "A19"
						( Origin gPackager )
					)
					( objectStatus "U25W4.A19" )
				)
				( pin "gpiog1_sgps1ld"
					( attribute "PN" "E19"
						( Origin gPackager )
					)
					( objectStatus "U25W4.E19" )
				)
				( pin "gpiog2_sgps1i0"
					( attribute "PN" "C19"
						( Origin gPackager )
					)
					( objectStatus "U25W4.C19" )
				)
				( pin "gpiog3_sgps1i1"
					( attribute "PN" "E16"
						( Origin gPackager )
					)
					( objectStatus "U25W4.E16" )
				)
				( pin "\gpioi0_syscs#\"
					( attribute "PN" "C18"
						( Origin gPackager )
					)
					( objectStatus "U25W4.C18" )
				)
				( pin "gpioi1_sysck"
					( attribute "PN" "E15"
						( Origin gPackager )
					)
					( objectStatus "U25W4.E15" )
				)
				( pin "gpioi2_sysmosi"
					( attribute "PN" "B16"
						( Origin gPackager )
					)
					( objectStatus "U25W4.B16" )
				)
				( pin "gpioi3_sysmiso"
					( attribute "PN" "C16"
						( Origin gPackager )
					)
					( objectStatus "U25W4.C16" )
				)
				( pin "\gpioi4_spi1cs0#_vbcs#\"
					( attribute "PN" "B15"
						( Origin gPackager )
					)
					( objectStatus "U25W4.B15" )
				)
				( pin "gpioi5_spi1ck_vbck"
					( attribute "PN" "C15"
						( Origin gPackager )
					)
					( objectStatus "U25W4.C15" )
				)
				( pin "gpioi6_spi1mosi_vbmosi"
					( attribute "PN" "A14"
						( Origin gPackager )
					)
					( objectStatus "U25W4.A14" )
				)
				( pin "gpioi7_spi1miso_vbmiso"
					( attribute "PN" "A15"
						( Origin gPackager )
					)
					( objectStatus "U25W4.A15" )
				)
				( pin "gpioj0_sgpmck"
					( attribute "PN" "R2"
						( Origin gPackager )
					)
					( objectStatus "U25W4.R2" )
				)
				( pin "gpioj1_sgpmld"
					( attribute "PN" "L2"
						( Origin gPackager )
					)
					( objectStatus "U25W4.L2" )
				)
				( pin "gpioj2_sgpmo"
					( attribute "PN" "N3"
						( Origin gPackager )
					)
					( objectStatus "U25W4.N3" )
				)
				( pin "gpioj3_sgpmi"
					( attribute "PN" "N4"
						( Origin gPackager )
					)
					( objectStatus "U25W4.N4" )
				)
				( pin "gpiok0_scl5"
					( attribute "PN" "L3"
						( Origin gPackager )
					)
					( objectStatus "U25W4.L3" )
				)
				( pin "gpiok1_sda5"
					( attribute "PN" "L4"
						( Origin gPackager )
					)
					( objectStatus "U25W4.L4" )
				)
				( pin "gpiok2_scl6"
					( attribute "PN" "L1"
						( Origin gPackager )
					)
					( objectStatus "U25W4.L1" )
				)
				( pin "gpiok3_sda6"
					( attribute "PN" "N2"
						( Origin gPackager )
					)
					( objectStatus "U25W4.N2" )
				)
				( pin "gpiok4_scl7"
					( attribute "PN" "N1"
						( Origin gPackager )
					)
					( objectStatus "U25W4.N1" )
				)
				( pin "gpiok5_sda7"
					( attribute "PN" "P1"
						( Origin gPackager )
					)
					( objectStatus "U25W4.P1" )
				)
				( pin "gpiok6_scl8"
					( attribute "PN" "P2"
						( Origin gPackager )
					)
					( objectStatus "U25W4.P2" )
				)
				( pin "gpiok7_sda8"
					( attribute "PN" "R1"
						( Origin gPackager )
					)
					( objectStatus "U25W4.R1" )
				)
				( pin "gpioq0_scl3"
					( attribute "PN" "A11"
						( Origin gPackager )
					)
					( objectStatus "U25W4.A11" )
				)
				( pin "gpioq1_sda3"
					( attribute "PN" "A10"
						( Origin gPackager )
					)
					( objectStatus "U25W4.A10" )
				)
				( pin "gpioq2_scl4"
					( attribute "PN" "A9"
						( Origin gPackager )
					)
					( objectStatus "U25W4.A9" )
				)
				( pin "gpioq3_sda4"
					( attribute "PN" "B9"
						( Origin gPackager )
					)
					( objectStatus "U25W4.B9" )
				)
				( pin "gpioq4_scl14"
					( attribute "PN" "N21"
						( Origin gPackager )
					)
					( objectStatus "U25W4.N21" )
				)
				( pin "gpioq5_sda14"
					( attribute "PN" "N22"
						( Origin gPackager )
					)
					( objectStatus "U25W4.N22" )
				)
				( pin "gpioy4_scl1"
					( attribute "PN" "M18"
						( Origin gPackager )
					)
					( objectStatus "U25W4.M18" )
				)
				( pin "gpioy5_sda1"
					( attribute "PN" "M19"
						( Origin gPackager )
					)
					( objectStatus "U25W4.M19" )
				)
				( pin "gpioy6_scl2"
					( attribute "PN" "M20"
						( Origin gPackager )
					)
					( objectStatus "U25W4.M20" )
				)
				( pin "gpioy7_sda2"
					( attribute "PN" "P20"
						( Origin gPackager )
					)
					( objectStatus "U25W4.P20" )
				)
				( pin "ntrst"
					( attribute "PN" "E11"
						( Origin gPackager )
					)
					( objectStatus "U25W4.E11" )
				)
				( pin "rtck"
					( attribute "PN" "C9"
						( Origin gPackager )
					)
					( objectStatus "U25W4.C9" )
				)
				( pin "tck"
					( attribute "PN" "C10"
						( Origin gPackager )
					)
					( objectStatus "U25W4.C10" )
				)
				( pin "tdi"
					( attribute "PN" "D12"
						( Origin gPackager )
					)
					( objectStatus "U25W4.D12" )
				)
				( pin "tdo"
					( attribute "PN" "D11"
						( Origin gPackager )
					)
					( objectStatus "U25W4.D11" )
				)
				( pin "tms"
					( attribute "PN" "C8"
						( Origin gPackager )
					)
					( objectStatus "U25W4.C8" )
				)
			)
			( gate "@baseboard_fab2_lib.baseboard_fab2(sch_1):page249_i30"
				( attribute "CDS_LIB" "mstr_discrete"
					( Origin gPackager )
				)
				( attribute "LOCATION" "Q9W1"
					( Origin gFrontEnd )
				)
				( attribute "MATERIAL" "FET"
					( Origin gFrontEnd )
				)
				( attribute "PACK_TYPE" "SOT23LF"
					( Origin gFrontEnd )
				)
				( attribute "PART_NUMBER" "C79254-001"
					( Origin gFrontEnd )
				)
				( attribute "PHYS_PAGE" "249"
					( Origin gFrontEnd )
				)
				( attribute "ROOM" "HOT_SWAP"
					( Origin gFrontEnd )
				)
				( attribute "ROT" "0"
					( Origin gFrontEnd )
				)
				( attribute "VALUE" "2N7002"
					( Origin gFrontEnd )
				)
				( attribute "VER" "8"
					( Origin gFrontEnd )
				)
				( attribute "XY" "(-5875,2250)"
					( Origin gFrontEnd )
				)
				( attribute "CHIPS_PART_NAME" "FET_N"
					( Origin gPackager )
				)
				( attribute "CDS_PART_NAME" "FET_N_SOT23LF-2N7002,FET,C7925A"
					( Origin gPackager )
				)
				( attribute "CDS_LOCATION" "Q9W1"
					( Origin gPackager )
				)
				( attribute "CDS_SEC" "1"
					( Origin gPackager )
				)
				( attribute "SEC" "1"
					( Origin gPackager )
				)
				( objectStatus "Q9W1" )
				( pin "drn"
					( attribute "PN" "3"
						( Origin gPackager )
					)
					( objectStatus "Q9W1.3" )
				)
				( pin "gate"
					( attribute "PN" "1"
						( Origin gPackager )
					)
					( objectStatus "Q9W1.1" )
				)
				( pin "src"
					( attribute "PN" "2"
						( Origin gPackager )
					)
					( objectStatus "Q9W1.2" )
				)
			)
			( gate "@baseboard_fab2_lib.baseboard_fab2(sch_1):page150_i57"
				( attribute "CDS_LIB" "w_hdl"
					( Origin gPackager )
				)
				( attribute "CDS_LMAN_SYM_OUTLINE" "-50,75,50,-75"
					( Origin gPackager )
				)
				( attribute "LOCATION" "R25W93"
					( Origin gFrontEnd )
				)
				( attribute "PACK_TYPE" "RCL_GP"
					( Origin gFrontEnd )
				)
				( attribute "PART_NUMBER" "63.00000.00L"
					( Origin gFrontEnd )
				)
				( attribute "PHYS_PAGE" "150"
					( Origin gFrontEnd )
				)
				( attribute "ROT" "1"
					( Origin gFrontEnd )
				)
				( attribute "VALUE" "0R3J-0-U-GP"
					( Origin gFrontEnd )
				)
				( attribute "VER" "1"
					( Origin gFrontEnd )
				)
				( attribute "XY" "(-4075,3850)"
					( Origin gFrontEnd )
				)
				( attribute "CHIPS_PART_NAME" "0R3J-0-U-GP"
					( Origin gPackager )
				)
				( attribute "CDS_PART_NAME" "0R3J-0-U-GP_RCL_GP-0R3J-0-U-GPA"
					( Origin gPackager )
				)
				( attribute "CDS_LOCATION" "R25W93"
					( Origin gPackager )
				)
				( attribute "CDS_SEC" "1"
					( Origin gPackager )
				)
				( attribute "SEC" "1"
					( Origin gPackager )
				)
				( objectStatus "R25W93" )
				( pin "\1\"
					( attribute "PN" "1"
						( Origin gPackager )
					)
					( objectStatus "R25W93.1" )
				)
				( pin "\2\"
					( attribute "PN" "2"
						( Origin gPackager )
					)
					( objectStatus "R25W93.2" )
				)
			)
			( gate "@baseboard_fab2_lib.baseboard_fab2(sch_1):page150_i59"
				( attribute "BOM_COST" "SM_CONTROLLER"
					( Origin gFrontEnd )
				)
				( attribute "CDS_LIB" "mstr_discrete"
					( Origin gPackager )
				)
				( attribute "LOCATION" "C25W33"
					( Origin gFrontEnd )
				)
				( attribute "MATERIAL" "X6S"
					( Origin gFrontEnd )
				)
				( attribute "PACK_TYPE" "0402"
					( Origin gFrontEnd )
				)
				( attribute "PART_NUMBER" "D97712-004"
					( Origin gFrontEnd )
				)
				( attribute "PHYS_PAGE" "150"
					( Origin gFrontEnd )
				)
				( attribute "ROOM" "BMC"
					( Origin gFrontEnd )
				)
				( attribute "ROT" "0"
					( Origin gFrontEnd )
				)
				( attribute "TOLERANCE" "10%"
					( Origin gFrontEnd )
				)
				( attribute "VALUE" "1.0UF"
					( Origin gFrontEnd )
				)
				( attribute "VER" "1"
					( Origin gFrontEnd )
				)
				( attribute "VOLTAGE" "6.3V"
					( Units "uVoltage" "V" 1.000000)
					( Origin gFrontEnd )
				)
				( attribute "XY" "(-4900,3700)"
					( Origin gFrontEnd )
				)
				( attribute "CHIPS_PART_NAME" "CAP"
					( Origin gPackager )
				)
				( attribute "CDS_PART_NAME" "CAP_0402-1.0UF,6.3V,10%,X6S,D9A"
					( Origin gPackager )
				)
				( attribute "CDS_LOCATION" "C25W33"
					( Origin gPackager )
				)
				( attribute "CDS_SEC" "1"
					( Origin gPackager )
				)
				( attribute "SEC" "1"
					( Origin gPackager )
				)
				( objectStatus "C25W33" )
				( pin "a"
					( attribute "PN" "1"
						( Origin gPackager )
					)
					( objectStatus "C25W33.1" )
				)
				( pin "b"
					( attribute "PN" "2"
						( Origin gPackager )
					)
					( objectStatus "C25W33.2" )
				)
			)
			( gate "@baseboard_fab2_lib.baseboard_fab2(sch_1):page150_i61"
				( attribute "CDS_LIB" "w_hdl"
					( Origin gPackager )
				)
				( attribute "CDS_LMAN_SYM_OUTLINE" "-50,25,50,-25"
					( Origin gPackager )
				)
				( attribute "LOCATION" "C25W45"
					( Origin gFrontEnd )
				)
				( attribute "PACK_TYPE" "SMD-BCG"
					( Origin gFrontEnd )
				)
				( attribute "PART_NUMBER" "78.10421.2FL"
					( Origin gFrontEnd )
				)
				( attribute "PHYS_PAGE" "150"
					( Origin gFrontEnd )
				)
				( attribute "ROT" "0"
					( Origin gFrontEnd )
				)
				( attribute "VALUE" "SCD1U16V2KX-3GP"
					( Origin gFrontEnd )
				)
				( attribute "VER" "1"
					( Origin gFrontEnd )
				)
				( attribute "XY" "(-4325,2500)"
					( Origin gFrontEnd )
				)
				( attribute "CHIPS_PART_NAME" "SCD1U16V2KX-3GP"
					( Origin gPackager )
				)
				( attribute "CDS_PART_NAME" "SCD1U16V2KX-3GP_SMD-BCG-SCD1U1A"
					( Origin gPackager )
				)
				( attribute "CDS_LOCATION" "C25W45"
					( Origin gPackager )
				)
				( attribute "CDS_SEC" "1"
					( Origin gPackager )
				)
				( attribute "SEC" "1"
					( Origin gPackager )
				)
				( objectStatus "C25W45" )
				( pin "\1\"
					( attribute "PN" "1"
						( Origin gPackager )
					)
					( objectStatus "C25W45.1" )
				)
				( pin "\2\"
					( attribute "PN" "2"
						( Origin gPackager )
					)
					( objectStatus "C25W45.2" )
				)
			)
			( gate "@baseboard_fab2_lib.baseboard_fab2(sch_1):page146_i104"
				( attribute "CDS_LIB" "w_hdl"
					( Origin gPackager )
				)
				( attribute "CDS_LMAN_SYM_OUTLINE" "-1350,800,1350,-800"
					( Origin gPackager )
				)
				( attribute "LOCATION" "U25W4"
					( Origin gFrontEnd )
				)
				( attribute "PACK_TYPE" "ASIC2-GB1"
					( Origin gFrontEnd )
				)
				( attribute "PART_NUMBER" "071.2520A.M001"
					( Origin gFrontEnd )
				)
				( attribute "PHYS_PAGE" "146"
					( Origin gFrontEnd )
				)
				( attribute "ROT" "0"
					( Origin gFrontEnd )
				)
				( attribute "VALUE" "AST2520A1-GP-GP"
					( Origin gFrontEnd )
				)
				( attribute "VER" "4"
					( Origin gFrontEnd )
				)
				( attribute "XY" "(-3875,4000)"
					( Origin gFrontEnd )
				)
				( attribute "CHIPS_PART_NAME" "AST2520A1-GP-GP"
					( Origin gPackager )
				)
				( attribute "CDS_PART_NAME" "AST2520A1-GP-GP_ASIC2-GB1-AST2A"
					( Origin gPackager )
				)
				( attribute "CDS_LOCATION" "U25W4"
					( Origin gPackager )
				)
				( attribute "CDS_SEC" "4"
					( Origin gPackager )
				)
				( attribute "SEC" "4"
					( Origin gPackager )
				)
				( objectStatus "U25W4" )
				( pin "gpioaa0_vpor2_nord0_salt7"
					( attribute "PN" "Y21"
						( Origin gPackager )
					)
					( objectStatus "U25W4.Y21" )
				)
				( pin "gpioaa1_vpor3_nord1_salt8"
					( attribute "PN" "V21"
						( Origin gPackager )
					)
					( objectStatus "U25W4.V21" )
				)
				( pin "gpioaa2_vpor4_nord2_salt9"
					( attribute "PN" "Y22"
						( Origin gPackager )
					)
					( objectStatus "U25W4.Y22" )
				)
				( pin "gpioaa3_vpor5_nord3_salt10"
					( attribute "PN" "AA22"
						( Origin gPackager )
					)
					( objectStatus "U25W4.AA22" )
				)
				( pin "gpioaa4_vpor6_nord4_salt11"
					( attribute "PN" "U22"
						( Origin gPackager )
					)
					( objectStatus "U25W4.U22" )
				)
				( pin "gpioaa5_vpor7_nord5_salt12"
					( attribute "PN" "T20"
						( Origin gPackager )
					)
					( objectStatus "U25W4.T20" )
				)
				( pin "gpioaa6_vpor8_nord6_salt13"
					( attribute "PN" "N18"
						( Origin gPackager )
					)
					( objectStatus "U25W4.N18" )
				)
				( pin "gpioaa7_vpor9_nord7_salt14"
					( attribute "PN" "P19"
						( Origin gPackager )
					)
					( objectStatus "U25W4.P19" )
				)
				( pin "gpioh0_ncts6"
					( attribute "PN" "A18"
						( Origin gPackager )
					)
					( objectStatus "U25W4.A18" )
				)
				( pin "gpioh1_ndcd6"
					( attribute "PN" "B18"
						( Origin gPackager )
					)
					( objectStatus "U25W4.B18" )
				)
				( pin "gpioh2_ndsr6"
					( attribute "PN" "D17"
						( Origin gPackager )
					)
					( objectStatus "U25W4.D17" )
				)
				( pin "gpioh3_nri6"
					( attribute "PN" "C17"
						( Origin gPackager )
					)
					( objectStatus "U25W4.C17" )
				)
				( pin "gpioh4_ndtr6"
					( attribute "PN" "A17"
						( Origin gPackager )
					)
					( objectStatus "U25W4.A17" )
				)
				( pin "gpioh5_nrts6"
					( attribute "PN" "B17"
						( Origin gPackager )
					)
					( objectStatus "U25W4.B17" )
				)
				( pin "gpioh6_txd6"
					( attribute "PN" "A16"
						( Origin gPackager )
					)
					( objectStatus "U25W4.A16" )
				)
				( pin "gpioh7_rxd6"
					( attribute "PN" "D18"
						( Origin gPackager )
					)
					( objectStatus "U25W4.D18" )
				)
				( pin "\gpios0_vpob2_spi2cs1#\"
					( attribute "PN" "V20"
						( Origin gPackager )
					)
					( objectStatus "U25W4.V20" )
				)
				( pin "gpios1_vpob3_bmcint"
					( attribute "PN" "U19"
						( Origin gPackager )
					)
					( objectStatus "U25W4.U19" )
				)
				( pin "gpios2_vpob4_salt5"
					( attribute "PN" "R18"
						( Origin gPackager )
					)
					( objectStatus "U25W4.R18" )
				)
				( pin "gpios3_vpob5_salt6"
					( attribute "PN" "P18"
						( Origin gPackager )
					)
					( objectStatus "U25W4.P18" )
				)
				( pin "gpios4_vpob6"
					( attribute "PN" "R19"
						( Origin gPackager )
					)
					( objectStatus "U25W4.R19" )
				)
				( pin "gpios5_vpob7"
					( attribute "PN" "W20"
						( Origin gPackager )
					)
					( objectStatus "U25W4.W20" )
				)
				( pin "gpios6_vpob8"
					( attribute "PN" "U20"
						( Origin gPackager )
					)
					( objectStatus "U25W4.U20" )
				)
				( pin "gpios7_vpob9"
					( attribute "PN" "AA20"
						( Origin gPackager )
					)
					( objectStatus "U25W4.AA20" )
				)
				( pin "\gpioz0_vpog2_nora0_siopbi#\"
					( attribute "PN" "Y20"
						( Origin gPackager )
					)
					( objectStatus "U25W4.Y20" )
				)
				( pin "gpioz1_vpog3_nora1_siopwrgd"
					( attribute "PN" "AB20"
						( Origin gPackager )
					)
					( objectStatus "U25W4.AB20" )
				)
				( pin "\gpioz2_vpog4_nora2_siopbo#\"
					( attribute "PN" "AB21"
						( Origin gPackager )
					)
					( objectStatus "U25W4.AB21" )
				)
				( pin "\gpioz3_vpog5_nora3_siosci#\"
					( attribute "PN" "AA21"
						( Origin gPackager )
					)
					( objectStatus "U25W4.AA21" )
				)
				( pin "gpioz4_vpog6_nora4"
					( attribute "PN" "U21"
						( Origin gPackager )
					)
					( objectStatus "U25W4.U21" )
				)
				( pin "gpioz5_vpog7_nora5"
					( attribute "PN" "W22"
						( Origin gPackager )
					)
					( objectStatus "U25W4.W22" )
				)
				( pin "gpioz6_vpog8_nora6"
					( attribute "PN" "V22"
						( Origin gPackager )
					)
					( objectStatus "U25W4.V22" )
				)
				( pin "gpioz7_vpog9_nora7"
					( attribute "PN" "W21"
						( Origin gPackager )
					)
					( objectStatus "U25W4.W21" )
				)
				( pin "usb2a_dn"
					( attribute "PN" "A8"
						( Origin gPackager )
					)
					( objectStatus "U25W4.A8" )
				)
				( pin "usb2a_dp"
					( attribute "PN" "A7"
						( Origin gPackager )
					)
					( objectStatus "U25W4.A7" )
				)
				( pin "usb2avres"
					( attribute "PN" "B8"
						( Origin gPackager )
					)
					( objectStatus "U25W4.B8" )
				)
				( pin "usb2b_dn"
					( attribute "PN" "A6"
						( Origin gPackager )
					)
					( objectStatus "U25W4.A6" )
				)
				( pin "usb2b_dp"
					( attribute "PN" "B6"
						( Origin gPackager )
					)
					( objectStatus "U25W4.B6" )
				)
				( pin "usb2bvres"
					( attribute "PN" "B7"
						( Origin gPackager )
					)
					( objectStatus "U25W4.B7" )
				)
			)
			( gate "@baseboard_fab2_lib.baseboard_fab2(sch_1):page150_i62"
				( attribute "BOM_COST" "SM_CONTROLLER"
					( Origin gFrontEnd )
				)
				( attribute "CDS_LIB" "mstr_discrete"
					( Origin gPackager )
				)
				( attribute "LOCATION" "C25W44"
					( Origin gFrontEnd )
				)
				( attribute "MATERIAL" "X6S"
					( Origin gFrontEnd )
				)
				( attribute "PACK_TYPE" "0402"
					( Origin gFrontEnd )
				)
				( attribute "PART_NUMBER" "D97712-004"
					( Origin gFrontEnd )
				)
				( attribute "PHYS_PAGE" "150"
					( Origin gFrontEnd )
				)
				( attribute "ROOM" "BMC"
					( Origin gFrontEnd )
				)
				( attribute "ROT" "0"
					( Origin gFrontEnd )
				)
				( attribute "TOLERANCE" "10%"
					( Origin gFrontEnd )
				)
				( attribute "VALUE" "1.0UF"
					( Origin gFrontEnd )
				)
				( attribute "VER" "1"
					( Origin gFrontEnd )
				)
				( attribute "VOLTAGE" "6.3V"
					( Units "uVoltage" "V" 1.000000)
					( Origin gFrontEnd )
				)
				( attribute "XY" "(-4575,2475)"
					( Origin gFrontEnd )
				)
				( attribute "CHIPS_PART_NAME" "CAP"
					( Origin gPackager )
				)
				( attribute "CDS_PART_NAME" "CAP_0402-1.0UF,6.3V,10%,X6S,D9A"
					( Origin gPackager )
				)
				( attribute "CDS_LOCATION" "C25W44"
					( Origin gPackager )
				)
				( attribute "CDS_SEC" "1"
					( Origin gPackager )
				)
				( attribute "SEC" "1"
					( Origin gPackager )
				)
				( objectStatus "C25W44" )
				( pin "a"
					( attribute "PN" "1"
						( Origin gPackager )
					)
					( objectStatus "C25W44.1" )
				)
				( pin "b"
					( attribute "PN" "2"
						( Origin gPackager )
					)
					( objectStatus "C25W44.2" )
				)
			)
			( gate "@baseboard_fab2_lib.baseboard_fab2(sch_1):page150_i63"
				( attribute "BOM_COST" "SM_CONTROLLER"
					( Origin gFrontEnd )
				)
				( attribute "CDS_LIB" "mstr_discrete"
					( Origin gPackager )
				)
				( attribute "LOCATION" "C25W43"
					( Origin gFrontEnd )
				)
				( attribute "MATERIAL" "X6S"
					( Origin gFrontEnd )
				)
				( attribute "PACK_TYPE" "0402"
					( Origin gFrontEnd )
				)
				( attribute "PART_NUMBER" "D97712-004"
					( Origin gFrontEnd )
				)
				( attribute "PHYS_PAGE" "150"
					( Origin gFrontEnd )
				)
				( attribute "ROOM" "BMC"
					( Origin gFrontEnd )
				)
				( attribute "ROT" "0"
					( Origin gFrontEnd )
				)
				( attribute "TOLERANCE" "10%"
					( Origin gFrontEnd )
				)
				( attribute "VALUE" "1.0UF"
					( Origin gFrontEnd )
				)
				( attribute "VER" "1"
					( Origin gFrontEnd )
				)
				( attribute "VOLTAGE" "6.3V"
					( Units "uVoltage" "V" 1.000000)
					( Origin gFrontEnd )
				)
				( attribute "XY" "(-4875,2475)"
					( Origin gFrontEnd )
				)
				( attribute "CHIPS_PART_NAME" "CAP"
					( Origin gPackager )
				)
				( attribute "CDS_PART_NAME" "CAP_0402-1.0UF,6.3V,10%,X6S,D9A"
					( Origin gPackager )
				)
				( attribute "CDS_LOCATION" "C25W43"
					( Origin gPackager )
				)
				( attribute "CDS_SEC" "1"
					( Origin gPackager )
				)
				( attribute "SEC" "1"
					( Origin gPackager )
				)
				( objectStatus "C25W43" )
				( pin "a"
					( attribute "PN" "1"
						( Origin gPackager )
					)
					( objectStatus "C25W43.1" )
				)
				( pin "b"
					( attribute "PN" "2"
						( Origin gPackager )
					)
					( objectStatus "C25W43.2" )
				)
			)
			( gate "@baseboard_fab2_lib.baseboard_fab2(sch_1):page150_i65"
				( attribute "CDS_LIB" "w_hdl"
					( Origin gPackager )
				)
				( attribute "CDS_LMAN_SYM_OUTLINE" "-50,25,50,-25"
					( Origin gPackager )
				)
				( attribute "LOCATION" "C25W62"
					( Origin gFrontEnd )
				)
				( attribute "PACK_TYPE" "SMD-BCG"
					( Origin gFrontEnd )
				)
				( attribute "PART_NUMBER" "78.47523.5BL"
					( Origin gFrontEnd )
				)
				( attribute "PHYS_PAGE" "150"
					( Origin gFrontEnd )
				)
				( attribute "ROT" "0"
					( Origin gFrontEnd )
				)
				( attribute "VALUE" "SC4D7U10V3KX-GP"
					( Origin gFrontEnd )
				)
				( attribute "VER" "1"
					( Origin gFrontEnd )
				)
				( attribute "XY" "(-1800,1325)"
					( Origin gFrontEnd )
				)
				( attribute "CHIPS_PART_NAME" "SC4D7U10V3KX-GP"
					( Origin gPackager )
				)
				( attribute "CDS_PART_NAME" "SC4D7U10V3KX-GP_SMD-BCG-SC4D7UA"
					( Origin gPackager )
				)
				( attribute "CDS_LOCATION" "C25W62"
					( Origin gPackager )
				)
				( attribute "CDS_SEC" "1"
					( Origin gPackager )
				)
				( attribute "SEC" "1"
					( Origin gPackager )
				)
				( objectStatus "C25W62" )
				( pin "\1\"
					( attribute "PN" "1"
						( Origin gPackager )
					)
					( objectStatus "C25W62.1" )
				)
				( pin "\2\"
					( attribute "PN" "2"
						( Origin gPackager )
					)
					( objectStatus "C25W62.2" )
				)
			)
			( gate "@baseboard_fab2_lib.baseboard_fab2(sch_1):page200_i235"
				( attribute "CDS_LIB" "w_hdl"
					( Origin gPackager )
				)
				( attribute "CDS_LMAN_SYM_OUTLINE" "-50,25,50,-25"
					( Origin gPackager )
				)
				( attribute "PACK_TYPE" "SMD-BCG"
					( Origin gFrontEnd )
				)
				( attribute "PART_NUMBER" "78.22034.1FL"
					( Origin gFrontEnd )
				)
				( attribute "PHYS_PAGE" "200"
					( Origin gFrontEnd )
				)
				( attribute "ROT" "0"
					( Origin gFrontEnd )
				)
				( attribute "VALUE" "SC22P50V2JN-4GP"
					( Origin gFrontEnd )
				)
				( attribute "VER" "1"
					( Origin gFrontEnd )
				)
				( attribute "XY" "(-700,-100)"
					( Origin gFrontEnd )
				)
				( attribute "CHIPS_PART_NAME" "SC22P50V2JN-4GP"
					( Origin gPackager )
				)
				( attribute "CDS_PART_NAME" "SC22P50V2JN-4GP_SMD-BCG-SC22P5A"
					( Origin gPackager )
				)
				( attribute "LOCATION" "C9W1"
					( Origin gFrontEnd )
				)
				( attribute "CDS_LOCATION" "C9W1"
					( Origin gPackager )
				)
				( attribute "CDS_SEC" "1"
					( Origin gPackager )
				)
				( attribute "SEC" "1"
					( Origin gPackager )
				)
				( attribute "STATUS" "NOPOP"
					( Origin gFrontEnd )
				)
				( objectStatus "C9W1" )
				( pin "\1\"
					( attribute "PN" "1"
						( Origin gPackager )
					)
					( objectStatus "C9W1.1" )
				)
				( pin "\2\"
					( attribute "PN" "2"
						( Origin gPackager )
					)
					( objectStatus "C9W1.2" )
				)
			)
			( gate "@baseboard_fab2_lib.baseboard_fab2(sch_1):page200_i236"
				( attribute "CDS_LIB" "w_hdl"
					( Origin gPackager )
				)
				( attribute "CDS_LMAN_SYM_OUTLINE" "-50,25,50,-25"
					( Origin gPackager )
				)
				( attribute "PACK_TYPE" "SMD-BCG"
					( Origin gFrontEnd )
				)
				( attribute "PART_NUMBER" "78.22034.1FL"
					( Origin gFrontEnd )
				)
				( attribute "PHYS_PAGE" "200"
					( Origin gFrontEnd )
				)
				( attribute "ROT" "0"
					( Origin gFrontEnd )
				)
				( attribute "VALUE" "SC22P50V2JN-4GP"
					( Origin gFrontEnd )
				)
				( attribute "VER" "1"
					( Origin gFrontEnd )
				)
				( attribute "XY" "(-1050,175)"
					( Origin gFrontEnd )
				)
				( attribute "CHIPS_PART_NAME" "SC22P50V2JN-4GP"
					( Origin gPackager )
				)
				( attribute "CDS_PART_NAME" "SC22P50V2JN-4GP_SMD-BCG-SC22P5A"
					( Origin gPackager )
				)
				( attribute "LOCATION" "C9W2"
					( Origin gFrontEnd )
				)
				( attribute "CDS_LOCATION" "C9W2"
					( Origin gPackager )
				)
				( attribute "CDS_SEC" "1"
					( Origin gPackager )
				)
				( attribute "SEC" "1"
					( Origin gPackager )
				)
				( attribute "STATUS" "NOPOP"
					( Origin gFrontEnd )
				)
				( objectStatus "C9W2" )
				( pin "\1\"
					( attribute "PN" "1"
						( Origin gPackager )
					)
					( objectStatus "C9W2.1" )
				)
				( pin "\2\"
					( attribute "PN" "2"
						( Origin gPackager )
					)
					( objectStatus "C9W2.2" )
				)
			)
			( gate "@baseboard_fab2_lib.baseboard_fab2(sch_1):page175_i89"
				( attribute "CDS_LIB" "w_hdl"
					( Origin gPackager )
				)
				( attribute "CDS_LMAN_SYM_OUTLINE" "-50,75,50,-75"
					( Origin gPackager )
				)
				( attribute "LOCATION" "R1L45"
					( Origin gFrontEnd )
				)
				( attribute "PACK_TYPE" "SMD-RG5"
					( Origin gFrontEnd )
				)
				( attribute "PART_NUMBER" "63.R0034.L0L"
					( Origin gFrontEnd )
				)
				( attribute "PHYS_PAGE" "175"
					( Origin gFrontEnd )
				)
				( attribute "ROT" "1"
					( Origin gFrontEnd )
				)
				( attribute "VALUE" "0R2J-L-GP"
					( Origin gFrontEnd )
				)
				( attribute "VER" "1"
					( Origin gFrontEnd )
				)
				( attribute "XY" "(-5550,1550)"
					( Origin gFrontEnd )
				)
				( attribute "CHIPS_PART_NAME" "0R2J-L-GP"
					( Origin gPackager )
				)
				( attribute "CDS_PART_NAME" "0R2J-L-GP_SMD-RG5-0R2J-L-GP,63A"
					( Origin gPackager )
				)
				( attribute "CDS_LOCATION" "R1L45"
					( Origin gPackager )
				)
				( attribute "CDS_SEC" "1"
					( Origin gPackager )
				)
				( attribute "SEC" "1"
					( Origin gPackager )
				)
				( objectStatus "R1L45" )
				( pin "\1\"
					( attribute "PN" "1"
						( Origin gPackager )
					)
					( objectStatus "R1L45.1" )
				)
				( pin "\2\"
					( attribute "PN" "2"
						( Origin gPackager )
					)
					( objectStatus "R1L45.2" )
				)
			)
			( gate "@baseboard_fab2_lib.baseboard_fab2(sch_1):page181_i278"
				( attribute "CDS_LIB" "mstr_discrete"
					( Origin gPackager )
				)
				( attribute "LOCATION" "R9T8"
					( Origin gFrontEnd )
				)
				( attribute "MATERIAL" "CHIP"
					( Origin gFrontEnd )
				)
				( attribute "PACK_TYPE" "0402"
					( Origin gFrontEnd )
				)
				( attribute "PART_NUMBER" "G21497-005"
					( Origin gFrontEnd )
				)
				( attribute "PHYS_PAGE" "181"
					( Origin gFrontEnd )
				)
				( attribute "ROT" "1"
					( Origin gFrontEnd )
				)
				( attribute "TOLERANCE" "5%"
					( Origin gFrontEnd )
				)
				( attribute "VALUE" "0.0"
					( Origin gFrontEnd )
				)
				( attribute "VER" "1"
					( Origin gFrontEnd )
				)
				( attribute "WATTAGE" "1/16W"
					( Origin gFrontEnd )
				)
				( attribute "XY" "(-3000,1475)"
					( Origin gFrontEnd )
				)
				( attribute "CHIPS_PART_NAME" "RES"
					( Origin gPackager )
				)
				( attribute "CDS_PART_NAME" "RES_0402-0.0,5%,1/16W,CHIP,G21A"
					( Origin gPackager )
				)
				( attribute "CDS_LOCATION" "R9T8"
					( Origin gPackager )
				)
				( attribute "CDS_SEC" "1"
					( Origin gPackager )
				)
				( attribute "SEC" "1"
					( Origin gPackager )
				)
				( objectStatus "R9T8" )
				( pin "a"
					( attribute "PN" "1"
						( Origin gPackager )
					)
					( objectStatus "R9T8.1" )
				)
				( pin "b"
					( attribute "PN" "2"
						( Origin gPackager )
					)
					( objectStatus "R9T8.2" )
				)
			)
			( gate "@baseboard_fab2_lib.baseboard_fab2(sch_1):page146_i67"
				( attribute "BOM_COST" "SM_CONTROLLER"
					( Origin gFrontEnd )
				)
				( attribute "CDS_LIB" "mstr_discrete"
					( Origin gPackager )
				)
				( attribute "CDS_LOCATION" "R25W81"
					( Origin gPackager )
				)
				( attribute "LOCATION" "R25W81"
					( Origin gFrontEnd )
				)
				( attribute "MATERIAL" "CHIP"
					( Origin gFrontEnd )
				)
				( attribute "PACK_TYPE" "0402"
					( Origin gFrontEnd )
				)
				( attribute "PART_NUMBER" "G21796-074"
					( Origin gFrontEnd )
				)
				( attribute "PHYS_PAGE" "146"
					( Origin gFrontEnd )
				)
				( attribute "ROOM" "BMC"
					( Origin gFrontEnd )
				)
				( attribute "ROT" "0"
					( Origin gFrontEnd )
				)
				( attribute "SEC" "1"
					( Origin gFrontEnd )
				)
				( attribute "SEC_TYPE" "0402"
					( Origin gFrontEnd )
				)
				( attribute "TOLERANCE" "1%"
					( Origin gFrontEnd )
				)
				( attribute "VALUE" "33.2"
					( Origin gFrontEnd )
				)
				( attribute "VER" "1"
					( Origin gFrontEnd )
				)
				( attribute "WATTAGE" "1/16W"
					( Origin gFrontEnd )
				)
				( attribute "XY" "(-6225,2350)"
					( Origin gFrontEnd )
				)
				( attribute "CHIPS_PART_NAME" "RES"
					( Origin gPackager )
				)
				( attribute "CDS_PART_NAME" "RES_0402-33.2,1%,1/16W,CHIP,G2A"
					( Origin gPackager )
				)
				( attribute "CDS_SEC" "1"
					( Origin gPackager )
				)
				( objectStatus "R25W81" )
				( pin "a"
					( attribute "PN" "1"
						( Origin gPackager )
					)
					( objectStatus "R25W81.1" )
				)
				( pin "b"
					( attribute "PN" "2"
						( Origin gPackager )
					)
					( objectStatus "R25W81.2" )
				)
			)
			( gate "@baseboard_fab2_lib.baseboard_fab2(sch_1):page151_i13"
				( attribute "BOM_COST" "SM_CONTROLLER"
					( Origin gFrontEnd )
				)
				( attribute "CDS_LIB" "mstr_discrete"
					( Origin gPackager )
				)
				( attribute "LOCATION" "R25W100"
					( Origin gFrontEnd )
				)
				( attribute "MATERIAL" "CHIP"
					( Origin gFrontEnd )
				)
				( attribute "PACK_TYPE" "0402"
					( Origin gFrontEnd )
				)
				( attribute "PART_NUMBER" "G21796-072"
					( Origin gFrontEnd )
				)
				( attribute "PHYS_PAGE" "151"
					( Origin gFrontEnd )
				)
				( attribute "ROOM" "BMC"
					( Origin gFrontEnd )
				)
				( attribute "ROT" "0"
					( Origin gFrontEnd )
				)
				( attribute "TOLERANCE" "1%"
					( Origin gFrontEnd )
				)
				( attribute "VALUE" "4.75K"
					( Origin gFrontEnd )
				)
				( attribute "VER" "1"
					( Origin gFrontEnd )
				)
				( attribute "WATTAGE" "1/16W"
					( Origin gFrontEnd )
				)
				( attribute "XY" "(-6900,3625)"
					( Origin gFrontEnd )
				)
				( attribute "CHIPS_PART_NAME" "RES"
					( Origin gPackager )
				)
				( attribute "CDS_PART_NAME" "RES_0402-4.75K,1%,1/16W,CHIP,GA"
					( Origin gPackager )
				)
				( attribute "CDS_LOCATION" "R25W100"
					( Origin gPackager )
				)
				( attribute "CDS_SEC" "1"
					( Origin gPackager )
				)
				( attribute "SEC" "1"
					( Origin gPackager )
				)
				( objectStatus "R25W100" )
				( pin "a"
					( attribute "PN" "1"
						( Origin gPackager )
					)
					( objectStatus "R25W100.1" )
				)
				( pin "b"
					( attribute "PN" "2"
						( Origin gPackager )
					)
					( objectStatus "R25W100.2" )
				)
			)
			( gate "@baseboard_fab2_lib.baseboard_fab2(sch_1):page151_i12"
				( attribute "BOM_COST" "SM_CONTROLLER"
					( Origin gFrontEnd )
				)
				( attribute "CDS_LIB" "mstr_discrete"
					( Origin gPackager )
				)
				( attribute "LOCATION" "R25W98"
					( Origin gFrontEnd )
				)
				( attribute "MATERIAL" "CHIP"
					( Origin gFrontEnd )
				)
				( attribute "PACK_TYPE" "0402"
					( Origin gFrontEnd )
				)
				( attribute "PART_NUMBER" "G21796-072"
					( Origin gFrontEnd )
				)
				( attribute "PHYS_PAGE" "151"
					( Origin gFrontEnd )
				)
				( attribute "ROOM" "BMC"
					( Origin gFrontEnd )
				)
				( attribute "ROT" "0"
					( Origin gFrontEnd )
				)
				( attribute "TOLERANCE" "1%"
					( Origin gFrontEnd )
				)
				( attribute "VALUE" "4.75K"
					( Origin gFrontEnd )
				)
				( attribute "VER" "1"
					( Origin gFrontEnd )
				)
				( attribute "WATTAGE" "1/16W"
					( Origin gFrontEnd )
				)
				( attribute "XY" "(-6900,4000)"
					( Origin gFrontEnd )
				)
				( attribute "CHIPS_PART_NAME" "RES"
					( Origin gPackager )
				)
				( attribute "CDS_PART_NAME" "RES_0402-4.75K,1%,1/16W,CHIP,GA"
					( Origin gPackager )
				)
				( attribute "CDS_LOCATION" "R25W98"
					( Origin gPackager )
				)
				( attribute "CDS_SEC" "1"
					( Origin gPackager )
				)
				( attribute "SEC" "1"
					( Origin gPackager )
				)
				( objectStatus "R25W98" )
				( pin "a"
					( attribute "PN" "1"
						( Origin gPackager )
					)
					( objectStatus "R25W98.1" )
				)
				( pin "b"
					( attribute "PN" "2"
						( Origin gPackager )
					)
					( objectStatus "R25W98.2" )
				)
			)
			( gate "@baseboard_fab2_lib.baseboard_fab2(sch_1):page151_i11"
				( attribute "BOM_COST" "SM_CONTROLLER"
					( Origin gFrontEnd )
				)
				( attribute "CDS_LIB" "mstr_discrete"
					( Origin gPackager )
				)
				( attribute "CDS_LOCATION" "R25W97"
					( Origin gPackager )
				)
				( attribute "CDS_SEC" "1"
					( Origin gPackager )
				)
				( attribute "LOCATION" "R25W97"
					( Origin gFrontEnd )
				)
				( attribute "MATERIAL" "EMPTY"
					( Origin gFrontEnd )
				)
				( attribute "PACK_TYPE" "0402"
					( Origin gFrontEnd )
				)
				( attribute "PART_NUMBER" "G21796-072"
					( Origin gFrontEnd )
				)
				( attribute "PHYS_PAGE" "151"
					( Origin gFrontEnd )
				)
				( attribute "ROOM" "BMC"
					( Origin gFrontEnd )
				)
				( attribute "ROT" "0"
					( Origin gFrontEnd )
				)
				( attribute "SEC" "1"
					( Origin gPackager )
				)
				( attribute "TOLERANCE" "1%"
					( Origin gFrontEnd )
				)
				( attribute "VALUE" "4.75K"
					( Origin gFrontEnd )
				)
				( attribute "VER" "1"
					( Origin gFrontEnd )
				)
				( attribute "WATTAGE" "1/16W"
					( Origin gFrontEnd )
				)
				( attribute "XY" "(-6900,4275)"
					( Origin gFrontEnd )
				)
				( attribute "CHIPS_PART_NAME" "RES"
					( Origin gPackager )
				)
				( attribute "CDS_PART_NAME" "RES_0402-4.75K,1%,1/16W,EMPTY,A"
					( Origin gPackager )
				)
				( objectStatus "R25W97" )
				( pin "a"
					( attribute "PN" "1"
						( Origin gPackager )
					)
					( objectStatus "R25W97.1" )
				)
				( pin "b"
					( attribute "PN" "2"
						( Origin gPackager )
					)
					( objectStatus "R25W97.2" )
				)
			)
			( gate "@baseboard_fab2_lib.baseboard_fab2(sch_1):page151_i2"
				( attribute "BOM_COST" "SM_CONTROLLER"
					( Origin gFrontEnd )
				)
				( attribute "CDS_LIB" "mstr_discrete"
					( Origin gPackager )
				)
				( attribute "LOCATION" "R25W95"
					( Origin gFrontEnd )
				)
				( attribute "MATERIAL" "CHIP"
					( Origin gFrontEnd )
				)
				( attribute "PACK_TYPE" "0402"
					( Origin gFrontEnd )
				)
				( attribute "PART_NUMBER" "G21796-072"
					( Origin gFrontEnd )
				)
				( attribute "PHYS_PAGE" "151"
					( Origin gFrontEnd )
				)
				( attribute "ROOM" "BMC"
					( Origin gFrontEnd )
				)
				( attribute "ROT" "0"
					( Origin gFrontEnd )
				)
				( attribute "TOLERANCE" "1%"
					( Origin gFrontEnd )
				)
				( attribute "VALUE" "4.75K"
					( Origin gFrontEnd )
				)
				( attribute "VER" "1"
					( Origin gFrontEnd )
				)
				( attribute "WATTAGE" "1/16W"
					( Origin gFrontEnd )
				)
				( attribute "XY" "(-6900,4550)"
					( Origin gFrontEnd )
				)
				( attribute "CHIPS_PART_NAME" "RES"
					( Origin gPackager )
				)
				( attribute "CDS_PART_NAME" "RES_0402-4.75K,1%,1/16W,CHIP,GA"
					( Origin gPackager )
				)
				( attribute "CDS_LOCATION" "R25W95"
					( Origin gPackager )
				)
				( attribute "CDS_SEC" "1"
					( Origin gPackager )
				)
				( attribute "SEC" "1"
					( Origin gPackager )
				)
				( objectStatus "R25W95" )
				( pin "a"
					( attribute "PN" "1"
						( Origin gPackager )
					)
					( objectStatus "R25W95.1" )
				)
				( pin "b"
					( attribute "PN" "2"
						( Origin gPackager )
					)
					( objectStatus "R25W95.2" )
				)
			)
			( gate "@baseboard_fab2_lib.baseboard_fab2(sch_1):page202_i88"
				( attribute "BOM_COST" "DEBUG"
					( Origin gFrontEnd )
				)
				( attribute "CDS_LIB" "mstr_discrete"
					( Origin gPackager )
				)
				( attribute "LOCATION" "RT1"
					( Origin gFrontEnd )
				)
				( attribute "MATERIAL" "CHIP"
					( Origin gFrontEnd )
				)
				( attribute "PACK_TYPE" "0402"
					( Origin gFrontEnd )
				)
				( attribute "PART_NUMBER" "G21497-005"
					( Origin gFrontEnd )
				)
				( attribute "PHYS_PAGE" "202"
					( Origin gFrontEnd )
				)
				( attribute "ROOM" "BMC_DEBUG_HEADER"
					( Origin gFrontEnd )
				)
				( attribute "ROT" "0"
					( Origin gFrontEnd )
				)
				( attribute "TOLERANCE" "5%"
					( Origin gFrontEnd )
				)
				( attribute "VALUE" "0.0"
					( Origin gFrontEnd )
				)
				( attribute "VER" "1"
					( Origin gFrontEnd )
				)
				( attribute "WATTAGE" "1/16W"
					( Origin gFrontEnd )
				)
				( attribute "XY" "(-4925,3575)"
					( Origin gFrontEnd )
				)
				( attribute "CHIPS_PART_NAME" "RES"
					( Origin gPackager )
				)
				( attribute "CDS_PART_NAME" "RES_0402-0.0,5%,1/16W,CHIP,G21A"
					( Origin gPackager )
				)
				( attribute "CDS_LOCATION" "RT1"
					( Origin gPackager )
				)
				( attribute "CDS_SEC" "1"
					( Origin gPackager )
				)
				( attribute "SEC" "1"
					( Origin gPackager )
				)
				( objectStatus "RT1" )
				( pin "a"
					( attribute "PN" "1"
						( Origin gPackager )
					)
					( objectStatus "RT1.1" )
				)
				( pin "b"
					( attribute "PN" "2"
						( Origin gPackager )
					)
					( objectStatus "RT1.2" )
				)
			)
			( gate "@baseboard_fab2_lib.baseboard_fab2(sch_1):page227_i126"
				( attribute "BOM_COST" "DEBUG"
					( Origin gFrontEnd )
				)
				( attribute "CDS_LIB" "mstr_discrete"
					( Origin gPackager )
				)
				( attribute "LOCATION" "RT5"
					( Origin gFrontEnd )
				)
				( attribute "MATERIAL" "CHIP"
					( Origin gFrontEnd )
				)
				( attribute "PACK_TYPE" "0402"
					( Origin gFrontEnd )
				)
				( attribute "PART_NUMBER" "G21497-005"
					( Origin gFrontEnd )
				)
				( attribute "PHYS_PAGE" "227"
					( Origin gFrontEnd )
				)
				( attribute "ROOM" "BMC_DEBUG_HEADER"
					( Origin gFrontEnd )
				)
				( attribute "ROT" "0"
					( Origin gFrontEnd )
				)
				( attribute "TOLERANCE" "5%"
					( Origin gFrontEnd )
				)
				( attribute "VALUE" "0.0"
					( Origin gFrontEnd )
				)
				( attribute "VER" "1"
					( Origin gFrontEnd )
				)
				( attribute "WATTAGE" "1/16W"
					( Origin gFrontEnd )
				)
				( attribute "XY" "(-75,1950)"
					( Origin gFrontEnd )
				)
				( attribute "CHIPS_PART_NAME" "RES"
					( Origin gPackager )
				)
				( attribute "CDS_PART_NAME" "RES_0402-0.0,5%,1/16W,CHIP,G21A"
					( Origin gPackager )
				)
				( attribute "CDS_LOCATION" "RT5"
					( Origin gPackager )
				)
				( attribute "CDS_SEC" "1"
					( Origin gPackager )
				)
				( attribute "SEC" "1"
					( Origin gPackager )
				)
				( objectStatus "RT5" )
				( pin "a"
					( attribute "PN" "1"
						( Origin gPackager )
					)
					( objectStatus "RT5.1" )
				)
				( pin "b"
					( attribute "PN" "2"
						( Origin gPackager )
					)
					( objectStatus "RT5.2" )
				)
			)
			( gate "@baseboard_fab2_lib.baseboard_fab2(sch_1):page227_i127"
				( attribute "BOM_COST" "DEBUG"
					( Origin gFrontEnd )
				)
				( attribute "CDS_LIB" "mstr_discrete"
					( Origin gPackager )
				)
				( attribute "LOCATION" "RT8"
					( Origin gFrontEnd )
				)
				( attribute "MATERIAL" "CHIP"
					( Origin gFrontEnd )
				)
				( attribute "PACK_TYPE" "0402"
					( Origin gFrontEnd )
				)
				( attribute "PART_NUMBER" "G21497-005"
					( Origin gFrontEnd )
				)
				( attribute "PHYS_PAGE" "227"
					( Origin gFrontEnd )
				)
				( attribute "ROOM" "BMC_DEBUG_HEADER"
					( Origin gFrontEnd )
				)
				( attribute "ROT" "0"
					( Origin gFrontEnd )
				)
				( attribute "TOLERANCE" "5%"
					( Origin gFrontEnd )
				)
				( attribute "VALUE" "0.0"
					( Origin gFrontEnd )
				)
				( attribute "VER" "1"
					( Origin gFrontEnd )
				)
				( attribute "WATTAGE" "1/16W"
					( Origin gFrontEnd )
				)
				( attribute "XY" "(-200,-225)"
					( Origin gFrontEnd )
				)
				( attribute "CHIPS_PART_NAME" "RES"
					( Origin gPackager )
				)
				( attribute "CDS_PART_NAME" "RES_0402-0.0,5%,1/16W,CHIP,G21A"
					( Origin gPackager )
				)
				( attribute "CDS_LOCATION" "RT8"
					( Origin gPackager )
				)
				( attribute "CDS_SEC" "1"
					( Origin gPackager )
				)
				( attribute "SEC" "1"
					( Origin gPackager )
				)
				( objectStatus "RT8" )
				( pin "a"
					( attribute "PN" "1"
						( Origin gPackager )
					)
					( objectStatus "RT8.1" )
				)
				( pin "b"
					( attribute "PN" "2"
						( Origin gPackager )
					)
					( objectStatus "RT8.2" )
				)
			)
			( gate "@baseboard_fab2_lib.baseboard_fab2(sch_1):page209_i69"
				( attribute "BOM_COST" "DEBUG"
					( Origin gFrontEnd )
				)
				( attribute "CDS_LIB" "mstr_discrete"
					( Origin gPackager )
				)
				( attribute "LOCATION" "RT9"
					( Origin gFrontEnd )
				)
				( attribute "MATERIAL" "CHIP"
					( Origin gFrontEnd )
				)
				( attribute "PACK_TYPE" "0402"
					( Origin gFrontEnd )
				)
				( attribute "PART_NUMBER" "G21497-005"
					( Origin gFrontEnd )
				)
				( attribute "PHYS_PAGE" "209"
					( Origin gFrontEnd )
				)
				( attribute "ROOM" "BMC_DEBUG_HEADER"
					( Origin gFrontEnd )
				)
				( attribute "ROT" "0"
					( Origin gFrontEnd )
				)
				( attribute "TOLERANCE" "5%"
					( Origin gFrontEnd )
				)
				( attribute "VALUE" "0.0"
					( Origin gFrontEnd )
				)
				( attribute "VER" "1"
					( Origin gFrontEnd )
				)
				( attribute "WATTAGE" "1/16W"
					( Origin gFrontEnd )
				)
				( attribute "XY" "(-4800,3575)"
					( Origin gFrontEnd )
				)
				( attribute "CHIPS_PART_NAME" "RES"
					( Origin gPackager )
				)
				( attribute "CDS_PART_NAME" "RES_0402-0.0,5%,1/16W,CHIP,G21A"
					( Origin gPackager )
				)
				( attribute "CDS_LOCATION" "RT9"
					( Origin gPackager )
				)
				( attribute "CDS_SEC" "1"
					( Origin gPackager )
				)
				( attribute "SEC" "1"
					( Origin gPackager )
				)
				( objectStatus "RT9" )
				( pin "a"
					( attribute "PN" "1"
						( Origin gPackager )
					)
					( objectStatus "RT9.1" )
				)
				( pin "b"
					( attribute "PN" "2"
						( Origin gPackager )
					)
					( objectStatus "RT9.2" )
				)
			)
			( gate "@baseboard_fab2_lib.baseboard_fab2(sch_1):page208_i97"
				( attribute "BOM_COST" "DEBUG"
					( Origin gFrontEnd )
				)
				( attribute "CDS_LIB" "mstr_discrete"
					( Origin gPackager )
				)
				( attribute "LOCATION" "RT14"
					( Origin gFrontEnd )
				)
				( attribute "MATERIAL" "CHIP"
					( Origin gFrontEnd )
				)
				( attribute "PACK_TYPE" "0402"
					( Origin gFrontEnd )
				)
				( attribute "PART_NUMBER" "G21497-005"
					( Origin gFrontEnd )
				)
				( attribute "PHYS_PAGE" "208"
					( Origin gFrontEnd )
				)
				( attribute "ROOM" "BMC_DEBUG_HEADER"
					( Origin gFrontEnd )
				)
				( attribute "ROT" "0"
					( Origin gFrontEnd )
				)
				( attribute "TOLERANCE" "5%"
					( Origin gFrontEnd )
				)
				( attribute "VALUE" "0.0"
					( Origin gFrontEnd )
				)
				( attribute "VER" "1"
					( Origin gFrontEnd )
				)
				( attribute "WATTAGE" "1/16W"
					( Origin gFrontEnd )
				)
				( attribute "XY" "(-4925,1075)"
					( Origin gFrontEnd )
				)
				( attribute "CHIPS_PART_NAME" "RES"
					( Origin gPackager )
				)
				( attribute "CDS_PART_NAME" "RES_0402-0.0,5%,1/16W,CHIP,G21A"
					( Origin gPackager )
				)
				( attribute "CDS_LOCATION" "RT14"
					( Origin gPackager )
				)
				( attribute "CDS_SEC" "1"
					( Origin gPackager )
				)
				( attribute "SEC" "1"
					( Origin gPackager )
				)
				( objectStatus "RT14" )
				( pin "a"
					( attribute "PN" "1"
						( Origin gPackager )
					)
					( objectStatus "RT14.1" )
				)
				( pin "b"
					( attribute "PN" "2"
						( Origin gPackager )
					)
					( objectStatus "RT14.2" )
				)
			)
			( gate "@baseboard_fab2_lib.baseboard_fab2(sch_1):page207_i87"
				( attribute "BOM_COST" "DEBUG"
					( Origin gFrontEnd )
				)
				( attribute "CDS_LIB" "mstr_discrete"
					( Origin gPackager )
				)
				( attribute "LOCATION" "RT15"
					( Origin gFrontEnd )
				)
				( attribute "MATERIAL" "CHIP"
					( Origin gFrontEnd )
				)
				( attribute "PACK_TYPE" "0402"
					( Origin gFrontEnd )
				)
				( attribute "PART_NUMBER" "G21497-005"
					( Origin gFrontEnd )
				)
				( attribute "PHYS_PAGE" "207"
					( Origin gFrontEnd )
				)
				( attribute "ROOM" "BMC_DEBUG_HEADER"
					( Origin gFrontEnd )
				)
				( attribute "ROT" "0"
					( Origin gFrontEnd )
				)
				( attribute "TOLERANCE" "5%"
					( Origin gFrontEnd )
				)
				( attribute "VALUE" "0.0"
					( Origin gFrontEnd )
				)
				( attribute "VER" "1"
					( Origin gFrontEnd )
				)
				( attribute "WATTAGE" "1/16W"
					( Origin gFrontEnd )
				)
				( attribute "XY" "(-5150,3650)"
					( Origin gFrontEnd )
				)
				( attribute "CHIPS_PART_NAME" "RES"
					( Origin gPackager )
				)
				( attribute "CDS_PART_NAME" "RES_0402-0.0,5%,1/16W,CHIP,G21A"
					( Origin gPackager )
				)
				( attribute "CDS_LOCATION" "RT15"
					( Origin gPackager )
				)
				( attribute "CDS_SEC" "1"
					( Origin gPackager )
				)
				( attribute "SEC" "1"
					( Origin gPackager )
				)
				( objectStatus "RT15" )
				( pin "a"
					( attribute "PN" "1"
						( Origin gPackager )
					)
					( objectStatus "RT15.1" )
				)
				( pin "b"
					( attribute "PN" "2"
						( Origin gPackager )
					)
					( objectStatus "RT15.2" )
				)
			)
			( gate "@baseboard_fab2_lib.baseboard_fab2(sch_1):page207_i88"
				( attribute "BOM_COST" "DEBUG"
					( Origin gFrontEnd )
				)
				( attribute "CDS_LIB" "mstr_discrete"
					( Origin gPackager )
				)
				( attribute "LOCATION" "RT17"
					( Origin gFrontEnd )
				)
				( attribute "MATERIAL" "CHIP"
					( Origin gFrontEnd )
				)
				( attribute "PACK_TYPE" "0402"
					( Origin gFrontEnd )
				)
				( attribute "PART_NUMBER" "G21497-005"
					( Origin gFrontEnd )
				)
				( attribute "PHYS_PAGE" "207"
					( Origin gFrontEnd )
				)
				( attribute "ROOM" "BMC_DEBUG_HEADER"
					( Origin gFrontEnd )
				)
				( attribute "ROT" "0"
					( Origin gFrontEnd )
				)
				( attribute "TOLERANCE" "5%"
					( Origin gFrontEnd )
				)
				( attribute "VALUE" "0.0"
					( Origin gFrontEnd )
				)
				( attribute "VER" "1"
					( Origin gFrontEnd )
				)
				( attribute "WATTAGE" "1/16W"
					( Origin gFrontEnd )
				)
				( attribute "XY" "(-5025,1000)"
					( Origin gFrontEnd )
				)
				( attribute "CHIPS_PART_NAME" "RES"
					( Origin gPackager )
				)
				( attribute "CDS_PART_NAME" "RES_0402-0.0,5%,1/16W,CHIP,G21A"
					( Origin gPackager )
				)
				( attribute "CDS_LOCATION" "RT17"
					( Origin gPackager )
				)
				( attribute "CDS_SEC" "1"
					( Origin gPackager )
				)
				( attribute "SEC" "1"
					( Origin gPackager )
				)
				( objectStatus "RT17" )
				( pin "a"
					( attribute "PN" "1"
						( Origin gPackager )
					)
					( objectStatus "RT17.1" )
				)
				( pin "b"
					( attribute "PN" "2"
						( Origin gPackager )
					)
					( objectStatus "RT17.2" )
				)
			)
			( gate "@baseboard_fab2_lib.baseboard_fab2(sch_1):page224_i132"
				( attribute "BOM_COST" "DEBUG"
					( Origin gFrontEnd )
				)
				( attribute "CDS_LIB" "mstr_discrete"
					( Origin gPackager )
				)
				( attribute "LOCATION" "RT19"
					( Origin gFrontEnd )
				)
				( attribute "MATERIAL" "CHIP"
					( Origin gFrontEnd )
				)
				( attribute "PACK_TYPE" "0402"
					( Origin gFrontEnd )
				)
				( attribute "PART_NUMBER" "G21497-005"
					( Origin gFrontEnd )
				)
				( attribute "PHYS_PAGE" "224"
					( Origin gFrontEnd )
				)
				( attribute "ROOM" "BMC_DEBUG_HEADER"
					( Origin gFrontEnd )
				)
				( attribute "ROT" "0"
					( Origin gFrontEnd )
				)
				( attribute "TOLERANCE" "5%"
					( Origin gFrontEnd )
				)
				( attribute "VALUE" "0.0"
					( Origin gFrontEnd )
				)
				( attribute "VER" "1"
					( Origin gFrontEnd )
				)
				( attribute "WATTAGE" "1/16W"
					( Origin gFrontEnd )
				)
				( attribute "XY" "(-275,2000)"
					( Origin gFrontEnd )
				)
				( attribute "CHIPS_PART_NAME" "RES"
					( Origin gPackager )
				)
				( attribute "CDS_PART_NAME" "RES_0402-0.0,5%,1/16W,CHIP,G21A"
					( Origin gPackager )
				)
				( attribute "CDS_LOCATION" "RT19"
					( Origin gPackager )
				)
				( attribute "CDS_SEC" "1"
					( Origin gPackager )
				)
				( attribute "SEC" "1"
					( Origin gPackager )
				)
				( objectStatus "RT19" )
				( pin "a"
					( attribute "PN" "1"
						( Origin gPackager )
					)
					( objectStatus "RT19.1" )
				)
				( pin "b"
					( attribute "PN" "2"
						( Origin gPackager )
					)
					( objectStatus "RT19.2" )
				)
			)
			( gate "@baseboard_fab2_lib.baseboard_fab2(sch_1):page224_i133"
				( attribute "BOM_COST" "DEBUG"
					( Origin gFrontEnd )
				)
				( attribute "CDS_LIB" "mstr_discrete"
					( Origin gPackager )
				)
				( attribute "LOCATION" "RT21"
					( Origin gFrontEnd )
				)
				( attribute "MATERIAL" "CHIP"
					( Origin gFrontEnd )
				)
				( attribute "PACK_TYPE" "0402"
					( Origin gFrontEnd )
				)
				( attribute "PART_NUMBER" "G21497-005"
					( Origin gFrontEnd )
				)
				( attribute "PHYS_PAGE" "224"
					( Origin gFrontEnd )
				)
				( attribute "ROOM" "BMC_DEBUG_HEADER"
					( Origin gFrontEnd )
				)
				( attribute "ROT" "0"
					( Origin gFrontEnd )
				)
				( attribute "TOLERANCE" "5%"
					( Origin gFrontEnd )
				)
				( attribute "VALUE" "0.0"
					( Origin gFrontEnd )
				)
				( attribute "VER" "1"
					( Origin gFrontEnd )
				)
				( attribute "WATTAGE" "1/16W"
					( Origin gFrontEnd )
				)
				( attribute "XY" "(50,-325)"
					( Origin gFrontEnd )
				)
				( attribute "CHIPS_PART_NAME" "RES"
					( Origin gPackager )
				)
				( attribute "CDS_PART_NAME" "RES_0402-0.0,5%,1/16W,CHIP,G21A"
					( Origin gPackager )
				)
				( attribute "CDS_LOCATION" "RT21"
					( Origin gPackager )
				)
				( attribute "CDS_SEC" "1"
					( Origin gPackager )
				)
				( attribute "SEC" "1"
					( Origin gPackager )
				)
				( objectStatus "RT21" )
				( pin "a"
					( attribute "PN" "1"
						( Origin gPackager )
					)
					( objectStatus "RT21.1" )
				)
				( pin "b"
					( attribute "PN" "2"
						( Origin gPackager )
					)
					( objectStatus "RT21.2" )
				)
			)
			( gate "@baseboard_fab2_lib.baseboard_fab2(sch_1):page204_i93"
				( attribute "BOM_COST" "DEBUG"
					( Origin gFrontEnd )
				)
				( attribute "CDS_LIB" "mstr_discrete"
					( Origin gPackager )
				)
				( attribute "LOCATION" "RT23"
					( Origin gFrontEnd )
				)
				( attribute "MATERIAL" "CHIP"
					( Origin gFrontEnd )
				)
				( attribute "PACK_TYPE" "0402"
					( Origin gFrontEnd )
				)
				( attribute "PART_NUMBER" "G21497-005"
					( Origin gFrontEnd )
				)
				( attribute "PHYS_PAGE" "204"
					( Origin gFrontEnd )
				)
				( attribute "ROOM" "BMC_DEBUG_HEADER"
					( Origin gFrontEnd )
				)
				( attribute "ROT" "0"
					( Origin gFrontEnd )
				)
				( attribute "TOLERANCE" "5%"
					( Origin gFrontEnd )
				)
				( attribute "VALUE" "0.0"
					( Origin gFrontEnd )
				)
				( attribute "VER" "1"
					( Origin gFrontEnd )
				)
				( attribute "WATTAGE" "1/16W"
					( Origin gFrontEnd )
				)
				( attribute "XY" "(-5275,3500)"
					( Origin gFrontEnd )
				)
				( attribute "CHIPS_PART_NAME" "RES"
					( Origin gPackager )
				)
				( attribute "CDS_PART_NAME" "RES_0402-0.0,5%,1/16W,CHIP,G21A"
					( Origin gPackager )
				)
				( attribute "CDS_LOCATION" "RT23"
					( Origin gPackager )
				)
				( attribute "CDS_SEC" "1"
					( Origin gPackager )
				)
				( attribute "SEC" "1"
					( Origin gPackager )
				)
				( objectStatus "RT23" )
				( pin "a"
					( attribute "PN" "1"
						( Origin gPackager )
					)
					( objectStatus "RT23.1" )
				)
				( pin "b"
					( attribute "PN" "2"
						( Origin gPackager )
					)
					( objectStatus "RT23.2" )
				)
			)
			( gate "@baseboard_fab2_lib.baseboard_fab2(sch_1):page203_i111"
				( attribute "BOM_COST" "DEBUG"
					( Origin gFrontEnd )
				)
				( attribute "CDS_LIB" "mstr_discrete"
					( Origin gPackager )
				)
				( attribute "LOCATION" "RT28"
					( Origin gFrontEnd )
				)
				( attribute "MATERIAL" "CHIP"
					( Origin gFrontEnd )
				)
				( attribute "PACK_TYPE" "0402"
					( Origin gFrontEnd )
				)
				( attribute "PART_NUMBER" "G21497-005"
					( Origin gFrontEnd )
				)
				( attribute "PHYS_PAGE" "203"
					( Origin gFrontEnd )
				)
				( attribute "ROOM" "BMC_DEBUG_HEADER"
					( Origin gFrontEnd )
				)
				( attribute "ROT" "0"
					( Origin gFrontEnd )
				)
				( attribute "TOLERANCE" "5%"
					( Origin gFrontEnd )
				)
				( attribute "VALUE" "0.0"
					( Origin gFrontEnd )
				)
				( attribute "VER" "1"
					( Origin gFrontEnd )
				)
				( attribute "WATTAGE" "1/16W"
					( Origin gFrontEnd )
				)
				( attribute "XY" "(-5175,950)"
					( Origin gFrontEnd )
				)
				( attribute "CHIPS_PART_NAME" "RES"
					( Origin gPackager )
				)
				( attribute "CDS_PART_NAME" "RES_0402-0.0,5%,1/16W,CHIP,G21A"
					( Origin gPackager )
				)
				( attribute "CDS_LOCATION" "RT28"
					( Origin gPackager )
				)
				( attribute "CDS_SEC" "1"
					( Origin gPackager )
				)
				( attribute "SEC" "1"
					( Origin gPackager )
				)
				( objectStatus "RT28" )
				( pin "a"
					( attribute "PN" "1"
						( Origin gPackager )
					)
					( objectStatus "RT28.1" )
				)
				( pin "b"
					( attribute "PN" "2"
						( Origin gPackager )
					)
					( objectStatus "RT28.2" )
				)
			)
			( gate "@baseboard_fab2_lib.baseboard_fab2(sch_1):page181_i281"
				( attribute "CDS_LIB" "mstr_discrete"
					( Origin gPackager )
				)
				( attribute "CDS_LOCATION" "R9F64"
					( Origin gPackager )
				)
				( attribute "CDS_SEC" "1"
					( Origin gPackager )
				)
				( attribute "LOCATION" "R9F64"
					( Origin gFrontEnd )
				)
				( attribute "MATERIAL" "CHIP"
					( Origin gFrontEnd )
				)
				( attribute "PACK_TYPE" "0402"
					( Origin gFrontEnd )
				)
				( attribute "PART_NUMBER" "G21497-005"
					( Origin gFrontEnd )
				)
				( attribute "PHYS_PAGE" "181"
					( Origin gFrontEnd )
				)
				( attribute "ROOM" "UART_MUX"
					( Origin gFrontEnd )
				)
				( attribute "ROT" "0"
					( Origin gFrontEnd )
				)
				( attribute "SEC" "1"
					( Origin gFrontEnd )
				)
				( attribute "SEC_TYPE" "0402"
					( Origin gFrontEnd )
				)
				( attribute "TOLERANCE" "5%"
					( Origin gFrontEnd )
				)
				( attribute "VALUE" "0.0"
					( Origin gFrontEnd )
				)
				( attribute "VER" "1"
					( Origin gFrontEnd )
				)
				( attribute "WATTAGE" "1/16W"
					( Origin gFrontEnd )
				)
				( attribute "XY" "(-2775,3800)"
					( Origin gFrontEnd )
				)
				( attribute "CHIPS_PART_NAME" "RES"
					( Origin gPackager )
				)
				( attribute "CDS_PART_NAME" "RES_0402-0.0,5%,1/16W,CHIP,G21A"
					( Origin gPackager )
				)
				( objectStatus "R9F64" )
				( pin "a"
					( attribute "PN" "1"
						( Origin gPackager )
					)
					( objectStatus "R9F64.1" )
				)
				( pin "b"
					( attribute "PN" "2"
						( Origin gPackager )
					)
					( objectStatus "R9F64.2" )
				)
			)
			( gate "@baseboard_fab2_lib.baseboard_fab2(sch_1):page181_i282"
				( attribute "CDS_LIB" "mstr_discrete"
					( Origin gPackager )
				)
				( attribute "CDS_LOCATION" "R9F63"
					( Origin gPackager )
				)
				( attribute "CDS_SEC" "1"
					( Origin gPackager )
				)
				( attribute "LOCATION" "R9F63"
					( Origin gFrontEnd )
				)
				( attribute "MATERIAL" "EMPTY"
					( Origin gFrontEnd )
				)
				( attribute "PACK_TYPE" "0402"
					( Origin gFrontEnd )
				)
				( attribute "PART_NUMBER" "G21497-005"
					( Origin gFrontEnd )
				)
				( attribute "PHYS_PAGE" "181"
					( Origin gFrontEnd )
				)
				( attribute "ROOM" "UART_MUX"
					( Origin gFrontEnd )
				)
				( attribute "ROT" "0"
					( Origin gFrontEnd )
				)
				( attribute "SEC" "1"
					( Origin gFrontEnd )
				)
				( attribute "SEC_TYPE" "0402"
					( Origin gFrontEnd )
				)
				( attribute "TOLERANCE" "5%"
					( Origin gFrontEnd )
				)
				( attribute "VALUE" "0.0"
					( Origin gFrontEnd )
				)
				( attribute "VER" "1"
					( Origin gFrontEnd )
				)
				( attribute "WATTAGE" "1/16W"
					( Origin gFrontEnd )
				)
				( attribute "XY" "(-2725,3350)"
					( Origin gFrontEnd )
				)
				( attribute "CHIPS_PART_NAME" "RES"
					( Origin gPackager )
				)
				( attribute "CDS_PART_NAME" "RES_0402-0.0,5%,1/16W,EMPTY,G2A"
					( Origin gPackager )
				)
				( objectStatus "R9F63" )
				( pin "a"
					( attribute "PN" "1"
						( Origin gPackager )
					)
					( objectStatus "R9F63.1" )
				)
				( pin "b"
					( attribute "PN" "2"
						( Origin gPackager )
					)
					( objectStatus "R9F63.2" )
				)
			)
			( gate "@baseboard_fab2_lib.baseboard_fab2(sch_1):page158_i152"
				( attribute "BOM_COST" "DEBUG"
					( Origin gFrontEnd )
				)
				( attribute "CDS_LIB" "mstr_discrete"
					( Origin gPackager )
				)
				( attribute "LOCATION" "R9F66"
					( Origin gFrontEnd )
				)
				( attribute "MATERIAL" "EMPTY"
					( Origin gFrontEnd )
				)
				( attribute "PACK_TYPE" "0402"
					( Origin gFrontEnd )
				)
				( attribute "PART_NUMBER" "G21497-005"
					( Origin gFrontEnd )
				)
				( attribute "PHYS_PAGE" "158"
					( Origin gFrontEnd )
				)
				( attribute "ROOM" "UART_MUX"
					( Origin gFrontEnd )
				)
				( attribute "ROT" "0"
					( Origin gFrontEnd )
				)
				( attribute "TOLERANCE" "5%"
					( Origin gFrontEnd )
				)
				( attribute "VALUE" "0.0"
					( Origin gFrontEnd )
				)
				( attribute "VER" "1"
					( Origin gFrontEnd )
				)
				( attribute "WATTAGE" "1/16W"
					( Origin gFrontEnd )
				)
				( attribute "XY" "(-3150,2575)"
					( Origin gFrontEnd )
				)
				( attribute "CHIPS_PART_NAME" "RES"
					( Origin gPackager )
				)
				( attribute "CDS_PART_NAME" "RES_0402-0.0,5%,1/16W,EMPTY,G2A"
					( Origin gPackager )
				)
				( attribute "CDS_LOCATION" "R9F66"
					( Origin gPackager )
				)
				( attribute "CDS_SEC" "1"
					( Origin gPackager )
				)
				( attribute "SEC" "1"
					( Origin gPackager )
				)
				( objectStatus "R9F66" )
				( pin "a"
					( attribute "PN" "1"
						( Origin gPackager )
					)
					( objectStatus "R9F66.1" )
				)
				( pin "b"
					( attribute "PN" "2"
						( Origin gPackager )
					)
					( objectStatus "R9F66.2" )
				)
			)
			( gate "@baseboard_fab2_lib.baseboard_fab2(sch_1):page149_i72"
				( attribute "CDS_LIB" "mstr_discrete"
					( Origin gPackager )
				)
				( attribute "LOCATION" "C25W2"
					( Origin gFrontEnd )
				)
				( attribute "MATERIAL" "X6S"
					( Origin gFrontEnd )
				)
				( attribute "PACK_TYPE" "0402"
					( Origin gFrontEnd )
				)
				( attribute "PART_NUMBER" "D97712-011"
					( Origin gFrontEnd )
				)
				( attribute "PHYS_PAGE" "149"
					( Origin gFrontEnd )
				)
				( attribute "ROOM" "VDDQ_KLM_PWR_VR"
					( Origin gFrontEnd )
				)
				( attribute "ROT" "1"
					( Origin gFrontEnd )
				)
				( attribute "TOLERANCE" "10%"
					( Origin gFrontEnd )
				)
				( attribute "VALUE" "1.0UF"
					( Origin gFrontEnd )
				)
				( attribute "VER" "1"
					( Origin gFrontEnd )
				)
				( attribute "VOLTAGE" "16V"
					( Units "uVoltage" "V" 1.000000)
					( Origin gFrontEnd )
				)
				( attribute "XY" "(-5300,4050)"
					( Origin gFrontEnd )
				)
				( attribute "CHIPS_PART_NAME" "CAP"
					( Origin gPackager )
				)
				( attribute "CDS_PART_NAME" "CAP_0402-1.0UF,16V,10%,X6S,D97A"
					( Origin gPackager )
				)
				( attribute "CDS_LOCATION" "C25W2"
					( Origin gPackager )
				)
				( attribute "CDS_SEC" "1"
					( Origin gPackager )
				)
				( attribute "SEC" "1"
					( Origin gPackager )
				)
				( objectStatus "C25W2" )
				( pin "a"
					( attribute "PN" "1"
						( Origin gPackager )
					)
					( objectStatus "C25W2.1" )
				)
				( pin "b"
					( attribute "PN" "2"
						( Origin gPackager )
					)
					( objectStatus "C25W2.2" )
				)
			)
			( gate "@baseboard_fab2_lib.baseboard_fab2(sch_1):page144_i58"
				( attribute "CDS_LIB" "mstr_discrete"
					( Origin gPackager )
				)
				( attribute "CDS_LOCATION" "R1U13"
					( Origin gPackager )
				)
				( attribute "CDS_SEC" "1"
					( Origin gPackager )
				)
				( attribute "LOCATION" "R1U13"
					( Origin gFrontEnd )
				)
				( attribute "MATERIAL" "CHIP"
					( Origin gFrontEnd )
				)
				( attribute "PACK_TYPE" "0402"
					( Origin gFrontEnd )
				)
				( attribute "PART_NUMBER" "G21497-048"
					( Origin gFrontEnd )
				)
				( attribute "PHYS_PAGE" "144"
					( Origin gFrontEnd )
				)
				( attribute "ROOM" "BMC"
					( Origin gFrontEnd )
				)
				( attribute "ROT" "0"
					( Origin gFrontEnd )
				)
				( attribute "SEC" "1"
					( Origin gPackager )
				)
				( attribute "TOLERANCE" "5.0%"
					( Origin gFrontEnd )
				)
				( attribute "VALUE" "51"
					( Origin gFrontEnd )
				)
				( attribute "VER" "1"
					( Origin gFrontEnd )
				)
				( attribute "WATTAGE" "1/16W"
					( Origin gFrontEnd )
				)
				( attribute "XY" "(-1475,-2050)"
					( Origin gFrontEnd )
				)
				( attribute "CHIPS_PART_NAME" "RES"
					( Origin gPackager )
				)
				( attribute "CDS_PART_NAME" "RES_0402-51,5.0%,1/16W,CHIP,G2A"
					( Origin gPackager )
				)
				( objectStatus "R1U13" )
				( pin "a"
					( attribute "PN" "1"
						( Origin gPackager )
					)
					( objectStatus "R1U13.1" )
				)
				( pin "b"
					( attribute "PN" "2"
						( Origin gPackager )
					)
					( objectStatus "R1U13.2" )
				)
			)
			( gate "@baseboard_fab2_lib.baseboard_fab2(sch_1):page144_i57"
				( attribute "CDS_LIB" "mstr_discrete"
					( Origin gPackager )
				)
				( attribute "CDS_LOCATION" "R1U14"
					( Origin gPackager )
				)
				( attribute "CDS_SEC" "1"
					( Origin gPackager )
				)
				( attribute "LOCATION" "R1U14"
					( Origin gFrontEnd )
				)
				( attribute "MATERIAL" "CHIP"
					( Origin gFrontEnd )
				)
				( attribute "PACK_TYPE" "0402"
					( Origin gFrontEnd )
				)
				( attribute "PART_NUMBER" "G21497-048"
					( Origin gFrontEnd )
				)
				( attribute "PHYS_PAGE" "144"
					( Origin gFrontEnd )
				)
				( attribute "ROOM" "BMC"
					( Origin gFrontEnd )
				)
				( attribute "ROT" "0"
					( Origin gFrontEnd )
				)
				( attribute "SEC" "1"
					( Origin gPackager )
				)
				( attribute "TOLERANCE" "5.0%"
					( Origin gFrontEnd )
				)
				( attribute "VALUE" "51"
					( Origin gFrontEnd )
				)
				( attribute "VER" "1"
					( Origin gFrontEnd )
				)
				( attribute "WATTAGE" "1/16W"
					( Origin gFrontEnd )
				)
				( attribute "XY" "(-1500,-2200)"
					( Origin gFrontEnd )
				)
				( attribute "CHIPS_PART_NAME" "RES"
					( Origin gPackager )
				)
				( attribute "CDS_PART_NAME" "RES_0402-51,5.0%,1/16W,CHIP,G2A"
					( Origin gPackager )
				)
				( objectStatus "R1U14" )
				( pin "a"
					( attribute "PN" "1"
						( Origin gPackager )
					)
					( objectStatus "R1U14.1" )
				)
				( pin "b"
					( attribute "PN" "2"
						( Origin gPackager )
					)
					( objectStatus "R1U14.2" )
				)
			)
			( gate "@baseboard_fab2_lib.baseboard_fab2(sch_1):page148_i28"
				( attribute "CDS_LIB" "w_hdl"
					( Origin gPackager )
				)
				( attribute "CDS_LMAN_SYM_OUTLINE" "-850,2100,850,-2100"
					( Origin gPackager )
				)
				( attribute "LOCATION" "U25W4"
					( Origin gPackager )
				)
				( attribute "PACK_TYPE" "ASIC2-GB1"
					( Origin gFrontEnd )
				)
				( attribute "PART_NUMBER" "071.2520A.M001"
					( Origin gFrontEnd )
				)
				( attribute "PHYS_PAGE" "148"
					( Origin gFrontEnd )
				)
				( attribute "ROT" "0"
					( Origin gFrontEnd )
				)
				( attribute "VALUE" "AST2520A1-GP-GP"
					( Origin gFrontEnd )
				)
				( attribute "VER" "7"
					( Origin gFrontEnd )
				)
				( attribute "XY" "(-3600,2575)"
					( Origin gFrontEnd )
				)
				( attribute "CHIPS_PART_NAME" "AST2520A1-GP-GP"
					( Origin gPackager )
				)
				( attribute "CDS_PART_NAME" "AST2520A1-GP-GP_ASIC2-GB1-AST2A"
					( Origin gPackager )
				)
				( attribute "CDS_LOCATION" "U25W4"
					( Origin gPackager )
				)
				( attribute "CDS_SEC" "7"
					( Origin gPackager )
				)
				( attribute "SEC" "7"
					( Origin gPackager )
				)
				( objectStatus "U25W4" )
				( pin "adcav33"
					( attribute "PN" "J6"
						( Origin gPackager )
					)
					( objectStatus "U25W4.J6" )
				)
				( pin "batvdd"
					( attribute "PN" "E4"
						( Origin gPackager )
					)
					( objectStatus "U25W4.E4" )
				)
				( pin "dacav33"
					( attribute "PN" "K6"
						( Origin gPackager )
					)
					( objectStatus "U25W4.K6" )
				)
				( pin "dacdv33"
					( attribute "PN" "K5"
						( Origin gPackager )
					)
					( objectStatus "U25W4.K5" )
				)
				( pin "gnd0"
					( attribute "PN" "A1"
						( Origin gPackager )
					)
					( objectStatus "U25W4.A1" )
				)
				( pin "gnd1"
					( attribute "PN" "A22"
						( Origin gPackager )
					)
					( objectStatus "U25W4.A22" )
				)
				( pin "gnd2"
					( attribute "PN" "AA11"
						( Origin gPackager )
					)
					( objectStatus "U25W4.AA11" )
				)
				( pin "gnd3"
					( attribute "PN" "AA13"
						( Origin gPackager )
					)
					( objectStatus "U25W4.AA13" )
				)
				( pin "gnd4"
					( attribute "PN" "AA15"
						( Origin gPackager )
					)
					( objectStatus "U25W4.AA15" )
				)
				( pin "gnd5"
					( attribute "PN" "AA7"
						( Origin gPackager )
					)
					( objectStatus "U25W4.AA7" )
				)
				( pin "gnd6"
					( attribute "PN" "AA9"
						( Origin gPackager )
					)
					( objectStatus "U25W4.AA9" )
				)
				( pin "gnd7"
					( attribute "PN" "AB1"
						( Origin gPackager )
					)
					( objectStatus "U25W4.AB1" )
				)
				( pin "gnd8"
					( attribute "PN" "AB22"
						( Origin gPackager )
					)
					( objectStatus "U25W4.AB22" )
				)
				( pin "gnd9"
					( attribute "PN" "C6"
						( Origin gPackager )
					)
					( objectStatus "U25W4.C6" )
				)
				( pin "gnd10"
					( attribute "PN" "E8"
						( Origin gPackager )
					)
					( objectStatus "U25W4.E8" )
				)
				( pin "gnd11"
					( attribute "PN" "F16"
						( Origin gPackager )
					)
					( objectStatus "U25W4.F16" )
				)
				( pin "gnd12"
					( attribute "PN" "G19"
						( Origin gPackager )
					)
					( objectStatus "U25W4.G19" )
				)
				( pin "gnd13"
					( attribute "PN" "G6"
						( Origin gPackager )
					)
					( objectStatus "U25W4.G6" )
				)
				( pin "gnd14"
					( attribute "PN" "H6"
						( Origin gPackager )
					)
					( objectStatus "U25W4.H6" )
				)
				( pin "gnd15"
					( attribute "PN" "J10"
						( Origin gPackager )
					)
					( objectStatus "U25W4.J10" )
				)
				( pin "gnd16"
					( attribute "PN" "J11"
						( Origin gPackager )
					)
					( objectStatus "U25W4.J11" )
				)
				( pin "gnd17"
					( attribute "PN" "J12"
						( Origin gPackager )
					)
					( objectStatus "U25W4.J12" )
				)
				( pin "gnd18"
					( attribute "PN" "J13"
						( Origin gPackager )
					)
					( objectStatus "U25W4.J13" )
				)
				( pin "gnd19"
					( attribute "PN" "J14"
						( Origin gPackager )
					)
					( objectStatus "U25W4.J14" )
				)
				( pin "gnd20"
					( attribute "PN" "J21"
						( Origin gPackager )
					)
					( objectStatus "U25W4.J21" )
				)
				( pin "gnd21"
					( attribute "PN" "J22"
						( Origin gPackager )
					)
					( objectStatus "U25W4.J22" )
				)
				( pin "gnd22"
					( attribute "PN" "J5"
						( Origin gPackager )
					)
					( objectStatus "U25W4.J5" )
				)
				( pin "gnd23"
					( attribute "PN" "J9"
						( Origin gPackager )
					)
					( objectStatus "U25W4.J9" )
				)
				( pin "gnd24"
					( attribute "PN" "K10"
						( Origin gPackager )
					)
					( objectStatus "U25W4.K10" )
				)
				( pin "gnd25"
					( attribute "PN" "K11"
						( Origin gPackager )
					)
					( objectStatus "U25W4.K11" )
				)
				( pin "gnd26"
					( attribute "PN" "K12"
						( Origin gPackager )
					)
					( objectStatus "U25W4.K12" )
				)
				( pin "gnd27"
					( attribute "PN" "K13"
						( Origin gPackager )
					)
					( objectStatus "U25W4.K13" )
				)
				( pin "gnd28"
					( attribute "PN" "K14"
						( Origin gPackager )
					)
					( objectStatus "U25W4.K14" )
				)
				( pin "gnd29"
					( attribute "PN" "K16"
						( Origin gPackager )
					)
					( objectStatus "U25W4.K16" )
				)
				( pin "gnd30"
					( attribute "PN" "K9"
						( Origin gPackager )
					)
					( objectStatus "U25W4.K9" )
				)
				( pin "gnd31"
					( attribute "PN" "L10"
						( Origin gPackager )
					)
					( objectStatus "U25W4.L10" )
				)
				( pin "gnd32"
					( attribute "PN" "L11"
						( Origin gPackager )
					)
					( objectStatus "U25W4.L11" )
				)
				( pin "gnd33"
					( attribute "PN" "L12"
						( Origin gPackager )
					)
					( objectStatus "U25W4.L12" )
				)
				( pin "gnd34"
					( attribute "PN" "L13"
						( Origin gPackager )
					)
					( objectStatus "U25W4.L13" )
				)
				( pin "gnd35"
					( attribute "PN" "L14"
						( Origin gPackager )
					)
					( objectStatus "U25W4.L14" )
				)
				( pin "gnd36"
					( attribute "PN" "L9"
						( Origin gPackager )
					)
					( objectStatus "U25W4.L9" )
				)
				( pin "gnd37"
					( attribute "PN" "M1"
						( Origin gPackager )
					)
					( objectStatus "U25W4.M1" )
				)
				( pin "gnd38"
					( attribute "PN" "M10"
						( Origin gPackager )
					)
					( objectStatus "U25W4.M10" )
				)
				( pin "gnd39"
					( attribute "PN" "M11"
						( Origin gPackager )
					)
					( objectStatus "U25W4.M11" )
				)
				( pin "gnd40"
					( attribute "PN" "M12"
						( Origin gPackager )
					)
					( objectStatus "U25W4.M12" )
				)
				( pin "gnd41"
					( attribute "PN" "M13"
						( Origin gPackager )
					)
					( objectStatus "U25W4.M13" )
				)
				( pin "gnd42"
					( attribute "PN" "M14"
						( Origin gPackager )
					)
					( objectStatus "U25W4.M14" )
				)
				( pin "gnd43"
					( attribute "PN" "M16"
						( Origin gPackager )
					)
					( objectStatus "U25W4.M16" )
				)
				( pin "gnd44"
					( attribute "PN" "M17"
						( Origin gPackager )
					)
					( objectStatus "U25W4.M17" )
				)
				( pin "gnd45"
					( attribute "PN" "M2"
						( Origin gPackager )
					)
					( objectStatus "U25W4.M2" )
				)
				( pin "gnd46"
					( attribute "PN" "M3"
						( Origin gPackager )
					)
					( objectStatus "U25W4.M3" )
				)
				( pin "gnd47"
					( attribute "PN" "M4"
						( Origin gPackager )
					)
					( objectStatus "U25W4.M4" )
				)
				( pin "gnd48"
					( attribute "PN" "M5"
						( Origin gPackager )
					)
					( objectStatus "U25W4.M5" )
				)
				( pin "gnd49"
					( attribute "PN" "M6"
						( Origin gPackager )
					)
					( objectStatus "U25W4.M6" )
				)
				( pin "gnd50"
					( attribute "PN" "M7"
						( Origin gPackager )
					)
					( objectStatus "U25W4.M7" )
				)
				( pin "gnd51"
					( attribute "PN" "M9"
						( Origin gPackager )
					)
					( objectStatus "U25W4.M9" )
				)
				( pin "gnd52"
					( attribute "PN" "N10"
						( Origin gPackager )
					)
					( objectStatus "U25W4.N10" )
				)
				( pin "gnd53"
					( attribute "PN" "N11"
						( Origin gPackager )
					)
					( objectStatus "U25W4.N11" )
				)
				( pin "gnd54"
					( attribute "PN" "N12"
						( Origin gPackager )
					)
					( objectStatus "U25W4.N12" )
				)
				( pin "gnd55"
					( attribute "PN" "N13"
						( Origin gPackager )
					)
					( objectStatus "U25W4.N13" )
				)
				( pin "gnd56"
					( attribute "PN" "N14"
						( Origin gPackager )
					)
					( objectStatus "U25W4.N14" )
				)
				( pin "gnd57"
					( attribute "PN" "N9"
						( Origin gPackager )
					)
					( objectStatus "U25W4.N9" )
				)
				( pin "gnd58"
					( attribute "PN" "T16"
						( Origin gPackager )
					)
					( objectStatus "U25W4.T16" )
				)
				( pin "gnd59"
					( attribute "PN" "T6"
						( Origin gPackager )
					)
					( objectStatus "U25W4.T6" )
				)
				( pin "gnd60"
					( attribute "PN" "T7"
						( Origin gPackager )
					)
					( objectStatus "U25W4.T7" )
				)
				( pin "gnd61"
					( attribute "PN" "U11"
						( Origin gPackager )
					)
					( objectStatus "U25W4.U11" )
				)
				( pin "gnd62"
					( attribute "PN" "U6"
						( Origin gPackager )
					)
					( objectStatus "U25W4.U6" )
				)
				( pin "gnd63"
					( attribute "PN" "V10"
						( Origin gPackager )
					)
					( objectStatus "U25W4.V10" )
				)
				( pin "gnd64"
					( attribute "PN" "V12"
						( Origin gPackager )
					)
					( objectStatus "U25W4.V12" )
				)
				( pin "gnd65"
					( attribute "PN" "V14"
						( Origin gPackager )
					)
					( objectStatus "U25W4.V14" )
				)
				( pin "gnd66"
					( attribute "PN" "V16"
						( Origin gPackager )
					)
					( objectStatus "U25W4.V16" )
				)
				( pin "gnd67"
					( attribute "PN" "V8"
						( Origin gPackager )
					)
					( objectStatus "U25W4.V8" )
				)
				( pin "gnd68"
					( attribute "PN" "E5"
						( Origin gPackager )
					)
					( objectStatus "U25W4.E5" )
				)
				( pin "\gpioy0_sios3#\"
					( attribute "PN" "R22"
						( Origin gPackager )
					)
					( objectStatus "U25W4.R22" )
				)
				( pin "\gpioy1_sios5#\"
					( attribute "PN" "R21"
						( Origin gPackager )
					)
					( objectStatus "U25W4.R21" )
				)
				( pin "\gpioy2_siopwreq#\"
					( attribute "PN" "P22"
						( Origin gPackager )
					)
					( objectStatus "U25W4.P22" )
				)
				( pin "iv11d0"
					( attribute "PN" "F6"
						( Origin gPackager )
					)
					( objectStatus "U25W4.F6" )
				)
				( pin "iv11d1"
					( attribute "PN" "G10"
						( Origin gPackager )
					)
					( objectStatus "U25W4.G10" )
				)
				( pin "iv11d2"
					( attribute "PN" "G11"
						( Origin gPackager )
					)
					( objectStatus "U25W4.G11" )
				)
				( pin "iv11d3"
					( attribute "PN" "G12"
						( Origin gPackager )
					)
					( objectStatus "U25W4.G12" )
				)
				( pin "iv11d4"
					( attribute "PN" "G13"
						( Origin gPackager )
					)
					( objectStatus "U25W4.G13" )
				)
				( pin "iv11d5"
					( attribute "PN" "G14"
						( Origin gPackager )
					)
					( objectStatus "U25W4.G14" )
				)
				( pin "iv11d6"
					( attribute "PN" "G15"
						( Origin gPackager )
					)
					( objectStatus "U25W4.G15" )
				)
				( pin "iv11d7"
					( attribute "PN" "G7"
						( Origin gPackager )
					)
					( objectStatus "U25W4.G7" )
				)
				( pin "iv11d8"
					( attribute "PN" "G8"
						( Origin gPackager )
					)
					( objectStatus "U25W4.G8" )
				)
				( pin "iv11d9"
					( attribute "PN" "G9"
						( Origin gPackager )
					)
					( objectStatus "U25W4.G9" )
				)
				( pin "iv11d10"
					( attribute "PN" "H16"
						( Origin gPackager )
					)
					( objectStatus "U25W4.H16" )
				)
				( pin "iv11d11"
					( attribute "PN" "J16"
						( Origin gPackager )
					)
					( objectStatus "U25W4.J16" )
				)
				( pin "iv11d12"
					( attribute "PN" "L7"
						( Origin gPackager )
					)
					( objectStatus "U25W4.L7" )
				)
				( pin "iv11d13"
					( attribute "PN" "N16"
						( Origin gPackager )
					)
					( objectStatus "U25W4.N16" )
				)
				( pin "iv11d14"
					( attribute "PN" "N7"
						( Origin gPackager )
					)
					( objectStatus "U25W4.N7" )
				)
				( pin "iv11d15"
					( attribute "PN" "P10"
						( Origin gPackager )
					)
					( objectStatus "U25W4.P10" )
				)
				( pin "iv11d16"
					( attribute "PN" "P11"
						( Origin gPackager )
					)
					( objectStatus "U25W4.P11" )
				)
				( pin "iv11d17"
					( attribute "PN" "P12"
						( Origin gPackager )
					)
					( objectStatus "U25W4.P12" )
				)
				( pin "iv11d18"
					( attribute "PN" "P13"
						( Origin gPackager )
					)
					( objectStatus "U25W4.P13" )
				)
				( pin "iv11d19"
					( attribute "PN" "P14"
						( Origin gPackager )
					)
					( objectStatus "U25W4.P14" )
				)
				( pin "iv11d20"
					( attribute "PN" "P16"
						( Origin gPackager )
					)
					( objectStatus "U25W4.P16" )
				)
				( pin "iv11d21"
					( attribute "PN" "P7"
						( Origin gPackager )
					)
					( objectStatus "U25W4.P7" )
				)
				( pin "iv11d22"
					( attribute "PN" "P9"
						( Origin gPackager )
					)
					( objectStatus "U25W4.P9" )
				)
				( pin "iv11d23"
					( attribute "PN" "R16"
						( Origin gPackager )
					)
					( objectStatus "U25W4.R16" )
				)
				( pin "iv11d24"
					( attribute "PN" "R7"
						( Origin gPackager )
					)
					( objectStatus "U25W4.R7" )
				)
				( pin "lpvdd0"
					( attribute "PN" "J17"
						( Origin gPackager )
					)
					( objectStatus "U25W4.J17" )
				)
				( pin "lpvdd1"
					( attribute "PN" "K17"
						( Origin gPackager )
					)
					( objectStatus "U25W4.K17" )
				)
				( pin "mvdd0"
					( attribute "PN" "T10"
						( Origin gPackager )
					)
					( objectStatus "U25W4.T10" )
				)
				( pin "mvdd1"
					( attribute "PN" "T12"
						( Origin gPackager )
					)
					( objectStatus "U25W4.T12" )
				)
				( pin "mvdd2"
					( attribute "PN" "T13"
						( Origin gPackager )
					)
					( objectStatus "U25W4.T13" )
				)
				( pin "mvdd3"
					( attribute "PN" "T14"
						( Origin gPackager )
					)
					( objectStatus "U25W4.T14" )
				)
				( pin "mvdd4"
					( attribute "PN" "T8"
						( Origin gPackager )
					)
					( objectStatus "U25W4.T8" )
				)
				( pin "peav11"
					( attribute "PN" "L17"
						( Origin gPackager )
					)
					( objectStatus "U25W4.L17" )
				)
				( pin "peav33"
					( attribute "PN" "L16"
						( Origin gPackager )
					)
					( objectStatus "U25W4.L16" )
				)
				( pin "pecivdd"
					( attribute "PN" "AA17"
						( Origin gPackager )
					)
					( objectStatus "U25W4.AA17" )
				)
				( pin "pllav330"
					( attribute "PN" "Y17"
						( Origin gPackager )
					)
					( objectStatus "U25W4.Y17" )
				)
				( pin "pllav331"
					( attribute "PN" "W17"
						( Origin gPackager )
					)
					( objectStatus "U25W4.W17" )
				)
				( pin "plldv11"
					( attribute "PN" "V17"
						( Origin gPackager )
					)
					( objectStatus "U25W4.V17" )
				)
				( pin "pv33d0"
					( attribute "PN" "F12"
						( Origin gPackager )
					)
					( objectStatus "U25W4.F12" )
				)
				( pin "pv33d1"
					( attribute "PN" "F13"
						( Origin gPackager )
					)
					( objectStatus "U25W4.F13" )
				)
				( pin "pv33d2"
					( attribute "PN" "F14"
						( Origin gPackager )
					)
					( objectStatus "U25W4.F14" )
				)
				( pin "pv33d3"
					( attribute "PN" "F15"
						( Origin gPackager )
					)
					( objectStatus "U25W4.F15" )
				)
				( pin "pv33d4"
					( attribute "PN" "G16"
						( Origin gPackager )
					)
					( objectStatus "U25W4.G16" )
				)
				( pin "pv33d5"
					( attribute "PN" "H17"
						( Origin gPackager )
					)
					( objectStatus "U25W4.H17" )
				)
				( pin "pv33d6"
					( attribute "PN" "K7"
						( Origin gPackager )
					)
					( objectStatus "U25W4.K7" )
				)
				( pin "pv33d7"
					( attribute "PN" "N17"
						( Origin gPackager )
					)
					( objectStatus "U25W4.N17" )
				)
				( pin "pv33d8"
					( attribute "PN" "N6"
						( Origin gPackager )
					)
					( objectStatus "U25W4.N6" )
				)
				( pin "pv33d9"
					( attribute "PN" "P17"
						( Origin gPackager )
					)
					( objectStatus "U25W4.P17" )
				)
				( pin "pv33d10"
					( attribute "PN" "P6"
						( Origin gPackager )
					)
					( objectStatus "U25W4.P6" )
				)
				( pin "pv33d11"
					( attribute "PN" "R17"
						( Origin gPackager )
					)
					( objectStatus "U25W4.R17" )
				)
				( pin "pv33d12"
					( attribute "PN" "R6"
						( Origin gPackager )
					)
					( objectStatus "U25W4.R6" )
				)
				( pin "pv33d13"
					( attribute "PN" "T11"
						( Origin gPackager )
					)
					( objectStatus "U25W4.T11" )
				)
				( pin "pv33d14"
					( attribute "PN" "T15"
						( Origin gPackager )
					)
					( objectStatus "U25W4.T15" )
				)
				( pin "r1vdd0"
					( attribute "PN" "F10"
						( Origin gPackager )
					)
					( objectStatus "U25W4.F10" )
				)
				( pin "r1vdd1"
					( attribute "PN" "F11"
						( Origin gPackager )
					)
					( objectStatus "U25W4.F11" )
				)
				( pin "r2vdd0"
					( attribute "PN" "F7"
						( Origin gPackager )
					)
					( objectStatus "U25W4.F7" )
				)
				( pin "r2vdd1"
					( attribute "PN" "F8"
						( Origin gPackager )
					)
					( objectStatus "U25W4.F8" )
				)
				( pin "usb2av33"
					( attribute "PN" "C7"
						( Origin gPackager )
					)
					( objectStatus "U25W4.C7" )
				)
				( pin "vpllav110"
					( attribute "PN" "L5"
						( Origin gPackager )
					)
					( objectStatus "U25W4.L5" )
				)
				( pin "vpllav111"
					( attribute "PN" "L6"
						( Origin gPackager )
					)
					( objectStatus "U25W4.L6" )
				)
				( pin "vpllav330"
					( attribute "PN" "J7"
						( Origin gPackager )
					)
					( objectStatus "U25W4.J7" )
				)
				( pin "vpllav331"
					( attribute "PN" "H7"
						( Origin gPackager )
					)
					( objectStatus "U25W4.H7" )
				)
			)
			( gate "@baseboard_fab2_lib.baseboard_fab2(sch_1):page149_i73"
				( attribute "CDS_LIB" "mstr_discrete"
					( Origin gPackager )
				)
				( attribute "LOCATION" "C25W3"
					( Origin gFrontEnd )
				)
				( attribute "MATERIAL" "X6S"
					( Origin gFrontEnd )
				)
				( attribute "PACK_TYPE" "0402"
					( Origin gFrontEnd )
				)
				( attribute "PART_NUMBER" "D97712-011"
					( Origin gFrontEnd )
				)
				( attribute "PHYS_PAGE" "149"
					( Origin gFrontEnd )
				)
				( attribute "ROOM" "VDDQ_KLM_PWR_VR"
					( Origin gFrontEnd )
				)
				( attribute "ROT" "1"
					( Origin gFrontEnd )
				)
				( attribute "TOLERANCE" "10%"
					( Origin gFrontEnd )
				)
				( attribute "VALUE" "1.0UF"
					( Origin gFrontEnd )
				)
				( attribute "VER" "1"
					( Origin gFrontEnd )
				)
				( attribute "VOLTAGE" "16V"
					( Units "uVoltage" "V" 1.000000)
					( Origin gFrontEnd )
				)
				( attribute "XY" "(-5300,3800)"
					( Origin gFrontEnd )
				)
				( attribute "CHIPS_PART_NAME" "CAP"
					( Origin gPackager )
				)
				( attribute "CDS_PART_NAME" "CAP_0402-1.0UF,16V,10%,X6S,D97A"
					( Origin gPackager )
				)
				( attribute "CDS_LOCATION" "C25W3"
					( Origin gPackager )
				)
				( attribute "CDS_SEC" "1"
					( Origin gPackager )
				)
				( attribute "SEC" "1"
					( Origin gPackager )
				)
				( objectStatus "C25W3" )
				( pin "a"
					( attribute "PN" "1"
						( Origin gPackager )
					)
					( objectStatus "C25W3.1" )
				)
				( pin "b"
					( attribute "PN" "2"
						( Origin gPackager )
					)
					( objectStatus "C25W3.2" )
				)
			)
			( gate "@baseboard_fab2_lib.baseboard_fab2(sch_1):page149_i74"
				( attribute "CDS_LIB" "mstr_discrete"
					( Origin gPackager )
				)
				( attribute "LOCATION" "C25W4"
					( Origin gFrontEnd )
				)
				( attribute "MATERIAL" "X6S"
					( Origin gFrontEnd )
				)
				( attribute "PACK_TYPE" "0402"
					( Origin gFrontEnd )
				)
				( attribute "PART_NUMBER" "D97712-011"
					( Origin gFrontEnd )
				)
				( attribute "PHYS_PAGE" "149"
					( Origin gFrontEnd )
				)
				( attribute "ROOM" "VDDQ_KLM_PWR_VR"
					( Origin gFrontEnd )
				)
				( attribute "ROT" "1"
					( Origin gFrontEnd )
				)
				( attribute "TOLERANCE" "10%"
					( Origin gFrontEnd )
				)
				( attribute "VALUE" "1.0UF"
					( Origin gFrontEnd )
				)
				( attribute "VER" "1"
					( Origin gFrontEnd )
				)
				( attribute "VOLTAGE" "16V"
					( Units "uVoltage" "V" 1.000000)
					( Origin gFrontEnd )
				)
				( attribute "XY" "(-5300,3550)"
					( Origin gFrontEnd )
				)
				( attribute "CHIPS_PART_NAME" "CAP"
					( Origin gPackager )
				)
				( attribute "CDS_PART_NAME" "CAP_0402-1.0UF,16V,10%,X6S,D97A"
					( Origin gPackager )
				)
				( attribute "CDS_LOCATION" "C25W4"
					( Origin gPackager )
				)
				( attribute "CDS_SEC" "1"
					( Origin gPackager )
				)
				( attribute "SEC" "1"
					( Origin gPackager )
				)
				( objectStatus "C25W4" )
				( pin "a"
					( attribute "PN" "1"
						( Origin gPackager )
					)
					( objectStatus "C25W4.1" )
				)
				( pin "b"
					( attribute "PN" "2"
						( Origin gPackager )
					)
					( objectStatus "C25W4.2" )
				)
			)
			( gate "@baseboard_fab2_lib.baseboard_fab2(sch_1):page148_i20"
				( attribute "BOM_COST" "SM_CONTROLLER"
					( Origin gFrontEnd )
				)
				( attribute "CDS_LIB" "dev_discrete"
					( Origin gPackager )
				)
				( attribute "CDS_LOCATION" "C1T21"
					( Origin gPackager )
				)
				( attribute "CDS_SEC" "1"
					( Origin gPackager )
				)
				( attribute "LOCATION" "C1T21"
					( Origin gFrontEnd )
				)
				( attribute "MATERIAL" "X6S"
					( Origin gFrontEnd )
				)
				( attribute "PACK_TYPE" "0402V"
					( Origin gFrontEnd )
				)
				( attribute "PART_NUMBER" "D97712-004"
					( Origin gFrontEnd )
				)
				( attribute "PHYS_PAGE" "148"
					( Origin gFrontEnd )
				)
				( attribute "ROOM" "BMC"
					( Origin gFrontEnd )
				)
				( attribute "ROT" "0"
					( Origin gFrontEnd )
				)
				( attribute "SEC" "1"
					( Origin gFrontEnd )
				)
				( attribute "SEC_TYPE" "0402V"
					( Origin gFrontEnd )
				)
				( attribute "TOLERANCE" "10%"
					( Origin gFrontEnd )
				)
				( attribute "VALUE" "1.0UF"
					( Origin gFrontEnd )
				)
				( attribute "VER" "1"
					( Origin gFrontEnd )
				)
				( attribute "VOLTAGE" "6.3V"
					( Units "uVoltage" "V" 1.000000)
					( Origin gFrontEnd )
				)
				( attribute "XY" "(-6925,2100)"
					( Origin gFrontEnd )
				)
				( attribute "CHIPS_PART_NAME" "CAP_A"
					( Origin gPackager )
				)
				( attribute "CDS_PART_NAME" "CAP_A_0402V-1.0UF,6.3V,10%,X6SA"
					( Origin gPackager )
				)
				( objectStatus "C1T21" )
				( pin "a"
					( attribute "PN" "1"
						( Origin gPackager )
					)
					( objectStatus "C1T21.1" )
				)
				( pin "b"
					( attribute "PN" "2"
						( Origin gPackager )
					)
					( objectStatus "C1T21.2" )
				)
			)
			( gate "@baseboard_fab2_lib.baseboard_fab2(sch_1):page144_i59"
				( attribute "CDS_LIB" "mstr_discrete"
					( Origin gPackager )
				)
				( attribute "CDS_LOCATION" "R1U12"
					( Origin gPackager )
				)
				( attribute "CDS_SEC" "1"
					( Origin gPackager )
				)
				( attribute "LOCATION" "R1U12"
					( Origin gFrontEnd )
				)
				( attribute "MATERIAL" "CHIP"
					( Origin gFrontEnd )
				)
				( attribute "PACK_TYPE" "0402"
					( Origin gFrontEnd )
				)
				( attribute "PART_NUMBER" "G21497-048"
					( Origin gFrontEnd )
				)
				( attribute "PHYS_PAGE" "144"
					( Origin gFrontEnd )
				)
				( attribute "ROOM" "BMC"
					( Origin gFrontEnd )
				)
				( attribute "ROT" "0"
					( Origin gFrontEnd )
				)
				( attribute "SEC" "1"
					( Origin gPackager )
				)
				( attribute "TOLERANCE" "5.0%"
					( Origin gFrontEnd )
				)
				( attribute "VALUE" "51"
					( Origin gFrontEnd )
				)
				( attribute "VER" "1"
					( Origin gFrontEnd )
				)
				( attribute "WATTAGE" "1/16W"
					( Origin gFrontEnd )
				)
				( attribute "XY" "(-1475,-2150)"
					( Origin gFrontEnd )
				)
				( attribute "CHIPS_PART_NAME" "RES"
					( Origin gPackager )
				)
				( attribute "CDS_PART_NAME" "RES_0402-51,5.0%,1/16W,CHIP,G2A"
					( Origin gPackager )
				)
				( objectStatus "R1U12" )
				( pin "a"
					( attribute "PN" "1"
						( Origin gPackager )
					)
					( objectStatus "R1U12.1" )
				)
				( pin "b"
					( attribute "PN" "2"
						( Origin gPackager )
					)
					( objectStatus "R1U12.2" )
				)
			)
			( gate "@baseboard_fab2_lib.baseboard_fab2(sch_1):page148_i16"
				( attribute "BOM_COST" "MIO_USB"
					( Origin gFrontEnd )
				)
				( attribute "CDS_LIB" "mstr_discrete"
					( Origin gPackager )
				)
				( attribute "LOCATION" "R25W59"
					( Origin gFrontEnd )
				)
				( attribute "MATERIAL" "CHIP"
					( Origin gFrontEnd )
				)
				( attribute "PACK_TYPE" "0402"
					( Origin gFrontEnd )
				)
				( attribute "PART_NUMBER" "G21497-005"
					( Origin gFrontEnd )
				)
				( attribute "PHYS_PAGE" "148"
					( Origin gFrontEnd )
				)
				( attribute "ROOM" "USB"
					( Origin gFrontEnd )
				)
				( attribute "ROT" "0"
					( Origin gFrontEnd )
				)
				( attribute "TOLERANCE" "5%"
					( Origin gFrontEnd )
				)
				( attribute "VALUE" "0.0"
					( Origin gFrontEnd )
				)
				( attribute "VER" "1"
					( Origin gFrontEnd )
				)
				( attribute "WATTAGE" "1/16W"
					( Origin gFrontEnd )
				)
				( attribute "XY" "(-6550,3825)"
					( Origin gFrontEnd )
				)
				( attribute "CHIPS_PART_NAME" "RES"
					( Origin gPackager )
				)
				( attribute "CDS_PART_NAME" "RES_0402-0.0,5%,1/16W,CHIP,G21A"
					( Origin gPackager )
				)
				( attribute "CDS_LOCATION" "R25W59"
					( Origin gPackager )
				)
				( attribute "CDS_SEC" "1"
					( Origin gPackager )
				)
				( attribute "SEC" "1"
					( Origin gPackager )
				)
				( objectStatus "R25W59" )
				( pin "a"
					( attribute "PN" "1"
						( Origin gPackager )
					)
					( objectStatus "R25W59.1" )
				)
				( pin "b"
					( attribute "PN" "2"
						( Origin gPackager )
					)
					( objectStatus "R25W59.2" )
				)
			)
			( gate "@baseboard_fab2_lib.baseboard_fab2(sch_1):page147_i62"
				( attribute "CDS_LIB" "mstr_discrete"
					( Origin gPackager )
				)
				( attribute "CDS_LOCATION" "R1U2"
					( Origin gPackager )
				)
				( attribute "LOCATION" "R1U2"
					( Origin gFrontEnd )
				)
				( attribute "MATERIAL" "CHIP"
					( Origin gFrontEnd )
				)
				( attribute "PACK_TYPE" "0402"
					( Origin gFrontEnd )
				)
				( attribute "PART_NUMBER" "G21796-010"
					( Origin gFrontEnd )
				)
				( attribute "PHYS_PAGE" "147"
					( Origin gFrontEnd )
				)
				( attribute "ROT" "0"
					( Origin gFrontEnd )
				)
				( attribute "SEC" "1"
					( Origin gFrontEnd )
				)
				( attribute "SEC_TYPE" "0402"
					( Origin gFrontEnd )
				)
				( attribute "TOLERANCE" "1%"
					( Origin gFrontEnd )
				)
				( attribute "VALUE" "100.0K"
					( Origin gFrontEnd )
				)
				( attribute "VER" "2"
					( Origin gFrontEnd )
				)
				( attribute "WATTAGE" "1/16W"
					( Origin gFrontEnd )
				)
				( attribute "XY" "(-3775,1950)"
					( Origin gFrontEnd )
				)
				( attribute "CHIPS_PART_NAME" "RES"
					( Origin gPackager )
				)
				( attribute "CDS_PART_NAME" "RES_0402-100.0K,1%,1/16W,CHIP,A"
					( Origin gPackager )
				)
				( attribute "CDS_SEC" "1"
					( Origin gPackager )
				)
				( objectStatus "R1U2" )
				( pin "a"
					( attribute "PN" "1"
						( Origin gPackager )
					)
					( objectStatus "R1U2.1" )
				)
				( pin "b"
					( attribute "PN" "2"
						( Origin gPackager )
					)
					( objectStatus "R1U2.2" )
				)
			)
			( gate "@baseboard_fab2_lib.baseboard_fab2(sch_1):page145_i34"
				( attribute "BOM_COST" "SM_CONTROLLER"
					( Origin gFrontEnd )
				)
				( attribute "CDS_LIB" "mstr_discrete"
					( Origin gPackager )
				)
				( attribute "CDS_LOCATION" "R25W60"
					( Origin gPackager )
				)
				( attribute "CDS_SEC" "1"
					( Origin gPackager )
				)
				( attribute "LOCATION" "R25W60"
					( Origin gFrontEnd )
				)
				( attribute "MATERIAL" "CHIP"
					( Origin gFrontEnd )
				)
				( attribute "PACK_TYPE" "0402"
					( Origin gFrontEnd )
				)
				( attribute "PART_NUMBER" "G21796-010"
					( Origin gFrontEnd )
				)
				( attribute "PHYS_PAGE" "145"
					( Origin gFrontEnd )
				)
				( attribute "ROOM" "BMC"
					( Origin gFrontEnd )
				)
				( attribute "ROT" "0"
					( Origin gFrontEnd )
				)
				( attribute "SEC" "1"
					( Origin gFrontEnd )
				)
				( attribute "SEC_TYPE" "0402"
					( Origin gFrontEnd )
				)
				( attribute "TOLERANCE" "1%"
					( Origin gFrontEnd )
				)
				( attribute "VALUE" "100.0K"
					( Origin gFrontEnd )
				)
				( attribute "VER" "2"
					( Origin gFrontEnd )
				)
				( attribute "WATTAGE" "1/16W"
					( Origin gFrontEnd )
				)
				( attribute "XY" "(-5700,-4350)"
					( Origin gFrontEnd )
				)
				( attribute "CHIPS_PART_NAME" "RES"
					( Origin gPackager )
				)
				( attribute "CDS_PART_NAME" "RES_0402-100.0K,1%,1/16W,CHIP,A"
					( Origin gPackager )
				)
				( objectStatus "R25W60" )
				( pin "a"
					( attribute "PN" "1"
						( Origin gPackager )
					)
					( objectStatus "R25W60.1" )
				)
				( pin "b"
					( attribute "PN" "2"
						( Origin gPackager )
					)
					( objectStatus "R25W60.2" )
				)
			)
			( gate "@baseboard_fab2_lib.baseboard_fab2(sch_1):page147_i106"
				( attribute "CDS_LIB" "w_hdl"
					( Origin gPackager )
				)
				( attribute "CDS_LMAN_SYM_OUTLINE" "-1400,1400,1400,-1400"
					( Origin gPackager )
				)
				( attribute "PACK_TYPE" "ASIC2-GB1"
					( Origin gFrontEnd )
				)
				( attribute "PART_NUMBER" "071.2520A.M001"
					( Origin gFrontEnd )
				)
				( attribute "PHYS_PAGE" "147"
					( Origin gFrontEnd )
				)
				( attribute "ROT" "0"
					( Origin gFrontEnd )
				)
				( attribute "VALUE" "AST2520A1-GP-GP"
					( Origin gFrontEnd )
				)
				( attribute "VER" "6"
					( Origin gFrontEnd )
				)
				( attribute "XY" "(-1825,3400)"
					( Origin gFrontEnd )
				)
				( attribute "CHIPS_PART_NAME" "AST2520A1-GP-GP"
					( Origin gPackager )
				)
				( attribute "CDS_PART_NAME" "AST2520A1-GP-GP_ASIC2-GB1-AST2A"
					( Origin gPackager )
				)
				( attribute "LOCATION" "U25W4"
					( Origin gFrontEnd )
				)
				( attribute "CDS_LOCATION" "U25W4"
					( Origin gPackager )
				)
				( attribute "CDS_SEC" "6"
					( Origin gPackager )
				)
				( attribute "SEC" "6"
					( Origin gPackager )
				)
				( objectStatus "U25W4" )
				( pin "adc0_gpiw0"
					( attribute "PN" "F4"
						( Origin gPackager )
					)
					( objectStatus "U25W4.F4" )
				)
				( pin "adc1_gpiw1"
					( attribute "PN" "F5"
						( Origin gPackager )
					)
					( objectStatus "U25W4.F5" )
				)
				( pin "adc2_gpiw2"
					( attribute "PN" "E2"
						( Origin gPackager )
					)
					( objectStatus "U25W4.E2" )
				)
				( pin "adc3_gpiw3"
					( attribute "PN" "E1"
						( Origin gPackager )
					)
					( objectStatus "U25W4.E1" )
				)
				( pin "adc4_gpiw4"
					( attribute "PN" "F3"
						( Origin gPackager )
					)
					( objectStatus "U25W4.F3" )
				)
				( pin "adc5_gpiw5"
					( attribute "PN" "E3"
						( Origin gPackager )
					)
					( objectStatus "U25W4.E3" )
				)
				( pin "adc6_gpiw6"
					( attribute "PN" "G5"
						( Origin gPackager )
					)
					( objectStatus "U25W4.G5" )
				)
				( pin "adc7_gpiw7"
					( attribute "PN" "G4"
						( Origin gPackager )
					)
					( objectStatus "U25W4.G4" )
				)
				( pin "adc8_gpix0"
					( attribute "PN" "F2"
						( Origin gPackager )
					)
					( objectStatus "U25W4.F2" )
				)
				( pin "adc9_gpix1"
					( attribute "PN" "G3"
						( Origin gPackager )
					)
					( objectStatus "U25W4.G3" )
				)
				( pin "adc10_gpix2"
					( attribute "PN" "G2"
						( Origin gPackager )
					)
					( objectStatus "U25W4.G2" )
				)
				( pin "adc11_gpix3"
					( attribute "PN" "F1"
						( Origin gPackager )
					)
					( objectStatus "U25W4.F1" )
				)
				( pin "adc12_gpix4"
					( attribute "PN" "H5"
						( Origin gPackager )
					)
					( objectStatus "U25W4.H5" )
				)
				( pin "adc13_gpix5"
					( attribute "PN" "G1"
						( Origin gPackager )
					)
					( objectStatus "U25W4.G1" )
				)
				( pin "adc14_gpix6"
					( attribute "PN" "H3"
						( Origin gPackager )
					)
					( objectStatus "U25W4.H3" )
				)
				( pin "adc15_gpix7"
					( attribute "PN" "H4"
						( Origin gPackager )
					)
					( objectStatus "U25W4.H4" )
				)
				( pin "adcrext"
					( attribute "PN" "J1"
						( Origin gPackager )
					)
					( objectStatus "U25W4.J1" )
				)
				( pin "adcvrefn"
					( attribute "PN" "H1"
						( Origin gPackager )
					)
					( objectStatus "U25W4.H1" )
				)
				( pin "adcvrefp"
					( attribute "PN" "H2"
						( Origin gPackager )
					)
					( objectStatus "U25W4.H2" )
				)
				( pin "gpioa6_timer7_mdc2"
					( attribute "PN" "C13"
						( Origin gPackager )
					)
					( objectStatus "U25W4.C13" )
				)
				( pin "gpioa7_timer8_mdio2"
					( attribute "PN" "B13"
						( Origin gPackager )
					)
					( objectStatus "U25W4.B13" )
				)
				( pin "gpion0_pwm0"
					( attribute "PN" "V2"
						( Origin gPackager )
					)
					( objectStatus "U25W4.V2" )
				)
				( pin "gpion1_pwm1"
					( attribute "PN" "W2"
						( Origin gPackager )
					)
					( objectStatus "U25W4.W2" )
				)
				( pin "gpion2_pwm2_vpig2"
					( attribute "PN" "V3"
						( Origin gPackager )
					)
					( objectStatus "U25W4.V3" )
				)
				( pin "gpion3_pwm3_vpig3"
					( attribute "PN" "U3"
						( Origin gPackager )
					)
					( objectStatus "U25W4.U3" )
				)
				( pin "gpion4_pwm4_vpig4"
					( attribute "PN" "W3"
						( Origin gPackager )
					)
					( objectStatus "U25W4.W3" )
				)
				( pin "gpion5_pwm5_vpig5"
					( attribute "PN" "AA3"
						( Origin gPackager )
					)
					( objectStatus "U25W4.AA3" )
				)
				( pin "gpion6_pwm6_vpig6"
					( attribute "PN" "Y3"
						( Origin gPackager )
					)
					( objectStatus "U25W4.Y3" )
				)
				( pin "gpion7_pwm7_vpig7"
					( attribute "PN" "T4"
						( Origin gPackager )
					)
					( objectStatus "U25W4.T4" )
				)
				( pin "gpioo0_tach0_vpig8"
					( attribute "PN" "U5"
						( Origin gPackager )
					)
					( objectStatus "U25W4.U5" )
				)
				( pin "gpioo1_tach1_vpig9"
					( attribute "PN" "U4"
						( Origin gPackager )
					)
					( objectStatus "U25W4.U4" )
				)
				( pin "gpioo2_tach2"
					( attribute "PN" "V5"
						( Origin gPackager )
					)
					( objectStatus "U25W4.V5" )
				)
				( pin "gpioo3_tach3"
					( attribute "PN" "AB4"
						( Origin gPackager )
					)
					( objectStatus "U25W4.AB4" )
				)
				( pin "gpioo4_tach4_vpir2"
					( attribute "PN" "AB3"
						( Origin gPackager )
					)
					( objectStatus "U25W4.AB3" )
				)
				( pin "gpioo5_tach5_vpir3"
					( attribute "PN" "Y4"
						( Origin gPackager )
					)
					( objectStatus "U25W4.Y4" )
				)
				( pin "gpioo6_tach6_vpir4"
					( attribute "PN" "AA4"
						( Origin gPackager )
					)
					( objectStatus "U25W4.AA4" )
				)
				( pin "gpioo7_tach7_vpir5"
					( attribute "PN" "W4"
						( Origin gPackager )
					)
					( objectStatus "U25W4.W4" )
				)
				( pin "gpiop0_tach8_vpir6"
					( attribute "PN" "V4"
						( Origin gPackager )
					)
					( objectStatus "U25W4.V4" )
				)
				( pin "gpiop1_tach9_vpir7"
					( attribute "PN" "W5"
						( Origin gPackager )
					)
					( objectStatus "U25W4.W5" )
				)
				( pin "gpiop2_tach10_vpir8"
					( attribute "PN" "AA5"
						( Origin gPackager )
					)
					( objectStatus "U25W4.AA5" )
				)
				( pin "gpiop3_tach11_vpir9"
					( attribute "PN" "AB5"
						( Origin gPackager )
					)
					( objectStatus "U25W4.AB5" )
				)
				( pin "gpiop4_tach12"
					( attribute "PN" "Y6"
						( Origin gPackager )
					)
					( objectStatus "U25W4.Y6" )
				)
				( pin "gpiop5_tach13"
					( attribute "PN" "Y5"
						( Origin gPackager )
					)
					( objectStatus "U25W4.Y5" )
				)
				( pin "gpiop6_tach14"
					( attribute "PN" "W6"
						( Origin gPackager )
					)
					( objectStatus "U25W4.W6" )
				)
				( pin "gpiop7_tach15"
					( attribute "PN" "V6"
						( Origin gPackager )
					)
					( objectStatus "U25W4.V6" )
				)
				( pin "gpior6_mdc1"
					( attribute "PN" "D8"
						( Origin gPackager )
					)
					( objectStatus "U25W4.D8" )
				)
				( pin "gpior7_mdio1"
					( attribute "PN" "E10"
						( Origin gPackager )
					)
					( objectStatus "U25W4.E10" )
				)
				( pin "rgmii1rxck_rmii1rclki_gpiou4"
					( attribute "PN" "B4"
						( Origin gPackager )
					)
					( objectStatus "U25W4.B4" )
				)
				( pin "rgmii1rxctl_gpiou5"
					( attribute "PN" "A4"
						( Origin gPackager )
					)
					( objectStatus "U25W4.A4" )
				)
				( pin "rgmii1rxd0_rmii1rxd0_gpiou6"
					( attribute "PN" "A3"
						( Origin gPackager )
					)
					( objectStatus "U25W4.A3" )
				)
				( pin "rgmii1rxd1_rmii1rxd1_gpiou7"
					( attribute "PN" "D6"
						( Origin gPackager )
					)
					( objectStatus "U25W4.D6" )
				)
				( pin "rgmii1rxd2_rmii1crsdv_gpiov0"
					( attribute "PN" "C5"
						( Origin gPackager )
					)
					( objectStatus "U25W4.C5" )
				)
				( pin "rgmii1rxd3_rmii1rxer_gpiov1"
					( attribute "PN" "C4"
						( Origin gPackager )
					)
					( objectStatus "U25W4.C4" )
				)
				( pin "rgmii1txck_rmii1rclko_gpiot0"
					( attribute "PN" "B5"
						( Origin gPackager )
					)
					( objectStatus "U25W4.B5" )
				)
				( pin "rgmii1txctl_rmii1txen_gpiot1"
					( attribute "PN" "E9"
						( Origin gPackager )
					)
					( objectStatus "U25W4.E9" )
				)
				( pin "rgmii1txd0_rmii1txd0_gpiot2"
					( attribute "PN" "F9"
						( Origin gPackager )
					)
					( objectStatus "U25W4.F9" )
				)
				( pin "rgmii1txd1_rmii1txd1_gpiot3"
					( attribute "PN" "A5"
						( Origin gPackager )
					)
					( objectStatus "U25W4.A5" )
				)
				( pin "rgmii1txd2_gpiot4"
					( attribute "PN" "E7"
						( Origin gPackager )
					)
					( objectStatus "U25W4.E7" )
				)
				( pin "rgmii1txd3_gpiot5"
					( attribute "PN" "D7"
						( Origin gPackager )
					)
					( objectStatus "U25W4.D7" )
				)
				( pin "rgmii2rxck_rmii2rclki_gpiov2"
					( attribute "PN" "C2"
						( Origin gPackager )
					)
					( objectStatus "U25W4.C2" )
				)
				( pin "rgmii2rxctl_gpiov3"
					( attribute "PN" "C1"
						( Origin gPackager )
					)
					( objectStatus "U25W4.C1" )
				)
				( pin "rgmii2rxd0_rmii2rxd0_gpiov4"
					( attribute "PN" "C3"
						( Origin gPackager )
					)
					( objectStatus "U25W4.C3" )
				)
				( pin "rgmii2rxd1_rmii2rxd1_gpiov5"
					( attribute "PN" "D1"
						( Origin gPackager )
					)
					( objectStatus "U25W4.D1" )
				)
				( pin "rgmii2rxd2_rmii2crsdv_gpiov6"
					( attribute "PN" "D2"
						( Origin gPackager )
					)
					( objectStatus "U25W4.D2" )
				)
				( pin "rgmii2rxd3_rmii2rxer_gpiov7"
					( attribute "PN" "E6"
						( Origin gPackager )
					)
					( objectStatus "U25W4.E6" )
				)
				( pin "rgmii2txck_rmii2rclko_gpiot6"
					( attribute "PN" "B2"
						( Origin gPackager )
					)
					( objectStatus "U25W4.B2" )
				)
				( pin "rgmii2txctl_rmii2txen_gpiot7"
					( attribute "PN" "B1"
						( Origin gPackager )
					)
					( objectStatus "U25W4.B1" )
				)
				( pin "rgmii2txd0_rmii2txd0_gpiou0"
					( attribute "PN" "A2"
						( Origin gPackager )
					)
					( objectStatus "U25W4.A2" )
				)
				( pin "rgmii2txd1_rmii2txd1_gpiou1"
					( attribute "PN" "B3"
						( Origin gPackager )
					)
					( objectStatus "U25W4.B3" )
				)
				( pin "rgmii2txd2_gpiou2"
					( attribute "PN" "D5"
						( Origin gPackager )
					)
					( objectStatus "U25W4.D5" )
				)
				( pin "rgmii2txd3_gpiou3"
					( attribute "PN" "D4"
						( Origin gPackager )
					)
					( objectStatus "U25W4.D4" )
				)
				( pin "rgmiick"
					( attribute "PN" "D3"
						( Origin gPackager )
					)
					( objectStatus "U25W4.D3" )
				)
			)
			( gate "@baseboard_fab2_lib.baseboard_fab2(sch_1):page147_i61"
				( attribute "CDS_LIB" "mstr_discrete"
					( Origin gPackager )
				)
				( attribute "CDS_LOCATION" "R1U1"
					( Origin gPackager )
				)
				( attribute "LOCATION" "R1U1"
					( Origin gFrontEnd )
				)
				( attribute "MATERIAL" "CHIP"
					( Origin gFrontEnd )
				)
				( attribute "PACK_TYPE" "0402"
					( Origin gFrontEnd )
				)
				( attribute "PART_NUMBER" "G21796-010"
					( Origin gFrontEnd )
				)
				( attribute "PHYS_PAGE" "147"
					( Origin gFrontEnd )
				)
				( attribute "ROT" "0"
					( Origin gFrontEnd )
				)
				( attribute "SEC" "1"
					( Origin gFrontEnd )
				)
				( attribute "SEC_TYPE" "0402"
					( Origin gFrontEnd )
				)
				( attribute "TOLERANCE" "1%"
					( Origin gFrontEnd )
				)
				( attribute "VALUE" "100.0K"
					( Origin gFrontEnd )
				)
				( attribute "VER" "2"
					( Origin gFrontEnd )
				)
				( attribute "WATTAGE" "1/16W"
					( Origin gFrontEnd )
				)
				( attribute "XY" "(-3525,1950)"
					( Origin gFrontEnd )
				)
				( attribute "CHIPS_PART_NAME" "RES"
					( Origin gPackager )
				)
				( attribute "CDS_PART_NAME" "RES_0402-100.0K,1%,1/16W,CHIP,A"
					( Origin gPackager )
				)
				( attribute "CDS_SEC" "1"
					( Origin gPackager )
				)
				( objectStatus "R1U1" )
				( pin "a"
					( attribute "PN" "1"
						( Origin gPackager )
					)
					( objectStatus "R1U1.1" )
				)
				( pin "b"
					( attribute "PN" "2"
						( Origin gPackager )
					)
					( objectStatus "R1U1.2" )
				)
			)
			( gate "@baseboard_fab2_lib.baseboard_fab2(sch_1):page146_i37"
				( attribute "BOM_COST" "SM_CONTROLLER"
					( Origin gFrontEnd )
				)
				( attribute "CDS_LIB" "mstr_discrete"
					( Origin gPackager )
				)
				( attribute "CDS_LOCATION" "R1T26"
					( Origin gPackager )
				)
				( attribute "CDS_SEC" "1"
					( Origin gPackager )
				)
				( attribute "LOCATION" "R1T26"
					( Origin gFrontEnd )
				)
				( attribute "MATERIAL" "CHIP"
					( Origin gFrontEnd )
				)
				( attribute "PACK_TYPE" "0402"
					( Origin gFrontEnd )
				)
				( attribute "PART_NUMBER" "G21796-345"
					( Origin gFrontEnd )
				)
				( attribute "PHYS_PAGE" "146"
					( Origin gFrontEnd )
				)
				( attribute "ROOM" "BMC"
					( Origin gFrontEnd )
				)
				( attribute "ROT" "1"
					( Origin gFrontEnd )
				)
				( attribute "SEC" "1"
					( Origin gPackager )
				)
				( attribute "TOLERANCE" "1%"
					( Origin gFrontEnd )
				)
				( attribute "VALUE" "8.2K"
					( Origin gFrontEnd )
				)
				( attribute "VER" "2"
					( Origin gFrontEnd )
				)
				( attribute "WATTAGE" "1/16W"
					( Origin gFrontEnd )
				)
				( attribute "XY" "(-725,4200)"
					( Origin gFrontEnd )
				)
				( attribute "CHIPS_PART_NAME" "RES"
					( Origin gPackager )
				)
				( attribute "CDS_PART_NAME" "RES_0402-8.2K,1%,1/16W,CHIP,G2A"
					( Origin gPackager )
				)
				( objectStatus "R1T26" )
				( pin "a"
					( attribute "PN" "1"
						( Origin gPackager )
					)
					( objectStatus "R1T26.1" )
				)
				( pin "b"
					( attribute "PN" "2"
						( Origin gPackager )
					)
					( objectStatus "R1T26.2" )
				)
			)
			( gate "@baseboard_fab2_lib.baseboard_fab2(sch_1):page146_i35"
				( attribute "BOM_COST" "SM_CONTROLLER"
					( Origin gFrontEnd )
				)
				( attribute "CDS_LIB" "mstr_discrete"
					( Origin gPackager )
				)
				( attribute "LOCATION" "R1T25"
					( Origin gFrontEnd )
				)
				( attribute "MATERIAL" "CHIP"
					( Origin gFrontEnd )
				)
				( attribute "PACK_TYPE" "0402"
					( Origin gFrontEnd )
				)
				( attribute "PART_NUMBER" "G21796-345"
					( Origin gFrontEnd )
				)
				( attribute "PHYS_PAGE" "146"
					( Origin gFrontEnd )
				)
				( attribute "ROOM" "BMC"
					( Origin gFrontEnd )
				)
				( attribute "ROT" "1"
					( Origin gFrontEnd )
				)
				( attribute "TOLERANCE" "1%"
					( Origin gFrontEnd )
				)
				( attribute "VALUE" "8.2K"
					( Origin gFrontEnd )
				)
				( attribute "VER" "2"
					( Origin gFrontEnd )
				)
				( attribute "WATTAGE" "1/16W"
					( Origin gFrontEnd )
				)
				( attribute "XY" "(-1175,4150)"
					( Origin gFrontEnd )
				)
				( attribute "CHIPS_PART_NAME" "RES"
					( Origin gPackager )
				)
				( attribute "CDS_PART_NAME" "RES_0402-8.2K,1%,1/16W,CHIP,G2A"
					( Origin gPackager )
				)
				( attribute "CDS_LOCATION" "R1T25"
					( Origin gPackager )
				)
				( attribute "CDS_SEC" "1"
					( Origin gPackager )
				)
				( attribute "SEC" "1"
					( Origin gPackager )
				)
				( objectStatus "R1T25" )
				( pin "a"
					( attribute "PN" "1"
						( Origin gPackager )
					)
					( objectStatus "R1T25.1" )
				)
				( pin "b"
					( attribute "PN" "2"
						( Origin gPackager )
					)
					( objectStatus "R1T25.2" )
				)
			)
			( gate "@baseboard_fab2_lib.baseboard_fab2(sch_1):page146_i27"
				( attribute "BOM_COST" "MIO_USB"
					( Origin gFrontEnd )
				)
				( attribute "CDS_LIB" "mstr_discrete"
					( Origin gPackager )
				)
				( attribute "LOCATION" "R25W84"
					( Origin gFrontEnd )
				)
				( attribute "MATERIAL" "CHIP"
					( Origin gFrontEnd )
				)
				( attribute "PACK_TYPE" "0402"
					( Origin gFrontEnd )
				)
				( attribute "PART_NUMBER" "G21497-005"
					( Origin gFrontEnd )
				)
				( attribute "PHYS_PAGE" "146"
					( Origin gFrontEnd )
				)
				( attribute "ROOM" "USB"
					( Origin gFrontEnd )
				)
				( attribute "ROT" "0"
					( Origin gFrontEnd )
				)
				( attribute "TOLERANCE" "5%"
					( Origin gFrontEnd )
				)
				( attribute "VALUE" "0.0"
					( Origin gFrontEnd )
				)
				( attribute "VER" "1"
					( Origin gFrontEnd )
				)
				( attribute "WATTAGE" "1/16W"
					( Origin gFrontEnd )
				)
				( attribute "XY" "(-6950,3825)"
					( Origin gFrontEnd )
				)
				( attribute "CHIPS_PART_NAME" "RES"
					( Origin gPackager )
				)
				( attribute "CDS_PART_NAME" "RES_0402-0.0,5%,1/16W,CHIP,G21A"
					( Origin gPackager )
				)
				( attribute "CDS_LOCATION" "R25W84"
					( Origin gPackager )
				)
				( attribute "CDS_SEC" "1"
					( Origin gPackager )
				)
				( attribute "SEC" "1"
					( Origin gPackager )
				)
				( objectStatus "R25W84" )
				( pin "a"
					( attribute "PN" "1"
						( Origin gPackager )
					)
					( objectStatus "R25W84.1" )
				)
				( pin "b"
					( attribute "PN" "2"
						( Origin gPackager )
					)
					( objectStatus "R25W84.2" )
				)
			)
			( gate "@baseboard_fab2_lib.baseboard_fab2(sch_1):page146_i26"
				( attribute "BOM_COST" "MIO_USB"
					( Origin gFrontEnd )
				)
				( attribute "CDS_LIB" "mstr_discrete"
					( Origin gPackager )
				)
				( attribute "LOCATION" "R25W83"
					( Origin gFrontEnd )
				)
				( attribute "MATERIAL" "CHIP"
					( Origin gFrontEnd )
				)
				( attribute "PACK_TYPE" "0402"
					( Origin gFrontEnd )
				)
				( attribute "PART_NUMBER" "G21497-005"
					( Origin gFrontEnd )
				)
				( attribute "PHYS_PAGE" "146"
					( Origin gFrontEnd )
				)
				( attribute "ROOM" "USB"
					( Origin gFrontEnd )
				)
				( attribute "ROT" "0"
					( Origin gFrontEnd )
				)
				( attribute "TOLERANCE" "5%"
					( Origin gFrontEnd )
				)
				( attribute "VALUE" "0.0"
					( Origin gFrontEnd )
				)
				( attribute "VER" "1"
					( Origin gFrontEnd )
				)
				( attribute "WATTAGE" "1/16W"
					( Origin gFrontEnd )
				)
				( attribute "XY" "(-6950,3900)"
					( Origin gFrontEnd )
				)
				( attribute "CHIPS_PART_NAME" "RES"
					( Origin gPackager )
				)
				( attribute "CDS_PART_NAME" "RES_0402-0.0,5%,1/16W,CHIP,G21A"
					( Origin gPackager )
				)
				( attribute "CDS_LOCATION" "R25W83"
					( Origin gPackager )
				)
				( attribute "CDS_SEC" "1"
					( Origin gPackager )
				)
				( attribute "SEC" "1"
					( Origin gPackager )
				)
				( objectStatus "R25W83" )
				( pin "a"
					( attribute "PN" "1"
						( Origin gPackager )
					)
					( objectStatus "R25W83.1" )
				)
				( pin "b"
					( attribute "PN" "2"
						( Origin gPackager )
					)
					( objectStatus "R25W83.2" )
				)
			)
			( gate "@baseboard_fab2_lib.baseboard_fab2(sch_1):page148_i23"
				( attribute "BOM_COST" "SM_CONTROLLER"
					( Origin gFrontEnd )
				)
				( attribute "CDS_LIB" "mstr_discrete"
					( Origin gPackager )
				)
				( attribute "CDS_LOCATION" "R25W75"
					( Origin gPackager )
				)
				( attribute "CDS_SEC" "1"
					( Origin gPackager )
				)
				( attribute "LOCATION" "R25W75"
					( Origin gFrontEnd )
				)
				( attribute "MATERIAL" "CHIP"
					( Origin gFrontEnd )
				)
				( attribute "PACK_TYPE" "0402"
					( Origin gFrontEnd )
				)
				( attribute "PART_NUMBER" "G21796-074"
					( Origin gFrontEnd )
				)
				( attribute "PHYS_PAGE" "148"
					( Origin gFrontEnd )
				)
				( attribute "ROOM" "BMC"
					( Origin gFrontEnd )
				)
				( attribute "ROT" "0"
					( Origin gFrontEnd )
				)
				( attribute "SEC" "1"
					( Origin gFrontEnd )
				)
				( attribute "SEC_TYPE" "0402"
					( Origin gFrontEnd )
				)
				( attribute "TOLERANCE" "1%"
					( Origin gFrontEnd )
				)
				( attribute "VALUE" "33.2"
					( Origin gFrontEnd )
				)
				( attribute "VER" "1"
					( Origin gFrontEnd )
				)
				( attribute "WATTAGE" "1/16W"
					( Origin gFrontEnd )
				)
				( attribute "XY" "(-5900,2475)"
					( Origin gFrontEnd )
				)
				( attribute "CHIPS_PART_NAME" "RES"
					( Origin gPackager )
				)
				( attribute "CDS_PART_NAME" "RES_0402-33.2,1%,1/16W,CHIP,G2A"
					( Origin gPackager )
				)
				( objectStatus "R25W75" )
				( pin "a"
					( attribute "PN" "1"
						( Origin gPackager )
					)
					( objectStatus "R25W75.1" )
				)
				( pin "b"
					( attribute "PN" "2"
						( Origin gPackager )
					)
					( objectStatus "R25W75.2" )
				)
			)
			( gate "@baseboard_fab2_lib.baseboard_fab2(sch_1):page147_i21"
				( attribute "BOM_COST" "SM_CONTROLLER"
					( Origin gFrontEnd )
				)
				( attribute "CDS_LIB" "mstr_discrete"
					( Origin gPackager )
				)
				( attribute "CDS_LOCATION" "R25W90"
					( Origin gPackager )
				)
				( attribute "CDS_SEC" "1"
					( Origin gPackager )
				)
				( attribute "LOCATION" "R25W90"
					( Origin gFrontEnd )
				)
				( attribute "MATERIAL" "CHIP"
					( Origin gFrontEnd )
				)
				( attribute "PACK_TYPE" "0402"
					( Origin gFrontEnd )
				)
				( attribute "PART_NUMBER" "G21796-250"
					( Origin gFrontEnd )
				)
				( attribute "PHYS_PAGE" "147"
					( Origin gFrontEnd )
				)
				( attribute "ROOM" "BMC"
					( Origin gFrontEnd )
				)
				( attribute "ROT" "0"
					( Origin gFrontEnd )
				)
				( attribute "SEC" "1"
					( Origin gFrontEnd )
				)
				( attribute "SEC_TYPE" "0402"
					( Origin gFrontEnd )
				)
				( attribute "TOLERANCE" "1.0%"
					( Origin gFrontEnd )
				)
				( attribute "VALUE" "22.1"
					( Origin gFrontEnd )
				)
				( attribute "VER" "1"
					( Origin gFrontEnd )
				)
				( attribute "WATTAGE" "1/16W"
					( Origin gFrontEnd )
				)
				( attribute "XY" "(925,4200)"
					( Origin gFrontEnd )
				)
				( attribute "CHIPS_PART_NAME" "RES"
					( Origin gPackager )
				)
				( attribute "CDS_PART_NAME" "RES_0402-22.1,1.0%,1/16W,CHIP,A"
					( Origin gPackager )
				)
				( objectStatus "R25W90" )
				( pin "a"
					( attribute "PN" "1"
						( Origin gPackager )
					)
					( objectStatus "R25W90.1" )
				)
				( pin "b"
					( attribute "PN" "2"
						( Origin gPackager )
					)
					( objectStatus "R25W90.2" )
				)
			)
			( gate "@baseboard_fab2_lib.baseboard_fab2(sch_1):page150_i71"
				( attribute "BOM_COST" "SM_CONTROLLER"
					( Origin gFrontEnd )
				)
				( attribute "CDS_LIB" "mstr_discrete"
					( Origin gPackager )
				)
				( attribute "LOCATION" "C25W26"
					( Origin gFrontEnd )
				)
				( attribute "MATERIAL" "X6S"
					( Origin gFrontEnd )
				)
				( attribute "PACK_TYPE" "0402"
					( Origin gFrontEnd )
				)
				( attribute "PART_NUMBER" "D97712-004"
					( Origin gFrontEnd )
				)
				( attribute "PHYS_PAGE" "150"
					( Origin gFrontEnd )
				)
				( attribute "ROOM" "BMC"
					( Origin gFrontEnd )
				)
				( attribute "ROT" "0"
					( Origin gFrontEnd )
				)
				( attribute "TOLERANCE" "10%"
					( Origin gFrontEnd )
				)
				( attribute "VALUE" "1.0UF"
					( Origin gFrontEnd )
				)
				( attribute "VER" "1"
					( Origin gFrontEnd )
				)
				( attribute "VOLTAGE" "6.3V"
					( Units "uVoltage" "V" 1.000000)
					( Origin gFrontEnd )
				)
				( attribute "XY" "(-5275,4975)"
					( Origin gFrontEnd )
				)
				( attribute "CHIPS_PART_NAME" "CAP"
					( Origin gPackager )
				)
				( attribute "CDS_PART_NAME" "CAP_0402-1.0UF,6.3V,10%,X6S,D9A"
					( Origin gPackager )
				)
				( attribute "CDS_LOCATION" "C25W26"
					( Origin gPackager )
				)
				( attribute "CDS_SEC" "1"
					( Origin gPackager )
				)
				( attribute "SEC" "1"
					( Origin gPackager )
				)
				( objectStatus "C25W26" )
				( pin "a"
					( attribute "PN" "1"
						( Origin gPackager )
					)
					( objectStatus "C25W26.1" )
				)
				( pin "b"
					( attribute "PN" "2"
						( Origin gPackager )
					)
					( objectStatus "C25W26.2" )
				)
			)
			( gate "@baseboard_fab2_lib.baseboard_fab2(sch_1):page150_i69"
				( attribute "CDS_LIB" "w_hdl"
					( Origin gPackager )
				)
				( attribute "CDS_LMAN_SYM_OUTLINE" "-50,25,50,-25"
					( Origin gPackager )
				)
				( attribute "LOCATION" "C25W59"
					( Origin gFrontEnd )
				)
				( attribute "PACK_TYPE" "SMD-BCG"
					( Origin gFrontEnd )
				)
				( attribute "PART_NUMBER" "78.47523.5BL"
					( Origin gFrontEnd )
				)
				( attribute "PHYS_PAGE" "150"
					( Origin gFrontEnd )
				)
				( attribute "ROT" "0"
					( Origin gFrontEnd )
				)
				( attribute "VALUE" "SC4D7U10V3KX-GP"
					( Origin gFrontEnd )
				)
				( attribute "VER" "1"
					( Origin gFrontEnd )
				)
				( attribute "XY" "(-4775,1400)"
					( Origin gFrontEnd )
				)
				( attribute "CHIPS_PART_NAME" "SC4D7U10V3KX-GP"
					( Origin gPackager )
				)
				( attribute "CDS_PART_NAME" "SC4D7U10V3KX-GP_SMD-BCG-SC4D7UA"
					( Origin gPackager )
				)
				( attribute "CDS_LOCATION" "C25W59"
					( Origin gPackager )
				)
				( attribute "CDS_SEC" "1"
					( Origin gPackager )
				)
				( attribute "SEC" "1"
					( Origin gPackager )
				)
				( objectStatus "C25W59" )
				( pin "\1\"
					( attribute "PN" "1"
						( Origin gPackager )
					)
					( objectStatus "C25W59.1" )
				)
				( pin "\2\"
					( attribute "PN" "2"
						( Origin gPackager )
					)
					( objectStatus "C25W59.2" )
				)
			)
			( gate "@baseboard_fab2_lib.baseboard_fab2(sch_1):page150_i67"
				( attribute "CDS_LIB" "w_hdl"
					( Origin gPackager )
				)
				( attribute "CDS_LMAN_SYM_OUTLINE" "-50,25,50,-25"
					( Origin gPackager )
				)
				( attribute "LOCATION" "C25W61"
					( Origin gFrontEnd )
				)
				( attribute "PACK_TYPE" "SMD-BCG"
					( Origin gFrontEnd )
				)
				( attribute "PART_NUMBER" "78.10421.2FL"
					( Origin gFrontEnd )
				)
				( attribute "PHYS_PAGE" "150"
					( Origin gFrontEnd )
				)
				( attribute "ROT" "0"
					( Origin gFrontEnd )
				)
				( attribute "VALUE" "SCD1U16V2KX-3GP"
					( Origin gFrontEnd )
				)
				( attribute "VER" "1"
					( Origin gFrontEnd )
				)
				( attribute "XY" "(-2200,1325)"
					( Origin gFrontEnd )
				)
				( attribute "CHIPS_PART_NAME" "SCD1U16V2KX-3GP"
					( Origin gPackager )
				)
				( attribute "CDS_PART_NAME" "SCD1U16V2KX-3GP_SMD-BCG-SCD1U1A"
					( Origin gPackager )
				)
				( attribute "CDS_LOCATION" "C25W61"
					( Origin gPackager )
				)
				( attribute "CDS_SEC" "1"
					( Origin gPackager )
				)
				( attribute "SEC" "1"
					( Origin gPackager )
				)
				( objectStatus "C25W61" )
				( pin "\1\"
					( attribute "PN" "1"
						( Origin gPackager )
					)
					( objectStatus "C25W61.1" )
				)
				( pin "\2\"
					( attribute "PN" "2"
						( Origin gPackager )
					)
					( objectStatus "C25W61.2" )
				)
			)
			( gate "@baseboard_fab2_lib.baseboard_fab2(sch_1):page150_i1"
				( attribute "BOM_COST" "SM_CONTROLLER"
					( Origin gFrontEnd )
				)
				( attribute "CDS_LIB" "mstr_discrete"
					( Origin gPackager )
				)
				( attribute "LOCATION" "C25W60"
					( Origin gFrontEnd )
				)
				( attribute "MATERIAL" "X6S"
					( Origin gFrontEnd )
				)
				( attribute "PACK_TYPE" "0402"
					( Origin gFrontEnd )
				)
				( attribute "PART_NUMBER" "D97712-004"
					( Origin gFrontEnd )
				)
				( attribute "PHYS_PAGE" "150"
					( Origin gFrontEnd )
				)
				( attribute "ROOM" "BMC"
					( Origin gFrontEnd )
				)
				( attribute "ROT" "0"
					( Origin gFrontEnd )
				)
				( attribute "TOLERANCE" "10%"
					( Origin gFrontEnd )
				)
				( attribute "VALUE" "1.0UF"
					( Origin gFrontEnd )
				)
				( attribute "VER" "1"
					( Origin gFrontEnd )
				)
				( attribute "VOLTAGE" "6.3V"
					( Units "uVoltage" "V" 1.000000)
					( Origin gFrontEnd )
				)
				( attribute "XY" "(-2750,1300)"
					( Origin gFrontEnd )
				)
				( attribute "CHIPS_PART_NAME" "CAP"
					( Origin gPackager )
				)
				( attribute "CDS_PART_NAME" "CAP_0402-1.0UF,6.3V,10%,X6S,D9A"
					( Origin gPackager )
				)
				( attribute "CDS_LOCATION" "C25W60"
					( Origin gPackager )
				)
				( attribute "CDS_SEC" "1"
					( Origin gPackager )
				)
				( attribute "SEC" "1"
					( Origin gPackager )
				)
				( objectStatus "C25W60" )
				( pin "a"
					( attribute "PN" "1"
						( Origin gPackager )
					)
					( objectStatus "C25W60.1" )
				)
				( pin "b"
					( attribute "PN" "2"
						( Origin gPackager )
					)
					( objectStatus "C25W60.2" )
				)
			)
			( gate "@baseboard_fab2_lib.baseboard_fab2(sch_1):page149_i34"
				( attribute "CDS_LIB" "mstr_ttl"
					( Origin gPackager )
				)
				( attribute "CDS_LOCATION" "U9F3"
					( Origin gPackager )
				)
				( attribute "CDS_SEC" "1"
					( Origin gPackager )
				)
				( attribute "LOCATION" "U9F3"
					( Origin gFrontEnd )
				)
				( attribute "MATERIAL" "IC"
					( Origin gFrontEnd )
				)
				( attribute "PACK_TYPE" "SOP"
					( Origin gFrontEnd )
				)
				( attribute "PART_NUMBER" "C88419-001"
					( Origin gFrontEnd )
				)
				( attribute "PHYS_PAGE" "149"
					( Origin gFrontEnd )
				)
				( attribute "ROOM" "BMC_MEMORY"
					( Origin gFrontEnd )
				)
				( attribute "ROT" "0"
					( Origin gFrontEnd )
				)
				( attribute "SEC" "1"
					( Origin gFrontEnd )
				)
				( attribute "SEC_TYPE" "SOP"
					( Origin gFrontEnd )
				)
				( attribute "VALUE" "74LVC1G07"
					( Origin gFrontEnd )
				)
				( attribute "VER" "1"
					( Origin gFrontEnd )
				)
				( attribute "XY" "(-2475,4600)"
					( Origin gFrontEnd )
				)
				( attribute "CHIPS_PART_NAME" "TTL1G07_A"
					( Origin gPackager )
				)
				( attribute "CDS_PART_NAME" "TTL1G07_A_SOP-74LVC1G07,IC,C88B"
					( Origin gPackager )
				)
				( objectStatus "U9F3" )
				( pin "a"
					( attribute "PN" "2"
						( Origin gPackager )
					)
					( objectStatus "U9F3.2" )
				)
				( pin "y"
					( attribute "PN" "4"
						( Origin gPackager )
					)
					( objectStatus "U9F3.4" )
				)
			)
			( gate "@baseboard_fab2_lib.baseboard_fab2(sch_1):page149_i37"
				( attribute "BOM_COST" "SM_CONTROLLER"
					( Origin gFrontEnd )
				)
				( attribute "CDS_LIB" "mstr_discrete"
					( Origin gPackager )
				)
				( attribute "LOCATION" "C25W16"
					( Origin gFrontEnd )
				)
				( attribute "MATERIAL" "COG"
					( Origin gFrontEnd )
				)
				( attribute "PACK_TYPE" "0402LF"
					( Origin gFrontEnd )
				)
				( attribute "PART_NUMBER" "A36095-026"
					( Origin gFrontEnd )
				)
				( attribute "PHYS_PAGE" "149"
					( Origin gFrontEnd )
				)
				( attribute "ROOM" "BMC"
					( Origin gFrontEnd )
				)
				( attribute "ROT" "0"
					( Origin gFrontEnd )
				)
				( attribute "TOLERANCE" "5%"
					( Origin gFrontEnd )
				)
				( attribute "VALUE" "100.0PF"
					( Origin gFrontEnd )
				)
				( attribute "VER" "1"
					( Origin gFrontEnd )
				)
				( attribute "VOLTAGE" "50V"
					( Units "uVoltage" "V" 1.000000)
					( Origin gFrontEnd )
				)
				( attribute "XY" "(-4025,4700)"
					( Origin gFrontEnd )
				)
				( attribute "CHIPS_PART_NAME" "CAP"
					( Origin gPackager )
				)
				( attribute "CDS_PART_NAME" "CAP_0402LF-100.0PF,50V,5%,COG,A"
					( Origin gPackager )
				)
				( attribute "CDS_LOCATION" "C25W16"
					( Origin gPackager )
				)
				( attribute "CDS_SEC" "1"
					( Origin gPackager )
				)
				( attribute "SEC" "1"
					( Origin gPackager )
				)
				( objectStatus "C25W16" )
				( pin "a"
					( attribute "PN" "1"
						( Origin gPackager )
					)
					( objectStatus "C25W16.1" )
				)
				( pin "b"
					( attribute "PN" "2"
						( Origin gPackager )
					)
					( objectStatus "C25W16.2" )
				)
			)
			( gate "@baseboard_fab2_lib.baseboard_fab2(sch_1):page149_i38"
				( attribute "CDS_LIB" "w_hdl"
					( Origin gPackager )
				)
				( attribute "CDS_LMAN_SYM_OUTLINE" "-50,25,50,-25"
					( Origin gPackager )
				)
				( attribute "LOCATION" "C25W17"
					( Origin gFrontEnd )
				)
				( attribute "PACK_TYPE" "SMD-BCG"
					( Origin gFrontEnd )
				)
				( attribute "PART_NUMBER" "78.10521.5BL"
					( Origin gFrontEnd )
				)
				( attribute "PHYS_PAGE" "149"
					( Origin gFrontEnd )
				)
				( attribute "ROT" "0"
					( Origin gFrontEnd )
				)
				( attribute "VALUE" "SC1U16V3KX-2GP"
					( Origin gFrontEnd )
				)
				( attribute "VER" "1"
					( Origin gFrontEnd )
				)
				( attribute "XY" "(-4450,4700)"
					( Origin gFrontEnd )
				)
				( attribute "CHIPS_PART_NAME" "SC1U16V3KX-2GP"
					( Origin gPackager )
				)
				( attribute "CDS_PART_NAME" "SC1U16V3KX-2GP_SMD-BCG-SC1U16VA"
					( Origin gPackager )
				)
				( attribute "CDS_LOCATION" "C25W17"
					( Origin gPackager )
				)
				( attribute "CDS_SEC" "1"
					( Origin gPackager )
				)
				( attribute "SEC" "1"
					( Origin gPackager )
				)
				( objectStatus "C25W17" )
				( pin "\1\"
					( attribute "PN" "1"
						( Origin gPackager )
					)
					( objectStatus "C25W17.1" )
				)
				( pin "\2\"
					( attribute "PN" "2"
						( Origin gPackager )
					)
					( objectStatus "C25W17.2" )
				)
			)
			( gate "@baseboard_fab2_lib.baseboard_fab2(sch_1):page149_i39"
				( attribute "CDS_LIB" "w_hdl"
					( Origin gPackager )
				)
				( attribute "CDS_LMAN_SYM_OUTLINE" "-50,25,50,-25"
					( Origin gPackager )
				)
				( attribute "LOCATION" "C25W15"
					( Origin gFrontEnd )
				)
				( attribute "PACK_TYPE" "SMD-BCG"
					( Origin gFrontEnd )
				)
				( attribute "PART_NUMBER" "78.10421.2FL"
					( Origin gFrontEnd )
				)
				( attribute "PHYS_PAGE" "149"
					( Origin gFrontEnd )
				)
				( attribute "ROT" "0"
					( Origin gFrontEnd )
				)
				( attribute "VALUE" "SCD1U16V2KX-3GP"
					( Origin gFrontEnd )
				)
				( attribute "VER" "1"
					( Origin gFrontEnd )
				)
				( attribute "XY" "(-3050,3075)"
					( Origin gFrontEnd )
				)
				( attribute "CHIPS_PART_NAME" "SCD1U16V2KX-3GP"
					( Origin gPackager )
				)
				( attribute "CDS_PART_NAME" "SCD1U16V2KX-3GP_SMD-BCG-SCD1U1A"
					( Origin gPackager )
				)
				( attribute "CDS_LOCATION" "C25W15"
					( Origin gPackager )
				)
				( attribute "CDS_SEC" "1"
					( Origin gPackager )
				)
				( attribute "SEC" "1"
					( Origin gPackager )
				)
				( objectStatus "C25W15" )
				( pin "\1\"
					( attribute "PN" "1"
						( Origin gPackager )
					)
					( objectStatus "C25W15.1" )
				)
				( pin "\2\"
					( attribute "PN" "2"
						( Origin gPackager )
					)
					( objectStatus "C25W15.2" )
				)
			)
			( gate "@baseboard_fab2_lib.baseboard_fab2(sch_1):page150_i2"
				( attribute "CDS_LIB" "w_hdl"
					( Origin gPackager )
				)
				( attribute "CDS_LMAN_SYM_OUTLINE" "-50,25,50,-25"
					( Origin gPackager )
				)
				( attribute "LOCATION" "C25W65"
					( Origin gFrontEnd )
				)
				( attribute "PACK_TYPE" "SMD-BCG"
					( Origin gFrontEnd )
				)
				( attribute "PART_NUMBER" "78.47523.5BL"
					( Origin gFrontEnd )
				)
				( attribute "PHYS_PAGE" "150"
					( Origin gFrontEnd )
				)
				( attribute "ROT" "0"
					( Origin gFrontEnd )
				)
				( attribute "VALUE" "SC4D7U10V3KX-GP"
					( Origin gFrontEnd )
				)
				( attribute "VER" "1"
					( Origin gFrontEnd )
				)
				( attribute "XY" "(650,1450)"
					( Origin gFrontEnd )
				)
				( attribute "CHIPS_PART_NAME" "SC4D7U10V3KX-GP"
					( Origin gPackager )
				)
				( attribute "CDS_PART_NAME" "SC4D7U10V3KX-GP_SMD-BCG-SC4D7UA"
					( Origin gPackager )
				)
				( attribute "CDS_LOCATION" "C25W65"
					( Origin gPackager )
				)
				( attribute "CDS_SEC" "1"
					( Origin gPackager )
				)
				( attribute "SEC" "1"
					( Origin gPackager )
				)
				( objectStatus "C25W65" )
				( pin "\1\"
					( attribute "PN" "1"
						( Origin gPackager )
					)
					( objectStatus "C25W65.1" )
				)
				( pin "\2\"
					( attribute "PN" "2"
						( Origin gPackager )
					)
					( objectStatus "C25W65.2" )
				)
			)
			( gate "@baseboard_fab2_lib.baseboard_fab2(sch_1):page150_i4"
				( attribute "BOM_COST" "SM_CONTROLLER"
					( Origin gFrontEnd )
				)
				( attribute "CDS_LIB" "mstr_discrete"
					( Origin gPackager )
				)
				( attribute "LOCATION" "C25W71"
					( Origin gFrontEnd )
				)
				( attribute "MATERIAL" "X6S"
					( Origin gFrontEnd )
				)
				( attribute "PACK_TYPE" "0402"
					( Origin gFrontEnd )
				)
				( attribute "PART_NUMBER" "D97712-004"
					( Origin gFrontEnd )
				)
				( attribute "PHYS_PAGE" "150"
					( Origin gFrontEnd )
				)
				( attribute "ROOM" "BMC"
					( Origin gFrontEnd )
				)
				( attribute "ROT" "0"
					( Origin gFrontEnd )
				)
				( attribute "TOLERANCE" "10%"
					( Origin gFrontEnd )
				)
				( attribute "VALUE" "1.0UF"
					( Origin gFrontEnd )
				)
				( attribute "VER" "1"
					( Origin gFrontEnd )
				)
				( attribute "VOLTAGE" "6.3V"
					( Units "uVoltage" "V" 1.000000)
					( Origin gFrontEnd )
				)
				( attribute "XY" "(575,4900)"
					( Origin gFrontEnd )
				)
				( attribute "CHIPS_PART_NAME" "CAP"
					( Origin gPackager )
				)
				( attribute "CDS_PART_NAME" "CAP_0402-1.0UF,6.3V,10%,X6S,D9A"
					( Origin gPackager )
				)
				( attribute "CDS_LOCATION" "C25W71"
					( Origin gPackager )
				)
				( attribute "CDS_SEC" "1"
					( Origin gPackager )
				)
				( attribute "SEC" "1"
					( Origin gPackager )
				)
				( objectStatus "C25W71" )
				( pin "a"
					( attribute "PN" "1"
						( Origin gPackager )
					)
					( objectStatus "C25W71.1" )
				)
				( pin "b"
					( attribute "PN" "2"
						( Origin gPackager )
					)
					( objectStatus "C25W71.2" )
				)
			)
			( gate "@baseboard_fab2_lib.baseboard_fab2(sch_1):page145_i14"
				( attribute "BOM_COST" "SM_CONTROLLER"
					( Origin gFrontEnd )
				)
				( attribute "CDS_LIB" "mstr_discrete"
					( Origin gPackager )
				)
				( attribute "CDS_LOCATION" "R9F61"
					( Origin gPackager )
				)
				( attribute "CDS_SEC" "1"
					( Origin gPackager )
				)
				( attribute "LOCATION" "R9F61"
					( Origin gFrontEnd )
				)
				( attribute "MATERIAL" "CHIP"
					( Origin gFrontEnd )
				)
				( attribute "PACK_TYPE" "0402"
					( Origin gFrontEnd )
				)
				( attribute "PART_NUMBER" "G21796-016"
					( Origin gFrontEnd )
				)
				( attribute "PHYS_PAGE" "145"
					( Origin gFrontEnd )
				)
				( attribute "ROOM" "BMC"
					( Origin gFrontEnd )
				)
				( attribute "ROT" "0"
					( Origin gFrontEnd )
				)
				( attribute "SEC" "1"
					( Origin gFrontEnd )
				)
				( attribute "SEC_TYPE" "0402"
					( Origin gFrontEnd )
				)
				( attribute "TOLERANCE" "1%"
					( Origin gFrontEnd )
				)
				( attribute "VALUE" "10.0K"
					( Origin gFrontEnd )
				)
				( attribute "VER" "2"
					( Origin gFrontEnd )
				)
				( attribute "WATTAGE" "1/16W"
					( Origin gFrontEnd )
				)
				( attribute "XY" "(-7000,-475)"
					( Origin gFrontEnd )
				)
				( attribute "CHIPS_PART_NAME" "RES"
					( Origin gPackager )
				)
				( attribute "CDS_PART_NAME" "RES_0402-10.0K,1%,1/16W,CHIP,GA"
					( Origin gPackager )
				)
				( objectStatus "R9F61" )
				( pin "a"
					( attribute "PN" "1"
						( Origin gPackager )
					)
					( objectStatus "R9F61.1" )
				)
				( pin "b"
					( attribute "PN" "2"
						( Origin gPackager )
					)
					( objectStatus "R9F61.2" )
				)
			)
			( gate "@baseboard_fab2_lib.baseboard_fab2(sch_1):page145_i11"
				( attribute "BOM_COST" "SM_CONTROLLER"
					( Origin gFrontEnd )
				)
				( attribute "CDS_LIB" "mstr_discrete"
					( Origin gPackager )
				)
				( attribute "CDS_LOCATION" "R9F62"
					( Origin gPackager )
				)
				( attribute "CDS_SEC" "1"
					( Origin gPackager )
				)
				( attribute "LOCATION" "R9F62"
					( Origin gFrontEnd )
				)
				( attribute "MATERIAL" "CHIP"
					( Origin gFrontEnd )
				)
				( attribute "PACK_TYPE" "0402"
					( Origin gFrontEnd )
				)
				( attribute "PART_NUMBER" "G21497-005"
					( Origin gFrontEnd )
				)
				( attribute "PHYS_PAGE" "145"
					( Origin gFrontEnd )
				)
				( attribute "ROOM" "BMC"
					( Origin gFrontEnd )
				)
				( attribute "ROT" "0"
					( Origin gFrontEnd )
				)
				( attribute "SEC" "1"
					( Origin gFrontEnd )
				)
				( attribute "SEC_TYPE" "0402"
					( Origin gFrontEnd )
				)
				( attribute "TOLERANCE" "5%"
					( Origin gFrontEnd )
				)
				( attribute "VALUE" "0.0"
					( Origin gFrontEnd )
				)
				( attribute "VER" "1"
					( Origin gFrontEnd )
				)
				( attribute "WATTAGE" "1/16W"
					( Origin gFrontEnd )
				)
				( attribute "XY" "(-4750,-550)"
					( Origin gFrontEnd )
				)
				( attribute "CHIPS_PART_NAME" "RES"
					( Origin gPackager )
				)
				( attribute "CDS_PART_NAME" "RES_0402-0.0,5%,1/16W,CHIP,G21A"
					( Origin gPackager )
				)
				( objectStatus "R9F62" )
				( pin "a"
					( attribute "PN" "1"
						( Origin gPackager )
					)
					( objectStatus "R9F62.1" )
				)
				( pin "b"
					( attribute "PN" "2"
						( Origin gPackager )
					)
					( objectStatus "R9F62.2" )
				)
			)
			( gate "@baseboard_fab2_lib.baseboard_fab2(sch_1):page145_i10"
				( attribute "BOM_COST" "SM_CONTROLLER"
					( Origin gFrontEnd )
				)
				( attribute "CDS_LIB" "mstr_discrete"
					( Origin gPackager )
				)
				( attribute "CDS_LOCATION" "R9F60"
					( Origin gPackager )
				)
				( attribute "CDS_SEC" "1"
					( Origin gPackager )
				)
				( attribute "LOCATION" "R9F60"
					( Origin gFrontEnd )
				)
				( attribute "MATERIAL" "EMPTY"
					( Origin gFrontEnd )
				)
				( attribute "PACK_TYPE" "0402"
					( Origin gFrontEnd )
				)
				( attribute "PART_NUMBER" "G21497-005"
					( Origin gFrontEnd )
				)
				( attribute "PHYS_PAGE" "145"
					( Origin gFrontEnd )
				)
				( attribute "ROOM" "BMC"
					( Origin gFrontEnd )
				)
				( attribute "ROT" "0"
					( Origin gFrontEnd )
				)
				( attribute "SEC" "1"
					( Origin gFrontEnd )
				)
				( attribute "SEC_TYPE" "0402"
					( Origin gFrontEnd )
				)
				( attribute "TOLERANCE" "5%"
					( Origin gFrontEnd )
				)
				( attribute "VALUE" "0.0"
					( Origin gFrontEnd )
				)
				( attribute "VER" "1"
					( Origin gFrontEnd )
				)
				( attribute "WATTAGE" "1/16W"
					( Origin gFrontEnd )
				)
				( attribute "XY" "(-4750,-250)"
					( Origin gFrontEnd )
				)
				( attribute "CHIPS_PART_NAME" "RES"
					( Origin gPackager )
				)
				( attribute "CDS_PART_NAME" "RES_0402-0.0,5%,1/16W,EMPTY,G2A"
					( Origin gPackager )
				)
				( objectStatus "R9F60" )
				( pin "a"
					( attribute "PN" "1"
						( Origin gPackager )
					)
					( objectStatus "R9F60.1" )
				)
				( pin "b"
					( attribute "PN" "2"
						( Origin gPackager )
					)
					( objectStatus "R9F60.2" )
				)
			)
			( gate "@baseboard_fab2_lib.baseboard_fab2(sch_1):page150_i72"
				( attribute "BOM_COST" "SM_CONTROLLER"
					( Origin gFrontEnd )
				)
				( attribute "CDS_LIB" "mstr_discrete"
					( Origin gPackager )
				)
				( attribute "CDS_LOCATION" "C25W25"
					( Origin gPackager )
				)
				( attribute "CDS_SEC" "1"
					( Origin gPackager )
				)
				( attribute "LOCATION" "C25W25"
					( Origin gFrontEnd )
				)
				( attribute "MATERIAL" "X6S"
					( Origin gFrontEnd )
				)
				( attribute "PACK_TYPE" "0402"
					( Origin gFrontEnd )
				)
				( attribute "PART_NUMBER" "D97712-004"
					( Origin gFrontEnd )
				)
				( attribute "PHYS_PAGE" "150"
					( Origin gFrontEnd )
				)
				( attribute "ROOM" "BMC"
					( Origin gFrontEnd )
				)
				( attribute "ROT" "0"
					( Origin gFrontEnd )
				)
				( attribute "SEC" "1"
					( Origin gFrontEnd )
				)
				( attribute "SEC_TYPE" "0402"
					( Origin gFrontEnd )
				)
				( attribute "TOLERANCE" "10%"
					( Origin gFrontEnd )
				)
				( attribute "VALUE" "1.0UF"
					( Origin gFrontEnd )
				)
				( attribute "VER" "1"
					( Origin gFrontEnd )
				)
				( attribute "VOLTAGE" "6.3V"
					( Units "uVoltage" "V" 1.000000)
					( Origin gFrontEnd )
				)
				( attribute "XY" "(-5675,4975)"
					( Origin gFrontEnd )
				)
				( attribute "CHIPS_PART_NAME" "CAP"
					( Origin gPackager )
				)
				( attribute "CDS_PART_NAME" "CAP_0402-1.0UF,6.3V,10%,X6S,D9A"
					( Origin gPackager )
				)
				( objectStatus "C25W25" )
				( pin "a"
					( attribute "PN" "1"
						( Origin gPackager )
					)
					( objectStatus "C25W25.1" )
				)
				( pin "b"
					( attribute "PN" "2"
						( Origin gPackager )
					)
					( objectStatus "C25W25.2" )
				)
			)
			( gate "@baseboard_fab2_lib.baseboard_fab2(sch_1):page145_i8"
				( attribute "BOM_COST" "SM_CONTROLLER"
					( Origin gFrontEnd )
				)
				( attribute "CDS_LIB" "mstr_discrete"
					( Origin gPackager )
				)
				( attribute "CDS_LMAN_SYM_OUTLINE" "-350,200,350,-200"
					( Origin gPackager )
				)
				( attribute "CDS_LOCATION" "Y9F2"
					( Origin gPackager )
				)
				( attribute "CDS_SEC" "1"
					( Origin gPackager )
				)
				( attribute "LOCATION" "Y9F2"
					( Origin gFrontEnd )
				)
				( attribute "MATERIAL" "OSC"
					( Origin gFrontEnd )
				)
				( attribute "PACK_TYPE" "SM4"
					( Origin gFrontEnd )
				)
				( attribute "PART_NUMBER" "D34520-021"
					( Origin gFrontEnd )
				)
				( attribute "PHYS_PAGE" "145"
					( Origin gFrontEnd )
				)
				( attribute "ROOM" "BMC"
					( Origin gFrontEnd )
				)
				( attribute "ROT" "0"
					( Origin gFrontEnd )
				)
				( attribute "SEC" "1"
					( Origin gFrontEnd )
				)
				( attribute "SEC_TYPE" "SM4"
					( Origin gFrontEnd )
				)
				( attribute "VALUE" "24MHZ"
					( Origin gFrontEnd )
				)
				( attribute "VER" "11"
					( Origin gFrontEnd )
				)
				( attribute "XY" "(-6050,-650)"
					( Origin gFrontEnd )
				)
				( attribute "CHIPS_PART_NAME" "OSC_C"
					( Origin gPackager )
				)
				( attribute "CDS_PART_NAME" "OSC_C_SM4-24MHZ,OSC,D34520-021"
					( Origin gPackager )
				)
				( objectStatus "Y9F2" )
				( pin "enable_control"
					( attribute "PN" "1"
						( Origin gPackager )
					)
					( objectStatus "Y9F2.1" )
				)
				( pin "gnd"
					( attribute "PN" "2"
						( Origin gPackager )
					)
					( objectStatus "Y9F2.2" )
				)
				( pin "\out\"
					( attribute "PN" "3"
						( Origin gPackager )
					)
					( objectStatus "Y9F2.3" )
				)
				( pin "vdd"
					( attribute "PN" "4"
						( Origin gPackager )
					)
					( objectStatus "Y9F2.4" )
				)
			)
			( gate "@baseboard_fab2_lib.baseboard_fab2(sch_1):page149_i16"
				( attribute "BOM_COST" "SM_MEM"
					( Origin gFrontEnd )
				)
				( attribute "CDS_LIB" "mstr_discrete"
					( Origin gPackager )
				)
				( attribute "CDS_LOCATION" "R9F29"
					( Origin gPackager )
				)
				( attribute "CDS_SEC" "1"
					( Origin gPackager )
				)
				( attribute "LOCATION" "R9F29"
					( Origin gFrontEnd )
				)
				( attribute "MATERIAL" "CHIP"
					( Origin gFrontEnd )
				)
				( attribute "PACK_TYPE" "0402"
					( Origin gFrontEnd )
				)
				( attribute "PART_NUMBER" "G21796-072"
					( Origin gFrontEnd )
				)
				( attribute "PHYS_PAGE" "149"
					( Origin gFrontEnd )
				)
				( attribute "ROOM" "BMC_MEMORY"
					( Origin gFrontEnd )
				)
				( attribute "ROT" "0"
					( Origin gFrontEnd )
				)
				( attribute "SEC" "1"
					( Origin gFrontEnd )
				)
				( attribute "SEC_TYPE" "0402"
					( Origin gFrontEnd )
				)
				( attribute "TOLERANCE" "1%"
					( Origin gFrontEnd )
				)
				( attribute "VALUE" "4.75K"
					( Origin gFrontEnd )
				)
				( attribute "VER" "2"
					( Origin gFrontEnd )
				)
				( attribute "WATTAGE" "1/16W"
					( Origin gFrontEnd )
				)
				( attribute "XY" "(-1725,4775)"
					( Origin gFrontEnd )
				)
				( attribute "CHIPS_PART_NAME" "RES"
					( Origin gPackager )
				)
				( attribute "CDS_PART_NAME" "RES_0402-4.75K,1%,1/16W,CHIP,GA"
					( Origin gPackager )
				)
				( objectStatus "R9F29" )
				( pin "a"
					( attribute "PN" "1"
						( Origin gPackager )
					)
					( objectStatus "R9F29.1" )
				)
				( pin "b"
					( attribute "PN" "2"
						( Origin gPackager )
					)
					( objectStatus "R9F29.2" )
				)
			)
			( gate "@baseboard_fab2_lib.baseboard_fab2(sch_1):page149_i201"
				( attribute "CDS_LIB" "w_hdl"
					( Origin gPackager )
				)
				( attribute "CDS_LMAN_SYM_OUTLINE" "-50,75,50,-75"
					( Origin gPackager )
				)
				( attribute "LOCATION" "R25W42"
					( Origin gFrontEnd )
				)
				( attribute "PACK_TYPE" "RCL_GP"
					( Origin gFrontEnd )
				)
				( attribute "PART_NUMBER" "64.12005.6DL"
					( Origin gFrontEnd )
				)
				( attribute "PHYS_PAGE" "149"
					( Origin gFrontEnd )
				)
				( attribute "ROT" "1"
					( Origin gFrontEnd )
				)
				( attribute "VALUE" "120R2F-GP"
					( Origin gFrontEnd )
				)
				( attribute "VER" "1"
					( Origin gFrontEnd )
				)
				( attribute "XY" "(-6150,3550)"
					( Origin gFrontEnd )
				)
				( attribute "CHIPS_PART_NAME" "120R2F-GP"
					( Origin gPackager )
				)
				( attribute "CDS_PART_NAME" "120R2F-GP_RCL_GP-120R2F-GP,64.A"
					( Origin gPackager )
				)
				( attribute "CDS_LOCATION" "R25W42"
					( Origin gPackager )
				)
				( attribute "CDS_SEC" "1"
					( Origin gPackager )
				)
				( attribute "SEC" "1"
					( Origin gPackager )
				)
				( objectStatus "R25W42" )
				( pin "\1\"
					( attribute "PN" "1"
						( Origin gPackager )
					)
					( objectStatus "R25W42.1" )
				)
				( pin "\2\"
					( attribute "PN" "2"
						( Origin gPackager )
					)
					( objectStatus "R25W42.2" )
				)
			)
			( gate "@baseboard_fab2_lib.baseboard_fab2(sch_1):page149_i202"
				( attribute "CDS_LIB" "w_hdl"
					( Origin gPackager )
				)
				( attribute "CDS_LMAN_SYM_OUTLINE" "-50,75,50,-75"
					( Origin gPackager )
				)
				( attribute "LOCATION" "R25W43"
					( Origin gFrontEnd )
				)
				( attribute "PACK_TYPE" "RCL_GP"
					( Origin gFrontEnd )
				)
				( attribute "PART_NUMBER" "64.12005.6DL"
					( Origin gFrontEnd )
				)
				( attribute "PHYS_PAGE" "149"
					( Origin gFrontEnd )
				)
				( attribute "ROT" "1"
					( Origin gFrontEnd )
				)
				( attribute "VALUE" "120R2F-GP"
					( Origin gFrontEnd )
				)
				( attribute "VER" "1"
					( Origin gFrontEnd )
				)
				( attribute "XY" "(-6150,3500)"
					( Origin gFrontEnd )
				)
				( attribute "CHIPS_PART_NAME" "120R2F-GP"
					( Origin gPackager )
				)
				( attribute "CDS_PART_NAME" "120R2F-GP_RCL_GP-120R2F-GP,64.A"
					( Origin gPackager )
				)
				( attribute "CDS_LOCATION" "R25W43"
					( Origin gPackager )
				)
				( attribute "CDS_SEC" "1"
					( Origin gPackager )
				)
				( attribute "SEC" "1"
					( Origin gPackager )
				)
				( objectStatus "R25W43" )
				( pin "\1\"
					( attribute "PN" "1"
						( Origin gPackager )
					)
					( objectStatus "R25W43.1" )
				)
				( pin "\2\"
					( attribute "PN" "2"
						( Origin gPackager )
					)
					( objectStatus "R25W43.2" )
				)
			)
			( gate "@baseboard_fab2_lib.baseboard_fab2(sch_1):page149_i203"
				( attribute "CDS_LIB" "w_hdl"
					( Origin gPackager )
				)
				( attribute "CDS_LMAN_SYM_OUTLINE" "-50,75,50,-75"
					( Origin gPackager )
				)
				( attribute "LOCATION" "R25W44"
					( Origin gFrontEnd )
				)
				( attribute "PACK_TYPE" "RCL_GP"
					( Origin gFrontEnd )
				)
				( attribute "PART_NUMBER" "64.12005.6DL"
					( Origin gFrontEnd )
				)
				( attribute "PHYS_PAGE" "149"
					( Origin gFrontEnd )
				)
				( attribute "ROT" "1"
					( Origin gFrontEnd )
				)
				( attribute "VALUE" "120R2F-GP"
					( Origin gFrontEnd )
				)
				( attribute "VER" "1"
					( Origin gFrontEnd )
				)
				( attribute "XY" "(-6150,3450)"
					( Origin gFrontEnd )
				)
				( attribute "CHIPS_PART_NAME" "120R2F-GP"
					( Origin gPackager )
				)
				( attribute "CDS_PART_NAME" "120R2F-GP_RCL_GP-120R2F-GP,64.A"
					( Origin gPackager )
				)
				( attribute "CDS_LOCATION" "R25W44"
					( Origin gPackager )
				)
				( attribute "CDS_SEC" "1"
					( Origin gPackager )
				)
				( attribute "SEC" "1"
					( Origin gPackager )
				)
				( objectStatus "R25W44" )
				( pin "\1\"
					( attribute "PN" "1"
						( Origin gPackager )
					)
					( objectStatus "R25W44.1" )
				)
				( pin "\2\"
					( attribute "PN" "2"
						( Origin gPackager )
					)
					( objectStatus "R25W44.2" )
				)
			)
			( gate "@baseboard_fab2_lib.baseboard_fab2(sch_1):page149_i204"
				( attribute "CDS_LIB" "w_hdl"
					( Origin gPackager )
				)
				( attribute "CDS_LMAN_SYM_OUTLINE" "-50,75,50,-75"
					( Origin gPackager )
				)
				( attribute "LOCATION" "R25W45"
					( Origin gFrontEnd )
				)
				( attribute "PACK_TYPE" "RCL_GP"
					( Origin gFrontEnd )
				)
				( attribute "PART_NUMBER" "64.12005.6DL"
					( Origin gFrontEnd )
				)
				( attribute "PHYS_PAGE" "149"
					( Origin gFrontEnd )
				)
				( attribute "ROT" "1"
					( Origin gFrontEnd )
				)
				( attribute "VALUE" "120R2F-GP"
					( Origin gFrontEnd )
				)
				( attribute "VER" "1"
					( Origin gFrontEnd )
				)
				( attribute "XY" "(-6150,3400)"
					( Origin gFrontEnd )
				)
				( attribute "CHIPS_PART_NAME" "120R2F-GP"
					( Origin gPackager )
				)
				( attribute "CDS_PART_NAME" "120R2F-GP_RCL_GP-120R2F-GP,64.A"
					( Origin gPackager )
				)
				( attribute "CDS_LOCATION" "R25W45"
					( Origin gPackager )
				)
				( attribute "CDS_SEC" "1"
					( Origin gPackager )
				)
				( attribute "SEC" "1"
					( Origin gPackager )
				)
				( objectStatus "R25W45" )
				( pin "\1\"
					( attribute "PN" "1"
						( Origin gPackager )
					)
					( objectStatus "R25W45.1" )
				)
				( pin "\2\"
					( attribute "PN" "2"
						( Origin gPackager )
					)
					( objectStatus "R25W45.2" )
				)
			)
			( gate "@baseboard_fab2_lib.baseboard_fab2(sch_1):page149_i205"
				( attribute "CDS_LIB" "w_hdl"
					( Origin gPackager )
				)
				( attribute "CDS_LMAN_SYM_OUTLINE" "-50,75,50,-75"
					( Origin gPackager )
				)
				( attribute "LOCATION" "R25W46"
					( Origin gFrontEnd )
				)
				( attribute "PACK_TYPE" "RCL_GP"
					( Origin gFrontEnd )
				)
				( attribute "PART_NUMBER" "64.12005.6DL"
					( Origin gFrontEnd )
				)
				( attribute "PHYS_PAGE" "149"
					( Origin gFrontEnd )
				)
				( attribute "ROT" "1"
					( Origin gFrontEnd )
				)
				( attribute "VALUE" "120R2F-GP"
					( Origin gFrontEnd )
				)
				( attribute "VER" "1"
					( Origin gFrontEnd )
				)
				( attribute "XY" "(-6150,3350)"
					( Origin gFrontEnd )
				)
				( attribute "CHIPS_PART_NAME" "120R2F-GP"
					( Origin gPackager )
				)
				( attribute "CDS_PART_NAME" "120R2F-GP_RCL_GP-120R2F-GP,64.A"
					( Origin gPackager )
				)
				( attribute "CDS_LOCATION" "R25W46"
					( Origin gPackager )
				)
				( attribute "CDS_SEC" "1"
					( Origin gPackager )
				)
				( attribute "SEC" "1"
					( Origin gPackager )
				)
				( objectStatus "R25W46" )
				( pin "\1\"
					( attribute "PN" "1"
						( Origin gPackager )
					)
					( objectStatus "R25W46.1" )
				)
				( pin "\2\"
					( attribute "PN" "2"
						( Origin gPackager )
					)
					( objectStatus "R25W46.2" )
				)
			)
			( gate "@baseboard_fab2_lib.baseboard_fab2(sch_1):page149_i206"
				( attribute "CDS_LIB" "w_hdl"
					( Origin gPackager )
				)
				( attribute "CDS_LMAN_SYM_OUTLINE" "-50,75,50,-75"
					( Origin gPackager )
				)
				( attribute "LOCATION" "R25W47"
					( Origin gFrontEnd )
				)
				( attribute "PACK_TYPE" "RCL_GP"
					( Origin gFrontEnd )
				)
				( attribute "PART_NUMBER" "64.12005.6DL"
					( Origin gFrontEnd )
				)
				( attribute "PHYS_PAGE" "149"
					( Origin gFrontEnd )
				)
				( attribute "ROT" "1"
					( Origin gFrontEnd )
				)
				( attribute "VALUE" "120R2F-GP"
					( Origin gFrontEnd )
				)
				( attribute "VER" "1"
					( Origin gFrontEnd )
				)
				( attribute "XY" "(-6150,3300)"
					( Origin gFrontEnd )
				)
				( attribute "CHIPS_PART_NAME" "120R2F-GP"
					( Origin gPackager )
				)
				( attribute "CDS_PART_NAME" "120R2F-GP_RCL_GP-120R2F-GP,64.A"
					( Origin gPackager )
				)
				( attribute "CDS_LOCATION" "R25W47"
					( Origin gPackager )
				)
				( attribute "CDS_SEC" "1"
					( Origin gPackager )
				)
				( attribute "SEC" "1"
					( Origin gPackager )
				)
				( objectStatus "R25W47" )
				( pin "\1\"
					( attribute "PN" "1"
						( Origin gPackager )
					)
					( objectStatus "R25W47.1" )
				)
				( pin "\2\"
					( attribute "PN" "2"
						( Origin gPackager )
					)
					( objectStatus "R25W47.2" )
				)
			)
			( gate "@baseboard_fab2_lib.baseboard_fab2(sch_1):page149_i207"
				( attribute "CDS_LIB" "w_hdl"
					( Origin gPackager )
				)
				( attribute "CDS_LMAN_SYM_OUTLINE" "-50,75,50,-75"
					( Origin gPackager )
				)
				( attribute "LOCATION" "R25W48"
					( Origin gFrontEnd )
				)
				( attribute "PACK_TYPE" "RCL_GP"
					( Origin gFrontEnd )
				)
				( attribute "PART_NUMBER" "64.12005.6DL"
					( Origin gFrontEnd )
				)
				( attribute "PHYS_PAGE" "149"
					( Origin gFrontEnd )
				)
				( attribute "ROT" "1"
					( Origin gFrontEnd )
				)
				( attribute "VALUE" "120R2F-GP"
					( Origin gFrontEnd )
				)
				( attribute "VER" "1"
					( Origin gFrontEnd )
				)
				( attribute "XY" "(-6150,3250)"
					( Origin gFrontEnd )
				)
				( attribute "CHIPS_PART_NAME" "120R2F-GP"
					( Origin gPackager )
				)
				( attribute "CDS_PART_NAME" "120R2F-GP_RCL_GP-120R2F-GP,64.A"
					( Origin gPackager )
				)
				( attribute "CDS_LOCATION" "R25W48"
					( Origin gPackager )
				)
				( attribute "CDS_SEC" "1"
					( Origin gPackager )
				)
				( attribute "SEC" "1"
					( Origin gPackager )
				)
				( objectStatus "R25W48" )
				( pin "\1\"
					( attribute "PN" "1"
						( Origin gPackager )
					)
					( objectStatus "R25W48.1" )
				)
				( pin "\2\"
					( attribute "PN" "2"
						( Origin gPackager )
					)
					( objectStatus "R25W48.2" )
				)
			)
			( gate "@baseboard_fab2_lib.baseboard_fab2(sch_1):page149_i208"
				( attribute "CDS_LIB" "w_hdl"
					( Origin gPackager )
				)
				( attribute "CDS_LMAN_SYM_OUTLINE" "-50,75,50,-75"
					( Origin gPackager )
				)
				( attribute "LOCATION" "R25W49"
					( Origin gFrontEnd )
				)
				( attribute "PACK_TYPE" "RCL_GP"
					( Origin gFrontEnd )
				)
				( attribute "PART_NUMBER" "64.12005.6DL"
					( Origin gFrontEnd )
				)
				( attribute "PHYS_PAGE" "149"
					( Origin gFrontEnd )
				)
				( attribute "ROT" "1"
					( Origin gFrontEnd )
				)
				( attribute "VALUE" "120R2F-GP"
					( Origin gFrontEnd )
				)
				( attribute "VER" "1"
					( Origin gFrontEnd )
				)
				( attribute "XY" "(-6150,3200)"
					( Origin gFrontEnd )
				)
				( attribute "CHIPS_PART_NAME" "120R2F-GP"
					( Origin gPackager )
				)
				( attribute "CDS_PART_NAME" "120R2F-GP_RCL_GP-120R2F-GP,64.A"
					( Origin gPackager )
				)
				( attribute "CDS_LOCATION" "R25W49"
					( Origin gPackager )
				)
				( attribute "CDS_SEC" "1"
					( Origin gPackager )
				)
				( attribute "SEC" "1"
					( Origin gPackager )
				)
				( objectStatus "R25W49" )
				( pin "\1\"
					( attribute "PN" "1"
						( Origin gPackager )
					)
					( objectStatus "R25W49.1" )
				)
				( pin "\2\"
					( attribute "PN" "2"
						( Origin gPackager )
					)
					( objectStatus "R25W49.2" )
				)
			)
			( gate "@baseboard_fab2_lib.baseboard_fab2(sch_1):page149_i209"
				( attribute "CDS_LIB" "w_hdl"
					( Origin gPackager )
				)
				( attribute "CDS_LMAN_SYM_OUTLINE" "-50,75,50,-75"
					( Origin gPackager )
				)
				( attribute "LOCATION" "R25W50"
					( Origin gFrontEnd )
				)
				( attribute "PACK_TYPE" "RCL_GP"
					( Origin gFrontEnd )
				)
				( attribute "PART_NUMBER" "64.12005.6DL"
					( Origin gFrontEnd )
				)
				( attribute "PHYS_PAGE" "149"
					( Origin gFrontEnd )
				)
				( attribute "ROT" "1"
					( Origin gFrontEnd )
				)
				( attribute "VALUE" "120R2F-GP"
					( Origin gFrontEnd )
				)
				( attribute "VER" "1"
					( Origin gFrontEnd )
				)
				( attribute "XY" "(-6150,3150)"
					( Origin gFrontEnd )
				)
				( attribute "CHIPS_PART_NAME" "120R2F-GP"
					( Origin gPackager )
				)
				( attribute "CDS_PART_NAME" "120R2F-GP_RCL_GP-120R2F-GP,64.A"
					( Origin gPackager )
				)
				( attribute "CDS_LOCATION" "R25W50"
					( Origin gPackager )
				)
				( attribute "CDS_SEC" "1"
					( Origin gPackager )
				)
				( attribute "SEC" "1"
					( Origin gPackager )
				)
				( objectStatus "R25W50" )
				( pin "\1\"
					( attribute "PN" "1"
						( Origin gPackager )
					)
					( objectStatus "R25W50.1" )
				)
				( pin "\2\"
					( attribute "PN" "2"
						( Origin gPackager )
					)
					( objectStatus "R25W50.2" )
				)
			)
			( gate "@baseboard_fab2_lib.baseboard_fab2(sch_1):page149_i210"
				( attribute "CDS_LIB" "w_hdl"
					( Origin gPackager )
				)
				( attribute "CDS_LMAN_SYM_OUTLINE" "-50,75,50,-75"
					( Origin gPackager )
				)
				( attribute "LOCATION" "R25W51"
					( Origin gFrontEnd )
				)
				( attribute "PACK_TYPE" "RCL_GP"
					( Origin gFrontEnd )
				)
				( attribute "PART_NUMBER" "64.12005.6DL"
					( Origin gFrontEnd )
				)
				( attribute "PHYS_PAGE" "149"
					( Origin gFrontEnd )
				)
				( attribute "ROT" "1"
					( Origin gFrontEnd )
				)
				( attribute "VALUE" "120R2F-GP"
					( Origin gFrontEnd )
				)
				( attribute "VER" "1"
					( Origin gFrontEnd )
				)
				( attribute "XY" "(-6150,3100)"
					( Origin gFrontEnd )
				)
				( attribute "CHIPS_PART_NAME" "120R2F-GP"
					( Origin gPackager )
				)
				( attribute "CDS_PART_NAME" "120R2F-GP_RCL_GP-120R2F-GP,64.A"
					( Origin gPackager )
				)
				( attribute "CDS_LOCATION" "R25W51"
					( Origin gPackager )
				)
				( attribute "CDS_SEC" "1"
					( Origin gPackager )
				)
				( attribute "SEC" "1"
					( Origin gPackager )
				)
				( objectStatus "R25W51" )
				( pin "\1\"
					( attribute "PN" "1"
						( Origin gPackager )
					)
					( objectStatus "R25W51.1" )
				)
				( pin "\2\"
					( attribute "PN" "2"
						( Origin gPackager )
					)
					( objectStatus "R25W51.2" )
				)
			)
			( gate "@baseboard_fab2_lib.baseboard_fab2(sch_1):page149_i161"
				( attribute "CDS_LIB" "w_hdl"
					( Origin gPackager )
				)
				( attribute "CDS_LMAN_SYM_OUTLINE" "-50,75,50,-75"
					( Origin gPackager )
				)
				( attribute "LOCATION" "R25W2"
					( Origin gFrontEnd )
				)
				( attribute "PACK_TYPE" "RCL_GP"
					( Origin gFrontEnd )
				)
				( attribute "PART_NUMBER" "64.12005.6DL"
					( Origin gFrontEnd )
				)
				( attribute "PHYS_PAGE" "149"
					( Origin gFrontEnd )
				)
				( attribute "ROT" "1"
					( Origin gFrontEnd )
				)
				( attribute "VALUE" "120R2F-GP"
					( Origin gFrontEnd )
				)
				( attribute "VER" "1"
					( Origin gFrontEnd )
				)
				( attribute "XY" "(-7525,4250)"
					( Origin gFrontEnd )
				)
				( attribute "CHIPS_PART_NAME" "120R2F-GP"
					( Origin gPackager )
				)
				( attribute "CDS_PART_NAME" "120R2F-GP_RCL_GP-120R2F-GP,64.A"
					( Origin gPackager )
				)
				( attribute "CDS_LOCATION" "R25W2"
					( Origin gPackager )
				)
				( attribute "CDS_SEC" "1"
					( Origin gPackager )
				)
				( attribute "SEC" "1"
					( Origin gPackager )
				)
				( objectStatus "R25W2" )
				( pin "\1\"
					( attribute "PN" "1"
						( Origin gPackager )
					)
					( objectStatus "R25W2.1" )
				)
				( pin "\2\"
					( attribute "PN" "2"
						( Origin gPackager )
					)
					( objectStatus "R25W2.2" )
				)
			)
			( gate "@baseboard_fab2_lib.baseboard_fab2(sch_1):page149_i126"
				( attribute "BOM_COST" "SM_MEM"
					( Origin gFrontEnd )
				)
				( attribute "CDS_LIB" "mstr_discrete"
					( Origin gPackager )
				)
				( attribute "CDS_LOCATION" "C25W12"
					( Origin gPackager )
				)
				( attribute "CDS_SEC" "1"
					( Origin gPackager )
				)
				( attribute "LOCATION" "C25W12"
					( Origin gFrontEnd )
				)
				( attribute "MATERIAL" "X6S"
					( Origin gFrontEnd )
				)
				( attribute "PACK_TYPE" "0402"
					( Origin gFrontEnd )
				)
				( attribute "PART_NUMBER" "D97712-004"
					( Origin gFrontEnd )
				)
				( attribute "PHYS_PAGE" "149"
					( Origin gFrontEnd )
				)
				( attribute "ROOM" "BMC_MEMORY"
					( Origin gFrontEnd )
				)
				( attribute "ROT" "0"
					( Origin gFrontEnd )
				)
				( attribute "SEC" "1"
					( Origin gFrontEnd )
				)
				( attribute "SEC_TYPE" "0402"
					( Origin gFrontEnd )
				)
				( attribute "TOLERANCE" "10%"
					( Origin gFrontEnd )
				)
				( attribute "VALUE" "1.0UF"
					( Origin gFrontEnd )
				)
				( attribute "VER" "1"
					( Origin gFrontEnd )
				)
				( attribute "VOLTAGE" "6.3V"
					( Units "uVoltage" "V" 1.000000)
					( Origin gFrontEnd )
				)
				( attribute "XY" "(-6450,625)"
					( Origin gFrontEnd )
				)
				( attribute "CHIPS_PART_NAME" "CAP"
					( Origin gPackager )
				)
				( attribute "CDS_PART_NAME" "CAP_0402-1.0UF,6.3V,10%,X6S,D9A"
					( Origin gPackager )
				)
				( objectStatus "C25W12" )
				( pin "a"
					( attribute "PN" "1"
						( Origin gPackager )
					)
					( objectStatus "C25W12.1" )
				)
				( pin "b"
					( attribute "PN" "2"
						( Origin gPackager )
					)
					( objectStatus "C25W12.2" )
				)
			)
			( gate "@baseboard_fab2_lib.baseboard_fab2(sch_1):page149_i125"
				( attribute "BOM_COST" "SM_MEM"
					( Origin gFrontEnd )
				)
				( attribute "CDS_LIB" "mstr_discrete"
					( Origin gPackager )
				)
				( attribute "LOCATION" "R1T29"
					( Origin gFrontEnd )
				)
				( attribute "MATERIAL" "CHIP"
					( Origin gFrontEnd )
				)
				( attribute "PACK_TYPE" "0402"
					( Origin gFrontEnd )
				)
				( attribute "PART_NUMBER" "G21796-026"
					( Origin gFrontEnd )
				)
				( attribute "PHYS_PAGE" "149"
					( Origin gFrontEnd )
				)
				( attribute "ROOM" "BMC_MEMORY"
					( Origin gFrontEnd )
				)
				( attribute "ROT" "0"
					( Origin gFrontEnd )
				)
				( attribute "SEC" "1"
					( Origin gFrontEnd )
				)
				( attribute "SEC_TYPE" "0402"
					( Origin gFrontEnd )
				)
				( attribute "TOLERANCE" "1%"
					( Origin gFrontEnd )
				)
				( attribute "VALUE" "1.00K"
					( Origin gFrontEnd )
				)
				( attribute "VER" "2"
					( Origin gFrontEnd )
				)
				( attribute "WATTAGE" "1/16W"
					( Origin gFrontEnd )
				)
				( attribute "XY" "(-6175,625)"
					( Origin gFrontEnd )
				)
				( attribute "CHIPS_PART_NAME" "RES"
					( Origin gPackager )
				)
				( attribute "CDS_PART_NAME" "RES_0402-1.00K,1%,1/16W,CHIP,GA"
					( Origin gPackager )
				)
				( attribute "CDS_LOCATION" "R1T29"
					( Origin gPackager )
				)
				( attribute "CDS_SEC" "1"
					( Origin gPackager )
				)
				( objectStatus "R1T29" )
				( pin "a"
					( attribute "PN" "1"
						( Origin gPackager )
					)
					( objectStatus "R1T29.1" )
				)
				( pin "b"
					( attribute "PN" "2"
						( Origin gPackager )
					)
					( objectStatus "R1T29.2" )
				)
			)
			( gate "@baseboard_fab2_lib.baseboard_fab2(sch_1):page149_i124"
				( attribute "BOM_COST" "SM_MEM"
					( Origin gFrontEnd )
				)
				( attribute "CDS_LIB" "mstr_discrete"
					( Origin gPackager )
				)
				( attribute "LOCATION" "R1T30"
					( Origin gFrontEnd )
				)
				( attribute "MATERIAL" "CHIP"
					( Origin gFrontEnd )
				)
				( attribute "PACK_TYPE" "0402"
					( Origin gFrontEnd )
				)
				( attribute "PART_NUMBER" "G21796-026"
					( Origin gFrontEnd )
				)
				( attribute "PHYS_PAGE" "149"
					( Origin gFrontEnd )
				)
				( attribute "ROOM" "BMC_MEMORY"
					( Origin gFrontEnd )
				)
				( attribute "ROT" "0"
					( Origin gFrontEnd )
				)
				( attribute "SEC" "1"
					( Origin gFrontEnd )
				)
				( attribute "SEC_TYPE" "0402"
					( Origin gFrontEnd )
				)
				( attribute "TOLERANCE" "1%"
					( Origin gFrontEnd )
				)
				( attribute "VALUE" "1.00K"
					( Origin gFrontEnd )
				)
				( attribute "VER" "2"
					( Origin gFrontEnd )
				)
				( attribute "WATTAGE" "1/16W"
					( Origin gFrontEnd )
				)
				( attribute "XY" "(-6175,1050)"
					( Origin gFrontEnd )
				)
				( attribute "CHIPS_PART_NAME" "RES"
					( Origin gPackager )
				)
				( attribute "CDS_PART_NAME" "RES_0402-1.00K,1%,1/16W,CHIP,GA"
					( Origin gPackager )
				)
				( attribute "CDS_LOCATION" "R1T30"
					( Origin gPackager )
				)
				( attribute "CDS_SEC" "1"
					( Origin gPackager )
				)
				( objectStatus "R1T30" )
				( pin "a"
					( attribute "PN" "1"
						( Origin gPackager )
					)
					( objectStatus "R1T30.1" )
				)
				( pin "b"
					( attribute "PN" "2"
						( Origin gPackager )
					)
					( objectStatus "R1T30.2" )
				)
			)
			( gate "@baseboard_fab2_lib.baseboard_fab2(sch_1):page149_i122"
				( attribute "BOM_COST" "MIO_BIOS_MEM"
					( Origin gFrontEnd )
				)
				( attribute "CDS_LIB" "mstr_discrete"
					( Origin gPackager )
				)
				( attribute "LOCATION" "R25W118"
					( Origin gFrontEnd )
				)
				( attribute "MATERIAL" "EMPTY"
					( Origin gFrontEnd )
				)
				( attribute "NO_XNET_CONNECTION" "1"
					( Origin gFrontEnd )
				)
				( attribute "PACK_TYPE" "0402"
					( Origin gFrontEnd )
				)
				( attribute "PART_NUMBER" "G21796-072"
					( Origin gFrontEnd )
				)
				( attribute "PHYS_PAGE" "149"
					( Origin gFrontEnd )
				)
				( attribute "ROOM" "SB_SPI"
					( Origin gFrontEnd )
				)
				( attribute "ROT" "2"
					( Origin gFrontEnd )
				)
				( attribute "TOLERANCE" "1%"
					( Origin gFrontEnd )
				)
				( attribute "VALUE" "4.75K"
					( Origin gFrontEnd )
				)
				( attribute "VER" "2"
					( Origin gFrontEnd )
				)
				( attribute "WATTAGE" "1/16W"
					( Origin gFrontEnd )
				)
				( attribute "XY" "(-4675,750)"
					( Origin gFrontEnd )
				)
				( attribute "CHIPS_PART_NAME" "RES"
					( Origin gPackager )
				)
				( attribute "CDS_PART_NAME" "RES_0402-4.75K,1%,1/16W,EMPTY,A"
					( Origin gPackager )
				)
				( attribute "CDS_LOCATION" "R25W118"
					( Origin gPackager )
				)
				( attribute "CDS_SEC" "1"
					( Origin gPackager )
				)
				( attribute "SEC" "1"
					( Origin gPackager )
				)
				( objectStatus "R25W118" )
				( pin "a"
					( attribute "PN" "1"
						( Origin gPackager )
					)
					( objectStatus "R25W118.1" )
				)
				( pin "b"
					( attribute "PN" "2"
						( Origin gPackager )
					)
					( objectStatus "R25W118.2" )
				)
			)
			( gate "@baseboard_fab2_lib.baseboard_fab2(sch_1):page149_i120"
				( attribute "BOM_COST" "MIO_BIOS_MEM"
					( Origin gFrontEnd )
				)
				( attribute "CDS_LIB" "mstr_discrete"
					( Origin gPackager )
				)
				( attribute "LOCATION" "R25W119"
					( Origin gFrontEnd )
				)
				( attribute "MATERIAL" "CHIP"
					( Origin gFrontEnd )
				)
				( attribute "NO_XNET_CONNECTION" "1"
					( Origin gFrontEnd )
				)
				( attribute "PACK_TYPE" "0402"
					( Origin gFrontEnd )
				)
				( attribute "PART_NUMBER" "G21796-072"
					( Origin gFrontEnd )
				)
				( attribute "PHYS_PAGE" "149"
					( Origin gFrontEnd )
				)
				( attribute "ROOM" "SB_SPI"
					( Origin gFrontEnd )
				)
				( attribute "ROT" "2"
					( Origin gFrontEnd )
				)
				( attribute "TOLERANCE" "1%"
					( Origin gFrontEnd )
				)
				( attribute "VALUE" "4.75K"
					( Origin gFrontEnd )
				)
				( attribute "VER" "2"
					( Origin gFrontEnd )
				)
				( attribute "WATTAGE" "1/16W"
					( Origin gFrontEnd )
				)
				( attribute "XY" "(-4675,1100)"
					( Origin gFrontEnd )
				)
				( attribute "CHIPS_PART_NAME" "RES"
					( Origin gPackager )
				)
				( attribute "CDS_PART_NAME" "RES_0402-4.75K,1%,1/16W,CHIP,GA"
					( Origin gPackager )
				)
				( attribute "CDS_LOCATION" "R25W119"
					( Origin gPackager )
				)
				( attribute "CDS_SEC" "1"
					( Origin gPackager )
				)
				( attribute "SEC" "1"
					( Origin gPackager )
				)
				( objectStatus "R25W119" )
				( pin "a"
					( attribute "PN" "1"
						( Origin gPackager )
					)
					( objectStatus "R25W119.1" )
				)
				( pin "b"
					( attribute "PN" "2"
						( Origin gPackager )
					)
					( objectStatus "R25W119.2" )
				)
			)
			( gate "@baseboard_fab2_lib.baseboard_fab2(sch_1):page149_i113"
				( attribute "BOM_COST" "SM_CONTROLLER"
					( Origin gFrontEnd )
				)
				( attribute "CDS_LIB" "mstr_discrete"
					( Origin gPackager )
				)
				( attribute "CDS_LOCATION" "Q9E1"
					( Origin gPackager )
				)
				( attribute "CDS_SEC" "1"
					( Origin gPackager )
				)
				( attribute "LOCATION" "Q9E1"
					( Origin gFrontEnd )
				)
				( attribute "MATERIAL" "FET"
					( Origin gFrontEnd )
				)
				( attribute "PACK_TYPE" "SMLF"
					( Origin gFrontEnd )
				)
				( attribute "PART_NUMBER" "E40049-001"
					( Origin gFrontEnd )
				)
				( attribute "PHYS_PAGE" "149"
					( Origin gFrontEnd )
				)
				( attribute "ROOM" "BMC"
					( Origin gFrontEnd )
				)
				( attribute "ROT" "0"
					( Origin gFrontEnd )
				)
				( attribute "SEC" "1"
					( Origin gFrontEnd )
				)
				( attribute "SEC_TYPE" "SMLF"
					( Origin gFrontEnd )
				)
				( attribute "VALUE" "NTJD4001N"
					( Origin gFrontEnd )
				)
				( attribute "VER" "5"
					( Origin gFrontEnd )
				)
				( attribute "XY" "(-6200,1825)"
					( Origin gFrontEnd )
				)
				( attribute "CHIPS_PART_NAME" "FET_N_DUAL"
					( Origin gPackager )
				)
				( attribute "CDS_PART_NAME" "FET_N_DUAL_SMLF-NTJD4001N,FET,A"
					( Origin gPackager )
				)
				( objectStatus "Q9E1" )
				( pin "drain(0)"
					( attribute "PN" "6"
						( Origin gPackager )
					)
					( objectStatus "Q9E1.6" )
				)
				( pin "gate(0)"
					( attribute "PN" "2"
						( Origin gPackager )
					)
					( objectStatus "Q9E1.2" )
				)
				( pin "source(0)"
					( attribute "PN" "1"
						( Origin gPackager )
					)
					( objectStatus "Q9E1.1" )
				)
			)
			( gate "@baseboard_fab2_lib.baseboard_fab2(sch_1):page149_i111"
				( attribute "BOM_COST" "SM_CONTROLLER"
					( Origin gFrontEnd )
				)
				( attribute "CDS_LIB" "mstr_discrete"
					( Origin gPackager )
				)
				( attribute "CDS_LOCATION" "R9E21"
					( Origin gPackager )
				)
				( attribute "CDS_SEC" "1"
					( Origin gPackager )
				)
				( attribute "LOCATION" "R9E21"
					( Origin gFrontEnd )
				)
				( attribute "MATERIAL" "CHIP"
					( Origin gFrontEnd )
				)
				( attribute "PACK_TYPE" "0402"
					( Origin gFrontEnd )
				)
				( attribute "PART_NUMBER" "G21796-072"
					( Origin gFrontEnd )
				)
				( attribute "PHYS_PAGE" "149"
					( Origin gFrontEnd )
				)
				( attribute "ROOM" "BMC"
					( Origin gFrontEnd )
				)
				( attribute "ROT" "0"
					( Origin gFrontEnd )
				)
				( attribute "SEC" "1"
					( Origin gFrontEnd )
				)
				( attribute "SEC_TYPE" "0402"
					( Origin gFrontEnd )
				)
				( attribute "TOLERANCE" "1%"
					( Origin gFrontEnd )
				)
				( attribute "VALUE" "4.75K"
					( Origin gFrontEnd )
				)
				( attribute "VER" "2"
					( Origin gFrontEnd )
				)
				( attribute "WATTAGE" "1/16W"
					( Origin gFrontEnd )
				)
				( attribute "XY" "(-6200,2325)"
					( Origin gFrontEnd )
				)
				( attribute "CHIPS_PART_NAME" "RES"
					( Origin gPackager )
				)
				( attribute "CDS_PART_NAME" "RES_0402-4.75K,1%,1/16W,CHIP,GA"
					( Origin gPackager )
				)
				( objectStatus "R9E21" )
				( pin "a"
					( attribute "PN" "1"
						( Origin gPackager )
					)
					( objectStatus "R9E21.1" )
				)
				( pin "b"
					( attribute "PN" "2"
						( Origin gPackager )
					)
					( objectStatus "R9E21.2" )
				)
			)
			( gate "@baseboard_fab2_lib.baseboard_fab2(sch_1):page149_i109"
				( attribute "BOM_COST" "SM_CONTROLLER"
					( Origin gFrontEnd )
				)
				( attribute "CDS_LIB" "mstr_discrete"
					( Origin gPackager )
				)
				( attribute "CDS_LOCATION" "Q9E1"
					( Origin gPackager )
				)
				( attribute "CDS_SEC" "2"
					( Origin gPackager )
				)
				( attribute "LOCATION" "Q9E1"
					( Origin gFrontEnd )
				)
				( attribute "MATERIAL" "FET"
					( Origin gFrontEnd )
				)
				( attribute "PACK_TYPE" "SMLF"
					( Origin gFrontEnd )
				)
				( attribute "PART_NUMBER" "E40049-001"
					( Origin gFrontEnd )
				)
				( attribute "PHYS_PAGE" "149"
					( Origin gFrontEnd )
				)
				( attribute "ROOM" "BMC"
					( Origin gFrontEnd )
				)
				( attribute "ROT" "0"
					( Origin gFrontEnd )
				)
				( attribute "SEC" "2"
					( Origin gFrontEnd )
				)
				( attribute "SEC_TYPE" "SMLF"
					( Origin gFrontEnd )
				)
				( attribute "VALUE" "NTJD4001N"
					( Origin gFrontEnd )
				)
				( attribute "VER" "5"
					( Origin gFrontEnd )
				)
				( attribute "XY" "(-5600,2250)"
					( Origin gFrontEnd )
				)
				( attribute "CHIPS_PART_NAME" "FET_N_DUAL"
					( Origin gPackager )
				)
				( attribute "CDS_PART_NAME" "FET_N_DUAL_SMLF-NTJD4001N,FET,A"
					( Origin gPackager )
				)
				( objectStatus "Q9E1" )
				( pin "drain(0)"
					( attribute "PN" "3"
						( Origin gPackager )
					)
					( objectStatus "Q9E1.3" )
				)
				( pin "gate(0)"
					( attribute "PN" "5"
						( Origin gPackager )
					)
					( objectStatus "Q9E1.5" )
				)
				( pin "source(0)"
					( attribute "PN" "4"
						( Origin gPackager )
					)
					( objectStatus "Q9E1.4" )
				)
			)
			( gate "@baseboard_fab2_lib.baseboard_fab2(sch_1):page149_i212"
				( attribute "CDS_LIB" "w_hdl"
					( Origin gPackager )
				)
				( attribute "CDS_LMAN_SYM_OUTLINE" "-50,75,50,-75"
					( Origin gPackager )
				)
				( attribute "LOCATION" "R1T28"
					( Origin gFrontEnd )
				)
				( attribute "PACK_TYPE" "RCL_GP"
					( Origin gFrontEnd )
				)
				( attribute "PART_NUMBER" "64.12005.6DL"
					( Origin gFrontEnd )
				)
				( attribute "PHYS_PAGE" "149"
					( Origin gFrontEnd )
				)
				( attribute "ROT" "4"
					( Origin gFrontEnd )
				)
				( attribute "VALUE" "120R2F-GP"
					( Origin gFrontEnd )
				)
				( attribute "VER" "1"
					( Origin gFrontEnd )
				)
				( attribute "XY" "(-3550,775)"
					( Origin gFrontEnd )
				)
				( attribute "CHIPS_PART_NAME" "120R2F-GP"
					( Origin gPackager )
				)
				( attribute "CDS_PART_NAME" "120R2F-GP_RCL_GP-120R2F-GP,64.A"
					( Origin gPackager )
				)
				( attribute "CDS_LOCATION" "R1T28"
					( Origin gPackager )
				)
				( attribute "CDS_SEC" "1"
					( Origin gPackager )
				)
				( attribute "SEC" "1"
					( Origin gPackager )
				)
				( objectStatus "R1T28" )
				( pin "\1\"
					( attribute "PN" "1"
						( Origin gPackager )
					)
					( objectStatus "R1T28.1" )
				)
				( pin "\2\"
					( attribute "PN" "2"
						( Origin gPackager )
					)
					( objectStatus "R1T28.2" )
				)
			)
			( gate "@baseboard_fab2_lib.baseboard_fab2(sch_1):page146_i96"
				( attribute "BOM_COST" "SM_CONTROLLER"
					( Origin gFrontEnd )
				)
				( attribute "CDS_LIB" "mstr_discrete"
					( Origin gPackager )
				)
				( attribute "CDS_LOCATION" "R2T41"
					( Origin gPackager )
				)
				( attribute "CDS_SEC" "1"
					( Origin gPackager )
				)
				( attribute "LOCATION" "R2T41"
					( Origin gFrontEnd )
				)
				( attribute "MATERIAL" "CHIP"
					( Origin gFrontEnd )
				)
				( attribute "PACK_TYPE" "0402"
					( Origin gFrontEnd )
				)
				( attribute "PART_NUMBER" "G21796-250"
					( Origin gFrontEnd )
				)
				( attribute "PHYS_PAGE" "146"
					( Origin gFrontEnd )
				)
				( attribute "ROOM" "BMC"
					( Origin gFrontEnd )
				)
				( attribute "ROT" "0"
					( Origin gFrontEnd )
				)
				( attribute "SEC" "1"
					( Origin gFrontEnd )
				)
				( attribute "SEC_TYPE" "0402"
					( Origin gFrontEnd )
				)
				( attribute "TOLERANCE" "1.0%"
					( Origin gFrontEnd )
				)
				( attribute "VALUE" "22.1"
					( Origin gFrontEnd )
				)
				( attribute "VER" "1"
					( Origin gFrontEnd )
				)
				( attribute "WATTAGE" "1/16W"
					( Origin gFrontEnd )
				)
				( attribute "XY" "(-6625,3950)"
					( Origin gFrontEnd )
				)
				( attribute "CHIPS_PART_NAME" "RES"
					( Origin gPackager )
				)
				( attribute "CDS_PART_NAME" "RES_0402-22.1,1.0%,1/16W,CHIP,A"
					( Origin gPackager )
				)
				( objectStatus "R2T41" )
				( pin "a"
					( attribute "PN" "1"
						( Origin gPackager )
					)
					( objectStatus "R2T41.1" )
				)
				( pin "b"
					( attribute "PN" "2"
						( Origin gPackager )
					)
					( objectStatus "R2T41.2" )
				)
			)
			( gate "@baseboard_fab2_lib.baseboard_fab2(sch_1):page149_i98"
				( attribute "BOM_COST" "SM_CONTROLLER"
					( Origin gFrontEnd )
				)
				( attribute "CDS_LIB" "mstr_discrete"
					( Origin gPackager )
				)
				( attribute "CDS_LOCATION" "DS9E1"
					( Origin gPackager )
				)
				( attribute "CDS_SEC" "1"
					( Origin gPackager )
				)
				( attribute "COLOR" "GREEN"
					( Origin gFrontEnd )
				)
				( attribute "LOCATION" "DS9E1"
					( Origin gFrontEnd )
				)
				( attribute "MATERIAL" "IC"
					( Origin gFrontEnd )
				)
				( attribute "PACK_TYPE" "A1LF"
					( Origin gFrontEnd )
				)
				( attribute "PART_NUMBER" "C97278-010"
					( Origin gFrontEnd )
				)
				( attribute "PHYS_PAGE" "149"
					( Origin gFrontEnd )
				)
				( attribute "ROOM" "BMC"
					( Origin gFrontEnd )
				)
				( attribute "ROT" "0"
					( Origin gFrontEnd )
				)
				( attribute "SEC" "1"
					( Origin gFrontEnd )
				)
				( attribute "SEC_TYPE" "A1LF"
					( Origin gFrontEnd )
				)
				( attribute "VER" "3"
					( Origin gFrontEnd )
				)
				( attribute "XY" "(-5400,2625)"
					( Origin gFrontEnd )
				)
				( attribute "CHIPS_PART_NAME" "LED"
					( Origin gPackager )
				)
				( attribute "CDS_PART_NAME" "LED_A1LF-GREEN,IC,C97278-010"
					( Origin gPackager )
				)
				( objectStatus "DS9E1" )
				( pin "a"
					( attribute "PN" "1"
						( Origin gPackager )
					)
					( objectStatus "DS9E1.1" )
				)
				( pin "c"
					( attribute "PN" "2"
						( Origin gPackager )
					)
					( objectStatus "DS9E1.2" )
				)
			)
			( gate "@baseboard_fab2_lib.baseboard_fab2(sch_1):page149_i97"
				( attribute "CDS_LIB" "mstr_discrete"
					( Origin gPackager )
				)
				( attribute "LOCATION" "C25W6"
					( Origin gFrontEnd )
				)
				( attribute "MATERIAL" "X6S"
					( Origin gFrontEnd )
				)
				( attribute "PACK_TYPE" "0402"
					( Origin gFrontEnd )
				)
				( attribute "PART_NUMBER" "D97712-011"
					( Origin gFrontEnd )
				)
				( attribute "PHYS_PAGE" "149"
					( Origin gFrontEnd )
				)
				( attribute "ROOM" "VDDQ_KLM_PWR_VR"
					( Origin gFrontEnd )
				)
				( attribute "ROT" "1"
					( Origin gFrontEnd )
				)
				( attribute "TOLERANCE" "10%"
					( Origin gFrontEnd )
				)
				( attribute "VALUE" "1.0UF"
					( Origin gFrontEnd )
				)
				( attribute "VER" "1"
					( Origin gFrontEnd )
				)
				( attribute "VOLTAGE" "16V"
					( Units "uVoltage" "V" 1.000000)
					( Origin gFrontEnd )
				)
				( attribute "XY" "(-5300,3050)"
					( Origin gFrontEnd )
				)
				( attribute "CHIPS_PART_NAME" "CAP"
					( Origin gPackager )
				)
				( attribute "CDS_PART_NAME" "CAP_0402-1.0UF,16V,10%,X6S,D97A"
					( Origin gPackager )
				)
				( attribute "CDS_LOCATION" "C25W6"
					( Origin gPackager )
				)
				( attribute "CDS_SEC" "1"
					( Origin gPackager )
				)
				( attribute "SEC" "1"
					( Origin gPackager )
				)
				( objectStatus "C25W6" )
				( pin "a"
					( attribute "PN" "1"
						( Origin gPackager )
					)
					( objectStatus "C25W6.1" )
				)
				( pin "b"
					( attribute "PN" "2"
						( Origin gPackager )
					)
					( objectStatus "C25W6.2" )
				)
			)
			( gate "@baseboard_fab2_lib.baseboard_fab2(sch_1):page149_i96"
				( attribute "CDS_LIB" "mstr_discrete"
					( Origin gPackager )
				)
				( attribute "LOCATION" "C25W5"
					( Origin gFrontEnd )
				)
				( attribute "MATERIAL" "X6S"
					( Origin gFrontEnd )
				)
				( attribute "PACK_TYPE" "0402"
					( Origin gFrontEnd )
				)
				( attribute "PART_NUMBER" "D97712-011"
					( Origin gFrontEnd )
				)
				( attribute "PHYS_PAGE" "149"
					( Origin gFrontEnd )
				)
				( attribute "ROOM" "VDDQ_KLM_PWR_VR"
					( Origin gFrontEnd )
				)
				( attribute "ROT" "1"
					( Origin gFrontEnd )
				)
				( attribute "TOLERANCE" "10%"
					( Origin gFrontEnd )
				)
				( attribute "VALUE" "1.0UF"
					( Origin gFrontEnd )
				)
				( attribute "VER" "1"
					( Origin gFrontEnd )
				)
				( attribute "VOLTAGE" "16V"
					( Units "uVoltage" "V" 1.000000)
					( Origin gFrontEnd )
				)
				( attribute "XY" "(-5300,3300)"
					( Origin gFrontEnd )
				)
				( attribute "CHIPS_PART_NAME" "CAP"
					( Origin gPackager )
				)
				( attribute "CDS_PART_NAME" "CAP_0402-1.0UF,16V,10%,X6S,D97A"
					( Origin gPackager )
				)
				( attribute "CDS_LOCATION" "C25W5"
					( Origin gPackager )
				)
				( attribute "CDS_SEC" "1"
					( Origin gPackager )
				)
				( attribute "SEC" "1"
					( Origin gPackager )
				)
				( objectStatus "C25W5" )
				( pin "a"
					( attribute "PN" "1"
						( Origin gPackager )
					)
					( objectStatus "C25W5.1" )
				)
				( pin "b"
					( attribute "PN" "2"
						( Origin gPackager )
					)
					( objectStatus "C25W5.2" )
				)
			)
			( gate "@baseboard_fab2_lib.baseboard_fab2(sch_1):page149_i94"
				( attribute "BOM_COST" "SM_CONTROLLER"
					( Origin gFrontEnd )
				)
				( attribute "CDS_LIB" "mstr_discrete"
					( Origin gPackager )
				)
				( attribute "CDS_LOCATION" "R9E24"
					( Origin gPackager )
				)
				( attribute "CDS_SEC" "1"
					( Origin gPackager )
				)
				( attribute "LOCATION" "R9E24"
					( Origin gFrontEnd )
				)
				( attribute "MATERIAL" "CHIP"
					( Origin gFrontEnd )
				)
				( attribute "PACK_TYPE" "0402"
					( Origin gFrontEnd )
				)
				( attribute "PART_NUMBER" "G21796-271"
					( Origin gFrontEnd )
				)
				( attribute "PHYS_PAGE" "149"
					( Origin gFrontEnd )
				)
				( attribute "ROOM" "BMC"
					( Origin gFrontEnd )
				)
				( attribute "ROT" "0"
					( Origin gFrontEnd )
				)
				( attribute "SEC" "1"
					( Origin gFrontEnd )
				)
				( attribute "SEC_TYPE" "0402"
					( Origin gFrontEnd )
				)
				( attribute "TOLERANCE" "1.0%"
					( Origin gFrontEnd )
				)
				( attribute "VALUE" "221"
					( Origin gFrontEnd )
				)
				( attribute "VER" "1"
					( Origin gFrontEnd )
				)
				( attribute "WATTAGE" "1/16W"
					( Origin gFrontEnd )
				)
				( attribute "XY" "(-4800,2625)"
					( Origin gFrontEnd )
				)
				( attribute "CHIPS_PART_NAME" "RES"
					( Origin gPackager )
				)
				( attribute "CDS_PART_NAME" "RES_0402-221,1.0%,1/16W,CHIP,GA"
					( Origin gPackager )
				)
				( objectStatus "R9E24" )
				( pin "a"
					( attribute "PN" "1"
						( Origin gPackager )
					)
					( objectStatus "R9E24.1" )
				)
				( pin "b"
					( attribute "PN" "2"
						( Origin gPackager )
					)
					( objectStatus "R9E24.2" )
				)
			)
			( gate "@baseboard_fab2_lib.baseboard_fab2(sch_1):page147_i66"
				( attribute "CDS_LIB" "mstr_discrete"
					( Origin gPackager )
				)
				( attribute "CDS_LOCATION" "R1U5"
					( Origin gPackager )
				)
				( attribute "LOCATION" "R1U5"
					( Origin gFrontEnd )
				)
				( attribute "MATERIAL" "CHIP"
					( Origin gFrontEnd )
				)
				( attribute "PACK_TYPE" "0402"
					( Origin gFrontEnd )
				)
				( attribute "PART_NUMBER" "G21796-010"
					( Origin gFrontEnd )
				)
				( attribute "PHYS_PAGE" "147"
					( Origin gFrontEnd )
				)
				( attribute "ROT" "0"
					( Origin gFrontEnd )
				)
				( attribute "SEC" "1"
					( Origin gFrontEnd )
				)
				( attribute "SEC_TYPE" "0402"
					( Origin gFrontEnd )
				)
				( attribute "TOLERANCE" "1%"
					( Origin gFrontEnd )
				)
				( attribute "VALUE" "100.0K"
					( Origin gFrontEnd )
				)
				( attribute "VER" "2"
					( Origin gFrontEnd )
				)
				( attribute "WATTAGE" "1/16W"
					( Origin gFrontEnd )
				)
				( attribute "XY" "(-4275,1950)"
					( Origin gFrontEnd )
				)
				( attribute "CHIPS_PART_NAME" "RES"
					( Origin gPackager )
				)
				( attribute "CDS_PART_NAME" "RES_0402-100.0K,1%,1/16W,CHIP,A"
					( Origin gPackager )
				)
				( attribute "CDS_SEC" "1"
					( Origin gPackager )
				)
				( objectStatus "R1U5" )
				( pin "a"
					( attribute "PN" "1"
						( Origin gPackager )
					)
					( objectStatus "R1U5.1" )
				)
				( pin "b"
					( attribute "PN" "2"
						( Origin gPackager )
					)
					( objectStatus "R1U5.2" )
				)
			)
			( gate "@baseboard_fab2_lib.baseboard_fab2(sch_1):page147_i65"
				( attribute "CDS_LIB" "mstr_discrete"
					( Origin gPackager )
				)
				( attribute "CDS_LOCATION" "R1U4"
					( Origin gPackager )
				)
				( attribute "LOCATION" "R1U4"
					( Origin gFrontEnd )
				)
				( attribute "MATERIAL" "CHIP"
					( Origin gFrontEnd )
				)
				( attribute "PACK_TYPE" "0402"
					( Origin gFrontEnd )
				)
				( attribute "PART_NUMBER" "G21796-010"
					( Origin gFrontEnd )
				)
				( attribute "PHYS_PAGE" "147"
					( Origin gFrontEnd )
				)
				( attribute "ROT" "0"
					( Origin gFrontEnd )
				)
				( attribute "SEC" "1"
					( Origin gFrontEnd )
				)
				( attribute "SEC_TYPE" "0402"
					( Origin gFrontEnd )
				)
				( attribute "TOLERANCE" "1%"
					( Origin gFrontEnd )
				)
				( attribute "VALUE" "100.0K"
					( Origin gFrontEnd )
				)
				( attribute "VER" "2"
					( Origin gFrontEnd )
				)
				( attribute "WATTAGE" "1/16W"
					( Origin gFrontEnd )
				)
				( attribute "XY" "(-4025,1950)"
					( Origin gFrontEnd )
				)
				( attribute "CHIPS_PART_NAME" "RES"
					( Origin gPackager )
				)
				( attribute "CDS_PART_NAME" "RES_0402-100.0K,1%,1/16W,CHIP,A"
					( Origin gPackager )
				)
				( attribute "CDS_SEC" "1"
					( Origin gPackager )
				)
				( objectStatus "R1U4" )
				( pin "a"
					( attribute "PN" "1"
						( Origin gPackager )
					)
					( objectStatus "R1U4.1" )
				)
				( pin "b"
					( attribute "PN" "2"
						( Origin gPackager )
					)
					( objectStatus "R1U4.2" )
				)
			)
			( gate "@baseboard_fab2_lib.baseboard_fab2(sch_1):page147_i43"
				( attribute "BOM_COST" "SM_CONTROLLER"
					( Origin gFrontEnd )
				)
				( attribute "CDS_LIB" "mstr_discrete"
					( Origin gPackager )
				)
				( attribute "CDS_LOCATION" "R25W80"
					( Origin gPackager )
				)
				( attribute "LOCATION" "R25W80"
					( Origin gFrontEnd )
				)
				( attribute "MATERIAL" "CHIP"
					( Origin gFrontEnd )
				)
				( attribute "PACK_TYPE" "0402"
					( Origin gFrontEnd )
				)
				( attribute "PART_NUMBER" "G21796-016"
					( Origin gFrontEnd )
				)
				( attribute "PHYS_PAGE" "147"
					( Origin gFrontEnd )
				)
				( attribute "ROOM" "BMC"
					( Origin gFrontEnd )
				)
				( attribute "ROT" "0"
					( Origin gFrontEnd )
				)
				( attribute "SEC" "1"
					( Origin gFrontEnd )
				)
				( attribute "SEC_TYPE" "0402"
					( Origin gFrontEnd )
				)
				( attribute "TOLERANCE" "1%"
					( Origin gFrontEnd )
				)
				( attribute "VALUE" "10.0K"
					( Origin gFrontEnd )
				)
				( attribute "VER" "2"
					( Origin gFrontEnd )
				)
				( attribute "WATTAGE" "1/16W"
					( Origin gFrontEnd )
				)
				( attribute "XY" "(-3900,4800)"
					( Origin gFrontEnd )
				)
				( attribute "CHIPS_PART_NAME" "RES"
					( Origin gPackager )
				)
				( attribute "CDS_PART_NAME" "RES_0402-10.0K,1%,1/16W,CHIP,GA"
					( Origin gPackager )
				)
				( attribute "CDS_SEC" "1"
					( Origin gPackager )
				)
				( objectStatus "R25W80" )
				( pin "a"
					( attribute "PN" "1"
						( Origin gPackager )
					)
					( objectStatus "R25W80.1" )
				)
				( pin "b"
					( attribute "PN" "2"
						( Origin gPackager )
					)
					( objectStatus "R25W80.2" )
				)
			)
			( gate "@baseboard_fab2_lib.baseboard_fab2(sch_1):page147_i42"
				( attribute "BOM_COST" "SM_CONTROLLER"
					( Origin gFrontEnd )
				)
				( attribute "CDS_LIB" "mstr_discrete"
					( Origin gPackager )
				)
				( attribute "CDS_LOCATION" "R25W79"
					( Origin gPackager )
				)
				( attribute "LOCATION" "R25W79"
					( Origin gFrontEnd )
				)
				( attribute "MATERIAL" "CHIP"
					( Origin gFrontEnd )
				)
				( attribute "PACK_TYPE" "0402"
					( Origin gFrontEnd )
				)
				( attribute "PART_NUMBER" "G21796-016"
					( Origin gFrontEnd )
				)
				( attribute "PHYS_PAGE" "147"
					( Origin gFrontEnd )
				)
				( attribute "ROOM" "BMC"
					( Origin gFrontEnd )
				)
				( attribute "ROT" "0"
					( Origin gFrontEnd )
				)
				( attribute "SEC" "1"
					( Origin gFrontEnd )
				)
				( attribute "SEC_TYPE" "0402"
					( Origin gFrontEnd )
				)
				( attribute "TOLERANCE" "1%"
					( Origin gFrontEnd )
				)
				( attribute "VALUE" "10.0K"
					( Origin gFrontEnd )
				)
				( attribute "VER" "2"
					( Origin gFrontEnd )
				)
				( attribute "WATTAGE" "1/16W"
					( Origin gFrontEnd )
				)
				( attribute "XY" "(-3650,4800)"
					( Origin gFrontEnd )
				)
				( attribute "CHIPS_PART_NAME" "RES"
					( Origin gPackager )
				)
				( attribute "CDS_PART_NAME" "RES_0402-10.0K,1%,1/16W,CHIP,GA"
					( Origin gPackager )
				)
				( attribute "CDS_SEC" "1"
					( Origin gPackager )
				)
				( objectStatus "R25W79" )
				( pin "a"
					( attribute "PN" "1"
						( Origin gPackager )
					)
					( objectStatus "R25W79.1" )
				)
				( pin "b"
					( attribute "PN" "2"
						( Origin gPackager )
					)
					( objectStatus "R25W79.2" )
				)
			)
			( gate "@baseboard_fab2_lib.baseboard_fab2(sch_1):page147_i40"
				( attribute "BOM_COST" "SM_CONTROLLER"
					( Origin gFrontEnd )
				)
				( attribute "CDS_LIB" "mstr_discrete"
					( Origin gPackager )
				)
				( attribute "CDS_LOCATION" "R25W57"
					( Origin gPackager )
				)
				( attribute "CDS_SEC" "1"
					( Origin gPackager )
				)
				( attribute "LOCATION" "R25W57"
					( Origin gFrontEnd )
				)
				( attribute "MATERIAL" "CHIP"
					( Origin gFrontEnd )
				)
				( attribute "PACK_TYPE" "0402"
					( Origin gFrontEnd )
				)
				( attribute "PART_NUMBER" "G21796-344"
					( Origin gFrontEnd )
				)
				( attribute "PHYS_PAGE" "147"
					( Origin gFrontEnd )
				)
				( attribute "ROOM" "BMC"
					( Origin gFrontEnd )
				)
				( attribute "ROT" "6"
					( Origin gFrontEnd )
				)
				( attribute "SEC" "1"
					( Origin gFrontEnd )
				)
				( attribute "SEC_TYPE" "0402"
					( Origin gFrontEnd )
				)
				( attribute "TOLERANCE" "1%"
					( Origin gFrontEnd )
				)
				( attribute "VALUE" "2.7K"
					( Origin gFrontEnd )
				)
				( attribute "VER" "2"
					( Origin gFrontEnd )
				)
				( attribute "WATTAGE" "1/16W"
					( Origin gFrontEnd )
				)
				( attribute "XY" "(775,1925)"
					( Origin gFrontEnd )
				)
				( attribute "CHIPS_PART_NAME" "RES"
					( Origin gPackager )
				)
				( attribute "CDS_PART_NAME" "RES_0402-2.7K,1%,1/16W,CHIP,G2A"
					( Origin gPackager )
				)
				( objectStatus "R25W57" )
				( pin "a"
					( attribute "PN" "1"
						( Origin gPackager )
					)
					( objectStatus "R25W57.1" )
				)
				( pin "b"
					( attribute "PN" "2"
						( Origin gPackager )
					)
					( objectStatus "R25W57.2" )
				)
			)
			( gate "@baseboard_fab2_lib.baseboard_fab2(sch_1):page147_i39"
				( attribute "BOM_COST" "SM_CONTROLLER"
					( Origin gFrontEnd )
				)
				( attribute "CDS_LIB" "mstr_discrete"
					( Origin gPackager )
				)
				( attribute "CDS_LOCATION" "C25W9"
					( Origin gPackager )
				)
				( attribute "CDS_SEC" "1"
					( Origin gPackager )
				)
				( attribute "LOCATION" "C25W9"
					( Origin gFrontEnd )
				)
				( attribute "MATERIAL" "EMPTY"
					( Origin gFrontEnd )
				)
				( attribute "PACK_TYPE" "0402"
					( Origin gFrontEnd )
				)
				( attribute "PART_NUMBER" "A36096-030"
					( Origin gFrontEnd )
				)
				( attribute "PHYS_PAGE" "147"
					( Origin gFrontEnd )
				)
				( attribute "ROOM" "BMC"
					( Origin gFrontEnd )
				)
				( attribute "ROT" "1"
					( Origin gFrontEnd )
				)
				( attribute "SEC" "1"
					( Origin gFrontEnd )
				)
				( attribute "SEC_TYPE" "0402"
					( Origin gFrontEnd )
				)
				( attribute "TOLERANCE" "10%"
					( Origin gFrontEnd )
				)
				( attribute "VALUE" "0.1UF"
					( Origin gFrontEnd )
				)
				( attribute "VER" "2"
					( Origin gFrontEnd )
				)
				( attribute "VOLTAGE" "16V"
					( Units "uVoltage" "V" 1.000000)
					( Origin gFrontEnd )
				)
				( attribute "XY" "(1625,2125)"
					( Origin gFrontEnd )
				)
				( attribute "CHIPS_PART_NAME" "CAP"
					( Origin gPackager )
				)
				( attribute "CDS_PART_NAME" "CAP_0402-0.1UF,16V,10%,EMPTY,AA"
					( Origin gPackager )
				)
				( objectStatus "C25W9" )
				( pin "a"
					( attribute "PN" "1"
						( Origin gPackager )
					)
					( objectStatus "C25W9.1" )
				)
				( pin "b"
					( attribute "PN" "2"
						( Origin gPackager )
					)
					( objectStatus "C25W9.2" )
				)
			)
			( gate "@baseboard_fab2_lib.baseboard_fab2(sch_1):page147_i38"
				( attribute "BOM_COST" "SM_CONTROLLER"
					( Origin gFrontEnd )
				)
				( attribute "CDS_LIB" "mstr_discrete"
					( Origin gPackager )
				)
				( attribute "CDS_LOCATION" "C25W8"
					( Origin gPackager )
				)
				( attribute "CDS_SEC" "1"
					( Origin gPackager )
				)
				( attribute "LOCATION" "C25W8"
					( Origin gFrontEnd )
				)
				( attribute "MATERIAL" "EMPTY"
					( Origin gFrontEnd )
				)
				( attribute "PACK_TYPE" "0402"
					( Origin gFrontEnd )
				)
				( attribute "PART_NUMBER" "A36096-030"
					( Origin gFrontEnd )
				)
				( attribute "PHYS_PAGE" "147"
					( Origin gFrontEnd )
				)
				( attribute "ROOM" "BMC"
					( Origin gFrontEnd )
				)
				( attribute "ROT" "0"
					( Origin gFrontEnd )
				)
				( attribute "SEC" "1"
					( Origin gFrontEnd )
				)
				( attribute "SEC_TYPE" "0402"
					( Origin gFrontEnd )
				)
				( attribute "TOLERANCE" "10%"
					( Origin gFrontEnd )
				)
				( attribute "VALUE" "0.1UF"
					( Origin gFrontEnd )
				)
				( attribute "VER" "2"
					( Origin gFrontEnd )
				)
				( attribute "VOLTAGE" "16V"
					( Units "uVoltage" "V" 1.000000)
					( Origin gFrontEnd )
				)
				( attribute "XY" "(2000,1950)"
					( Origin gFrontEnd )
				)
				( attribute "CHIPS_PART_NAME" "CAP"
					( Origin gPackager )
				)
				( attribute "CDS_PART_NAME" "CAP_0402-0.1UF,16V,10%,EMPTY,AA"
					( Origin gPackager )
				)
				( objectStatus "C25W8" )
				( pin "a"
					( attribute "PN" "1"
						( Origin gPackager )
					)
					( objectStatus "C25W8.1" )
				)
				( pin "b"
					( attribute "PN" "2"
						( Origin gPackager )
					)
					( objectStatus "C25W8.2" )
				)
			)
			( gate "@baseboard_fab2_lib.baseboard_fab2(sch_1):page147_i25"
				( attribute "BOM_COST" "SM_CONTROLLER"
					( Origin gFrontEnd )
				)
				( attribute "CDS_LIB" "mstr_discrete"
					( Origin gPackager )
				)
				( attribute "CDS_LOCATION" "R25W87"
					( Origin gPackager )
				)
				( attribute "CDS_SEC" "1"
					( Origin gPackager )
				)
				( attribute "LOCATION" "R25W87"
					( Origin gFrontEnd )
				)
				( attribute "MATERIAL" "CHIP"
					( Origin gFrontEnd )
				)
				( attribute "PACK_TYPE" "0402"
					( Origin gFrontEnd )
				)
				( attribute "PART_NUMBER" "G21796-250"
					( Origin gFrontEnd )
				)
				( attribute "PHYS_PAGE" "147"
					( Origin gFrontEnd )
				)
				( attribute "ROOM" "BMC"
					( Origin gFrontEnd )
				)
				( attribute "ROT" "0"
					( Origin gFrontEnd )
				)
				( attribute "SEC" "1"
					( Origin gFrontEnd )
				)
				( attribute "SEC_TYPE" "0402"
					( Origin gFrontEnd )
				)
				( attribute "TOLERANCE" "1.0%"
					( Origin gFrontEnd )
				)
				( attribute "VALUE" "22.1"
					( Origin gFrontEnd )
				)
				( attribute "VER" "1"
					( Origin gFrontEnd )
				)
				( attribute "WATTAGE" "1/16W"
					( Origin gFrontEnd )
				)
				( attribute "XY" "(875,3800)"
					( Origin gFrontEnd )
				)
				( attribute "CHIPS_PART_NAME" "RES"
					( Origin gPackager )
				)
				( attribute "CDS_PART_NAME" "RES_0402-22.1,1.0%,1/16W,CHIP,A"
					( Origin gPackager )
				)
				( objectStatus "R25W87" )
				( pin "a"
					( attribute "PN" "1"
						( Origin gPackager )
					)
					( objectStatus "R25W87.1" )
				)
				( pin "b"
					( attribute "PN" "2"
						( Origin gPackager )
					)
					( objectStatus "R25W87.2" )
				)
			)
			( gate "@baseboard_fab2_lib.baseboard_fab2(sch_1):page147_i24"
				( attribute "BOM_COST" "SM_CONTROLLER"
					( Origin gFrontEnd )
				)
				( attribute "CDS_LIB" "mstr_discrete"
					( Origin gPackager )
				)
				( attribute "CDS_LOCATION" "R25W86"
					( Origin gPackager )
				)
				( attribute "CDS_SEC" "1"
					( Origin gPackager )
				)
				( attribute "LOCATION" "R25W86"
					( Origin gFrontEnd )
				)
				( attribute "MATERIAL" "CHIP"
					( Origin gFrontEnd )
				)
				( attribute "PACK_TYPE" "0402"
					( Origin gFrontEnd )
				)
				( attribute "PART_NUMBER" "G21796-250"
					( Origin gFrontEnd )
				)
				( attribute "PHYS_PAGE" "147"
					( Origin gFrontEnd )
				)
				( attribute "ROOM" "BMC"
					( Origin gFrontEnd )
				)
				( attribute "ROT" "0"
					( Origin gFrontEnd )
				)
				( attribute "SEC" "1"
					( Origin gFrontEnd )
				)
				( attribute "SEC_TYPE" "0402"
					( Origin gFrontEnd )
				)
				( attribute "TOLERANCE" "1.0%"
					( Origin gFrontEnd )
				)
				( attribute "VALUE" "22.1"
					( Origin gFrontEnd )
				)
				( attribute "VER" "1"
					( Origin gFrontEnd )
				)
				( attribute "WATTAGE" "1/16W"
					( Origin gFrontEnd )
				)
				( attribute "XY" "(875,3750)"
					( Origin gFrontEnd )
				)
				( attribute "CHIPS_PART_NAME" "RES"
					( Origin gPackager )
				)
				( attribute "CDS_PART_NAME" "RES_0402-22.1,1.0%,1/16W,CHIP,A"
					( Origin gPackager )
				)
				( objectStatus "R25W86" )
				( pin "a"
					( attribute "PN" "1"
						( Origin gPackager )
					)
					( objectStatus "R25W86.1" )
				)
				( pin "b"
					( attribute "PN" "2"
						( Origin gPackager )
					)
					( objectStatus "R25W86.2" )
				)
			)
			( gate "@baseboard_fab2_lib.baseboard_fab2(sch_1):page147_i23"
				( attribute "BOM_COST" "SM_CONTROLLER"
					( Origin gFrontEnd )
				)
				( attribute "CDS_LIB" "mstr_discrete"
					( Origin gPackager )
				)
				( attribute "CDS_LOCATION" "R25W85"
					( Origin gPackager )
				)
				( attribute "CDS_SEC" "1"
					( Origin gPackager )
				)
				( attribute "LOCATION" "R25W85"
					( Origin gFrontEnd )
				)
				( attribute "MATERIAL" "CHIP"
					( Origin gFrontEnd )
				)
				( attribute "PACK_TYPE" "0402"
					( Origin gFrontEnd )
				)
				( attribute "PART_NUMBER" "G21796-250"
					( Origin gFrontEnd )
				)
				( attribute "PHYS_PAGE" "147"
					( Origin gFrontEnd )
				)
				( attribute "ROOM" "BMC"
					( Origin gFrontEnd )
				)
				( attribute "ROT" "0"
					( Origin gFrontEnd )
				)
				( attribute "SEC" "1"
					( Origin gFrontEnd )
				)
				( attribute "SEC_TYPE" "0402"
					( Origin gFrontEnd )
				)
				( attribute "TOLERANCE" "1.0%"
					( Origin gFrontEnd )
				)
				( attribute "VALUE" "22.1"
					( Origin gFrontEnd )
				)
				( attribute "VER" "1"
					( Origin gFrontEnd )
				)
				( attribute "WATTAGE" "1/16W"
					( Origin gFrontEnd )
				)
				( attribute "XY" "(875,4000)"
					( Origin gFrontEnd )
				)
				( attribute "CHIPS_PART_NAME" "RES"
					( Origin gPackager )
				)
				( attribute "CDS_PART_NAME" "RES_0402-22.1,1.0%,1/16W,CHIP,A"
					( Origin gPackager )
				)
				( objectStatus "R25W85" )
				( pin "a"
					( attribute "PN" "1"
						( Origin gPackager )
					)
					( objectStatus "R25W85.1" )
				)
				( pin "b"
					( attribute "PN" "2"
						( Origin gPackager )
					)
					( objectStatus "R25W85.2" )
				)
			)
			( gate "@baseboard_fab2_lib.baseboard_fab2(sch_1):page147_i22"
				( attribute "BOM_COST" "SM_CONTROLLER"
					( Origin gFrontEnd )
				)
				( attribute "CDS_LIB" "mstr_discrete"
					( Origin gPackager )
				)
				( attribute "CDS_LOCATION" "R25W89"
					( Origin gPackager )
				)
				( attribute "CDS_SEC" "1"
					( Origin gPackager )
				)
				( attribute "LOCATION" "R25W89"
					( Origin gFrontEnd )
				)
				( attribute "MATERIAL" "CHIP"
					( Origin gFrontEnd )
				)
				( attribute "PACK_TYPE" "0402"
					( Origin gFrontEnd )
				)
				( attribute "PART_NUMBER" "G21796-250"
					( Origin gFrontEnd )
				)
				( attribute "PHYS_PAGE" "147"
					( Origin gFrontEnd )
				)
				( attribute "ROOM" "BMC"
					( Origin gFrontEnd )
				)
				( attribute "ROT" "0"
					( Origin gFrontEnd )
				)
				( attribute "SEC" "1"
					( Origin gFrontEnd )
				)
				( attribute "SEC_TYPE" "0402"
					( Origin gFrontEnd )
				)
				( attribute "TOLERANCE" "1.0%"
					( Origin gFrontEnd )
				)
				( attribute "VALUE" "22.1"
					( Origin gFrontEnd )
				)
				( attribute "VER" "1"
					( Origin gFrontEnd )
				)
				( attribute "WATTAGE" "1/16W"
					( Origin gFrontEnd )
				)
				( attribute "XY" "(925,4150)"
					( Origin gFrontEnd )
				)
				( attribute "CHIPS_PART_NAME" "RES"
					( Origin gPackager )
				)
				( attribute "CDS_PART_NAME" "RES_0402-22.1,1.0%,1/16W,CHIP,A"
					( Origin gPackager )
				)
				( objectStatus "R25W89" )
				( pin "a"
					( attribute "PN" "1"
						( Origin gPackager )
					)
					( objectStatus "R25W89.1" )
				)
				( pin "b"
					( attribute "PN" "2"
						( Origin gPackager )
					)
					( objectStatus "R25W89.2" )
				)
			)
			( gate "@baseboard_fab2_lib.baseboard_fab2(sch_1):page147_i8"
				( attribute "BOM_COST" "SM_CONTROLLER"
					( Origin gFrontEnd )
				)
				( attribute "CDS_LIB" "mstr_discrete"
					( Origin gPackager )
				)
				( attribute "CDS_LOCATION" "R25W88"
					( Origin gPackager )
				)
				( attribute "CDS_SEC" "1"
					( Origin gPackager )
				)
				( attribute "LOCATION" "R25W88"
					( Origin gFrontEnd )
				)
				( attribute "MATERIAL" "CHIP"
					( Origin gFrontEnd )
				)
				( attribute "PACK_TYPE" "0402"
					( Origin gFrontEnd )
				)
				( attribute "PART_NUMBER" "G21796-250"
					( Origin gFrontEnd )
				)
				( attribute "PHYS_PAGE" "147"
					( Origin gFrontEnd )
				)
				( attribute "ROOM" "BMC"
					( Origin gFrontEnd )
				)
				( attribute "ROT" "0"
					( Origin gFrontEnd )
				)
				( attribute "SEC" "1"
					( Origin gFrontEnd )
				)
				( attribute "SEC_TYPE" "0402"
					( Origin gFrontEnd )
				)
				( attribute "TOLERANCE" "1.0%"
					( Origin gFrontEnd )
				)
				( attribute "VALUE" "22.1"
					( Origin gFrontEnd )
				)
				( attribute "VER" "1"
					( Origin gFrontEnd )
				)
				( attribute "WATTAGE" "1/16W"
					( Origin gFrontEnd )
				)
				( attribute "XY" "(925,4400)"
					( Origin gFrontEnd )
				)
				( attribute "CHIPS_PART_NAME" "RES"
					( Origin gPackager )
				)
				( attribute "CDS_PART_NAME" "RES_0402-22.1,1.0%,1/16W,CHIP,A"
					( Origin gPackager )
				)
				( objectStatus "R25W88" )
				( pin "a"
					( attribute "PN" "1"
						( Origin gPackager )
					)
					( objectStatus "R25W88.1" )
				)
				( pin "b"
					( attribute "PN" "2"
						( Origin gPackager )
					)
					( objectStatus "R25W88.2" )
				)
			)
			( gate "@baseboard_fab2_lib.baseboard_fab2(sch_1):page147_i4"
				( attribute "BOM_COST" "SM_CONTROLLER"
					( Origin gFrontEnd )
				)
				( attribute "CDS_LIB" "mstr_discrete"
					( Origin gPackager )
				)
				( attribute "CDS_LOCATION" "R25W91"
					( Origin gPackager )
				)
				( attribute "CDS_SEC" "1"
					( Origin gPackager )
				)
				( attribute "LOCATION" "R25W91"
					( Origin gFrontEnd )
				)
				( attribute "MATERIAL" "CHIP"
					( Origin gFrontEnd )
				)
				( attribute "PACK_TYPE" "0402"
					( Origin gFrontEnd )
				)
				( attribute "PART_NUMBER" "G21796-016"
					( Origin gFrontEnd )
				)
				( attribute "PHYS_PAGE" "147"
					( Origin gFrontEnd )
				)
				( attribute "ROOM" "BMC"
					( Origin gFrontEnd )
				)
				( attribute "ROT" "0"
					( Origin gFrontEnd )
				)
				( attribute "SEC" "1"
					( Origin gFrontEnd )
				)
				( attribute "SEC_TYPE" "0402"
					( Origin gFrontEnd )
				)
				( attribute "TOLERANCE" "1%"
					( Origin gFrontEnd )
				)
				( attribute "VALUE" "10.0K"
					( Origin gFrontEnd )
				)
				( attribute "VER" "2"
					( Origin gFrontEnd )
				)
				( attribute "WATTAGE" "1/16W"
					( Origin gFrontEnd )
				)
				( attribute "XY" "(1950,4775)"
					( Origin gFrontEnd )
				)
				( attribute "CHIPS_PART_NAME" "RES"
					( Origin gPackager )
				)
				( attribute "CDS_PART_NAME" "RES_0402-10.0K,1%,1/16W,CHIP,GA"
					( Origin gPackager )
				)
				( objectStatus "R25W91" )
				( pin "a"
					( attribute "PN" "1"
						( Origin gPackager )
					)
					( objectStatus "R25W91.1" )
				)
				( pin "b"
					( attribute "PN" "2"
						( Origin gPackager )
					)
					( objectStatus "R25W91.2" )
				)
			)
			( gate "@baseboard_fab2_lib.baseboard_fab2(sch_1):page147_i3"
				( attribute "BOM_COST" "SM_CONTROLLER"
					( Origin gFrontEnd )
				)
				( attribute "CDS_LIB" "mstr_discrete"
					( Origin gPackager )
				)
				( attribute "CDS_LOCATION" "R25W92"
					( Origin gPackager )
				)
				( attribute "CDS_SEC" "1"
					( Origin gPackager )
				)
				( attribute "LOCATION" "R25W92"
					( Origin gFrontEnd )
				)
				( attribute "MATERIAL" "CHIP"
					( Origin gFrontEnd )
				)
				( attribute "PACK_TYPE" "0402"
					( Origin gFrontEnd )
				)
				( attribute "PART_NUMBER" "G21796-016"
					( Origin gFrontEnd )
				)
				( attribute "PHYS_PAGE" "147"
					( Origin gFrontEnd )
				)
				( attribute "ROOM" "BMC"
					( Origin gFrontEnd )
				)
				( attribute "ROT" "0"
					( Origin gFrontEnd )
				)
				( attribute "SEC" "1"
					( Origin gFrontEnd )
				)
				( attribute "SEC_TYPE" "0402"
					( Origin gFrontEnd )
				)
				( attribute "TOLERANCE" "1%"
					( Origin gFrontEnd )
				)
				( attribute "VALUE" "10.0K"
					( Origin gFrontEnd )
				)
				( attribute "VER" "2"
					( Origin gFrontEnd )
				)
				( attribute "WATTAGE" "1/16W"
					( Origin gFrontEnd )
				)
				( attribute "XY" "(2200,4750)"
					( Origin gFrontEnd )
				)
				( attribute "CHIPS_PART_NAME" "RES"
					( Origin gPackager )
				)
				( attribute "CDS_PART_NAME" "RES_0402-10.0K,1%,1/16W,CHIP,GA"
					( Origin gPackager )
				)
				( objectStatus "R25W92" )
				( pin "a"
					( attribute "PN" "1"
						( Origin gPackager )
					)
					( objectStatus "R25W92.1" )
				)
				( pin "b"
					( attribute "PN" "2"
						( Origin gPackager )
					)
					( objectStatus "R25W92.2" )
				)
			)
			( gate "@baseboard_fab2_lib.baseboard_fab2(sch_1):page146_i85"
				( attribute "BOM_COST" "SB"
					( Origin gFrontEnd )
				)
				( attribute "CDS_LIB" "mstr_discrete"
					( Origin gPackager )
				)
				( attribute "LOCATION" "R25W69"
					( Origin gFrontEnd )
				)
				( attribute "MATERIAL" "CHIP"
					( Origin gFrontEnd )
				)
				( attribute "PACK_TYPE" "0402"
					( Origin gFrontEnd )
				)
				( attribute "PART_NUMBER" "G21796-074"
					( Origin gFrontEnd )
				)
				( attribute "PHYS_PAGE" "146"
					( Origin gFrontEnd )
				)
				( attribute "ROOM" "BMC"
					( Origin gFrontEnd )
				)
				( attribute "ROT" "0"
					( Origin gFrontEnd )
				)
				( attribute "TOLERANCE" "1%"
					( Origin gFrontEnd )
				)
				( attribute "VALUE" "33.2"
					( Origin gFrontEnd )
				)
				( attribute "VER" "1"
					( Origin gFrontEnd )
				)
				( attribute "WATTAGE" "1/16W"
					( Origin gFrontEnd )
				)
				( attribute "XY" "(-6850,1300)"
					( Origin gFrontEnd )
				)
				( attribute "CHIPS_PART_NAME" "RES"
					( Origin gPackager )
				)
				( attribute "CDS_PART_NAME" "RES_0402-33.2,1%,1/16W,CHIP,G2A"
					( Origin gPackager )
				)
				( attribute "CDS_LOCATION" "R25W69"
					( Origin gPackager )
				)
				( attribute "CDS_SEC" "1"
					( Origin gPackager )
				)
				( attribute "SEC" "1"
					( Origin gPackager )
				)
				( objectStatus "R25W69" )
				( pin "a"
					( attribute "PN" "1"
						( Origin gPackager )
					)
					( objectStatus "R25W69.1" )
				)
				( pin "b"
					( attribute "PN" "2"
						( Origin gPackager )
					)
					( objectStatus "R25W69.2" )
				)
			)
			( gate "@baseboard_fab2_lib.baseboard_fab2(sch_1):page146_i84"
				( attribute "BOM_COST" "SB"
					( Origin gFrontEnd )
				)
				( attribute "CDS_LIB" "mstr_discrete"
					( Origin gPackager )
				)
				( attribute "LOCATION" "R25W68"
					( Origin gFrontEnd )
				)
				( attribute "MATERIAL" "CHIP"
					( Origin gFrontEnd )
				)
				( attribute "PACK_TYPE" "0402"
					( Origin gFrontEnd )
				)
				( attribute "PART_NUMBER" "G21796-074"
					( Origin gFrontEnd )
				)
				( attribute "PHYS_PAGE" "146"
					( Origin gFrontEnd )
				)
				( attribute "ROOM" "BMC"
					( Origin gFrontEnd )
				)
				( attribute "ROT" "0"
					( Origin gFrontEnd )
				)
				( attribute "TOLERANCE" "1%"
					( Origin gFrontEnd )
				)
				( attribute "VALUE" "33.2"
					( Origin gFrontEnd )
				)
				( attribute "VER" "1"
					( Origin gFrontEnd )
				)
				( attribute "WATTAGE" "1/16W"
					( Origin gFrontEnd )
				)
				( attribute "XY" "(-6850,1400)"
					( Origin gFrontEnd )
				)
				( attribute "CHIPS_PART_NAME" "RES"
					( Origin gPackager )
				)
				( attribute "CDS_PART_NAME" "RES_0402-33.2,1%,1/16W,CHIP,G2A"
					( Origin gPackager )
				)
				( attribute "CDS_LOCATION" "R25W68"
					( Origin gPackager )
				)
				( attribute "CDS_SEC" "1"
					( Origin gPackager )
				)
				( attribute "SEC" "1"
					( Origin gPackager )
				)
				( objectStatus "R25W68" )
				( pin "a"
					( attribute "PN" "1"
						( Origin gPackager )
					)
					( objectStatus "R25W68.1" )
				)
				( pin "b"
					( attribute "PN" "2"
						( Origin gPackager )
					)
					( objectStatus "R25W68.2" )
				)
			)
			( gate "@baseboard_fab2_lib.baseboard_fab2(sch_1):page146_i78"
				( attribute "BOM_COST" "SM_CONTROLLER"
					( Origin gFrontEnd )
				)
				( attribute "CDS_LIB" "mstr_discrete"
					( Origin gPackager )
				)
				( attribute "CDS_LOCATION" "R1U7"
					( Origin gPackager )
				)
				( attribute "CDS_SEC" "1"
					( Origin gPackager )
				)
				( attribute "LOCATION" "R1U7"
					( Origin gFrontEnd )
				)
				( attribute "MATERIAL" "CHIP"
					( Origin gFrontEnd )
				)
				( attribute "PACK_TYPE" "0402"
					( Origin gFrontEnd )
				)
				( attribute "PART_NUMBER" "G21796-016"
					( Origin gFrontEnd )
				)
				( attribute "PHYS_PAGE" "146"
					( Origin gFrontEnd )
				)
				( attribute "ROOM" "BMC"
					( Origin gFrontEnd )
				)
				( attribute "ROT" "0"
					( Origin gFrontEnd )
				)
				( attribute "SEC" "1"
					( Origin gFrontEnd )
				)
				( attribute "SEC_TYPE" "0402"
					( Origin gFrontEnd )
				)
				( attribute "TOLERANCE" "1%"
					( Origin gFrontEnd )
				)
				( attribute "VALUE" "10.0K"
					( Origin gFrontEnd )
				)
				( attribute "VER" "1"
					( Origin gFrontEnd )
				)
				( attribute "WATTAGE" "1/16W"
					( Origin gFrontEnd )
				)
				( attribute "XY" "(-6725,2650)"
					( Origin gFrontEnd )
				)
				( attribute "CHIPS_PART_NAME" "RES"
					( Origin gPackager )
				)
				( attribute "CDS_PART_NAME" "RES_0402-10.0K,1%,1/16W,CHIP,GA"
					( Origin gPackager )
				)
				( objectStatus "R1U7" )
				( pin "a"
					( attribute "PN" "1"
						( Origin gPackager )
					)
					( objectStatus "R1U7.1" )
				)
				( pin "b"
					( attribute "PN" "2"
						( Origin gPackager )
					)
					( objectStatus "R1U7.2" )
				)
			)
			( gate "@baseboard_fab2_lib.baseboard_fab2(sch_1):page146_i76"
				( attribute "CDS_LIB" "mstr_discrete"
					( Origin gPackager )
				)
				( attribute "CDS_LOCATION" "R25W66"
					( Origin gPackager )
				)
				( attribute "CDS_SEC" "1"
					( Origin gPackager )
				)
				( attribute "LOCATION" "R25W66"
					( Origin gFrontEnd )
				)
				( attribute "MATERIAL" "CHIP"
					( Origin gFrontEnd )
				)
				( attribute "PACK_TYPE" "0402"
					( Origin gFrontEnd )
				)
				( attribute "PART_NUMBER" "G21796-010"
					( Origin gFrontEnd )
				)
				( attribute "PHYS_PAGE" "146"
					( Origin gFrontEnd )
				)
				( attribute "ROOM" "BMC"
					( Origin gFrontEnd )
				)
				( attribute "ROT" "0"
					( Origin gFrontEnd )
				)
				( attribute "SEC" "1"
					( Origin gPackager )
				)
				( attribute "TOLERANCE" "1%"
					( Origin gFrontEnd )
				)
				( attribute "VALUE" "100.0K"
					( Origin gFrontEnd )
				)
				( attribute "VER" "2"
					( Origin gFrontEnd )
				)
				( attribute "WATTAGE" "1/16W"
					( Origin gFrontEnd )
				)
				( attribute "XY" "(-5800,800)"
					( Origin gFrontEnd )
				)
				( attribute "CHIPS_PART_NAME" "RES"
					( Origin gPackager )
				)
				( attribute "CDS_PART_NAME" "RES_0402-100.0K,1%,1/16W,CHIP,A"
					( Origin gPackager )
				)
				( objectStatus "R25W66" )
				( pin "a"
					( attribute "PN" "1"
						( Origin gPackager )
					)
					( objectStatus "R25W66.1" )
				)
				( pin "b"
					( attribute "PN" "2"
						( Origin gPackager )
					)
					( objectStatus "R25W66.2" )
				)
			)
			( gate "@baseboard_fab2_lib.baseboard_fab2(sch_1):page146_i75"
				( attribute "BOM_COST" "SB"
					( Origin gFrontEnd )
				)
				( attribute "CDS_LIB" "mstr_discrete"
					( Origin gPackager )
				)
				( attribute "LOCATION" "R3N26"
					( Origin gFrontEnd )
				)
				( attribute "MATERIAL" "CHIP"
					( Origin gFrontEnd )
				)
				( attribute "PACK_TYPE" "0402"
					( Origin gFrontEnd )
				)
				( attribute "PART_NUMBER" "G21796-074"
					( Origin gFrontEnd )
				)
				( attribute "PHYS_PAGE" "146"
					( Origin gFrontEnd )
				)
				( attribute "ROOM" "BMC"
					( Origin gFrontEnd )
				)
				( attribute "ROT" "0"
					( Origin gFrontEnd )
				)
				( attribute "TOLERANCE" "1%"
					( Origin gFrontEnd )
				)
				( attribute "VALUE" "33.2"
					( Origin gFrontEnd )
				)
				( attribute "VER" "1"
					( Origin gFrontEnd )
				)
				( attribute "WATTAGE" "1/16W"
					( Origin gFrontEnd )
				)
				( attribute "XY" "(-6500,1250)"
					( Origin gFrontEnd )
				)
				( attribute "CHIPS_PART_NAME" "RES"
					( Origin gPackager )
				)
				( attribute "CDS_PART_NAME" "RES_0402-33.2,1%,1/16W,CHIP,G2A"
					( Origin gPackager )
				)
				( attribute "CDS_LOCATION" "R3N26"
					( Origin gPackager )
				)
				( attribute "CDS_SEC" "1"
					( Origin gPackager )
				)
				( attribute "SEC" "1"
					( Origin gPackager )
				)
				( objectStatus "R3N26" )
				( pin "a"
					( attribute "PN" "1"
						( Origin gPackager )
					)
					( objectStatus "R3N26.1" )
				)
				( pin "b"
					( attribute "PN" "2"
						( Origin gPackager )
					)
					( objectStatus "R3N26.2" )
				)
			)
			( gate "@baseboard_fab2_lib.baseboard_fab2(sch_1):page146_i74"
				( attribute "BOM_COST" "SB"
					( Origin gFrontEnd )
				)
				( attribute "CDS_LIB" "mstr_discrete"
					( Origin gPackager )
				)
				( attribute "LOCATION" "R3N24"
					( Origin gFrontEnd )
				)
				( attribute "MATERIAL" "CHIP"
					( Origin gFrontEnd )
				)
				( attribute "PACK_TYPE" "0402"
					( Origin gFrontEnd )
				)
				( attribute "PART_NUMBER" "G21796-074"
					( Origin gFrontEnd )
				)
				( attribute "PHYS_PAGE" "146"
					( Origin gFrontEnd )
				)
				( attribute "ROOM" "BMC"
					( Origin gFrontEnd )
				)
				( attribute "ROT" "0"
					( Origin gFrontEnd )
				)
				( attribute "TOLERANCE" "1%"
					( Origin gFrontEnd )
				)
				( attribute "VALUE" "33.2"
					( Origin gFrontEnd )
				)
				( attribute "VER" "1"
					( Origin gFrontEnd )
				)
				( attribute "WATTAGE" "1/16W"
					( Origin gFrontEnd )
				)
				( attribute "XY" "(-6500,1350)"
					( Origin gFrontEnd )
				)
				( attribute "CHIPS_PART_NAME" "RES"
					( Origin gPackager )
				)
				( attribute "CDS_PART_NAME" "RES_0402-33.2,1%,1/16W,CHIP,G2A"
					( Origin gPackager )
				)
				( attribute "CDS_LOCATION" "R3N24"
					( Origin gPackager )
				)
				( attribute "CDS_SEC" "1"
					( Origin gPackager )
				)
				( attribute "SEC" "1"
					( Origin gPackager )
				)
				( objectStatus "R3N24" )
				( pin "a"
					( attribute "PN" "1"
						( Origin gPackager )
					)
					( objectStatus "R3N24.1" )
				)
				( pin "b"
					( attribute "PN" "2"
						( Origin gPackager )
					)
					( objectStatus "R3N24.2" )
				)
			)
			( gate "@baseboard_fab2_lib.baseboard_fab2(sch_1):page146_i73"
				( attribute "BOM_COST" "SM_CONTROLLER"
					( Origin gFrontEnd )
				)
				( attribute "CDS_LIB" "mstr_discrete"
					( Origin gPackager )
				)
				( attribute "CDS_LOCATION" "R25W73"
					( Origin gPackager )
				)
				( attribute "CDS_SEC" "1"
					( Origin gPackager )
				)
				( attribute "LOCATION" "R25W73"
					( Origin gFrontEnd )
				)
				( attribute "MATERIAL" "CHIP"
					( Origin gFrontEnd )
				)
				( attribute "PACK_TYPE" "0402"
					( Origin gFrontEnd )
				)
				( attribute "PART_NUMBER" "G21796-074"
					( Origin gFrontEnd )
				)
				( attribute "PHYS_PAGE" "146"
					( Origin gFrontEnd )
				)
				( attribute "ROOM" "BMC"
					( Origin gFrontEnd )
				)
				( attribute "ROT" "0"
					( Origin gFrontEnd )
				)
				( attribute "SEC" "1"
					( Origin gFrontEnd )
				)
				( attribute "SEC_TYPE" "0402"
					( Origin gFrontEnd )
				)
				( attribute "TOLERANCE" "1%"
					( Origin gFrontEnd )
				)
				( attribute "VALUE" "33.2"
					( Origin gFrontEnd )
				)
				( attribute "VER" "1"
					( Origin gFrontEnd )
				)
				( attribute "WATTAGE" "1/16W"
					( Origin gFrontEnd )
				)
				( attribute "XY" "(-6425,1675)"
					( Origin gFrontEnd )
				)
				( attribute "CHIPS_PART_NAME" "RES"
					( Origin gPackager )
				)
				( attribute "CDS_PART_NAME" "RES_0402-33.2,1%,1/16W,CHIP,G2A"
					( Origin gPackager )
				)
				( objectStatus "R25W73" )
				( pin "a"
					( attribute "PN" "1"
						( Origin gPackager )
					)
					( objectStatus "R25W73.1" )
				)
				( pin "b"
					( attribute "PN" "2"
						( Origin gPackager )
					)
					( objectStatus "R25W73.2" )
				)
			)
			( gate "@baseboard_fab2_lib.baseboard_fab2(sch_1):page146_i72"
				( attribute "BOM_COST" "SM_CONTROLLER"
					( Origin gFrontEnd )
				)
				( attribute "CDS_LIB" "mstr_discrete"
					( Origin gPackager )
				)
				( attribute "LOCATION" "R25W71"
					( Origin gFrontEnd )
				)
				( attribute "MATERIAL" "CHIP"
					( Origin gFrontEnd )
				)
				( attribute "PACK_TYPE" "0402"
					( Origin gFrontEnd )
				)
				( attribute "PART_NUMBER" "G21796-074"
					( Origin gFrontEnd )
				)
				( attribute "PHYS_PAGE" "146"
					( Origin gFrontEnd )
				)
				( attribute "ROOM" "BMC"
					( Origin gFrontEnd )
				)
				( attribute "ROT" "0"
					( Origin gFrontEnd )
				)
				( attribute "TOLERANCE" "1%"
					( Origin gFrontEnd )
				)
				( attribute "VALUE" "33.2"
					( Origin gFrontEnd )
				)
				( attribute "VER" "1"
					( Origin gFrontEnd )
				)
				( attribute "WATTAGE" "1/16W"
					( Origin gFrontEnd )
				)
				( attribute "XY" "(-6425,1500)"
					( Origin gFrontEnd )
				)
				( attribute "CHIPS_PART_NAME" "RES"
					( Origin gPackager )
				)
				( attribute "CDS_PART_NAME" "RES_0402-33.2,1%,1/16W,CHIP,G2A"
					( Origin gPackager )
				)
				( attribute "CDS_LOCATION" "R25W71"
					( Origin gPackager )
				)
				( attribute "CDS_SEC" "1"
					( Origin gPackager )
				)
				( attribute "SEC" "1"
					( Origin gPackager )
				)
				( objectStatus "R25W71" )
				( pin "a"
					( attribute "PN" "1"
						( Origin gPackager )
					)
					( objectStatus "R25W71.1" )
				)
				( pin "b"
					( attribute "PN" "2"
						( Origin gPackager )
					)
					( objectStatus "R25W71.2" )
				)
			)
			( gate "@baseboard_fab2_lib.baseboard_fab2(sch_1):page146_i71"
				( attribute "BOM_COST" "SM_CONTROLLER"
					( Origin gFrontEnd )
				)
				( attribute "CDS_LIB" "mstr_discrete"
					( Origin gPackager )
				)
				( attribute "CDS_LOCATION" "R25W72"
					( Origin gPackager )
				)
				( attribute "CDS_SEC" "1"
					( Origin gPackager )
				)
				( attribute "LOCATION" "R25W72"
					( Origin gFrontEnd )
				)
				( attribute "MATERIAL" "CHIP"
					( Origin gFrontEnd )
				)
				( attribute "PACK_TYPE" "0402"
					( Origin gFrontEnd )
				)
				( attribute "PART_NUMBER" "G21796-074"
					( Origin gFrontEnd )
				)
				( attribute "PHYS_PAGE" "146"
					( Origin gFrontEnd )
				)
				( attribute "ROOM" "BMC"
					( Origin gFrontEnd )
				)
				( attribute "ROT" "0"
					( Origin gFrontEnd )
				)
				( attribute "SEC" "1"
					( Origin gFrontEnd )
				)
				( attribute "SEC_TYPE" "0402"
					( Origin gFrontEnd )
				)
				( attribute "TOLERANCE" "1%"
					( Origin gFrontEnd )
				)
				( attribute "VALUE" "33.2"
					( Origin gFrontEnd )
				)
				( attribute "VER" "1"
					( Origin gFrontEnd )
				)
				( attribute "WATTAGE" "1/16W"
					( Origin gFrontEnd )
				)
				( attribute "XY" "(-6425,1600)"
					( Origin gFrontEnd )
				)
				( attribute "CHIPS_PART_NAME" "RES"
					( Origin gPackager )
				)
				( attribute "CDS_PART_NAME" "RES_0402-33.2,1%,1/16W,CHIP,G2A"
					( Origin gPackager )
				)
				( objectStatus "R25W72" )
				( pin "a"
					( attribute "PN" "1"
						( Origin gPackager )
					)
					( objectStatus "R25W72.1" )
				)
				( pin "b"
					( attribute "PN" "2"
						( Origin gPackager )
					)
					( objectStatus "R25W72.2" )
				)
			)
			( gate "@baseboard_fab2_lib.baseboard_fab2(sch_1):page146_i70"
				( attribute "BOM_COST" "SM_CONTROLLER"
					( Origin gFrontEnd )
				)
				( attribute "CDS_LIB" "mstr_discrete"
					( Origin gPackager )
				)
				( attribute "CDS_LOCATION" "R25W74"
					( Origin gPackager )
				)
				( attribute "CDS_SEC" "1"
					( Origin gPackager )
				)
				( attribute "LOCATION" "R25W74"
					( Origin gFrontEnd )
				)
				( attribute "MATERIAL" "CHIP"
					( Origin gFrontEnd )
				)
				( attribute "PACK_TYPE" "0402"
					( Origin gFrontEnd )
				)
				( attribute "PART_NUMBER" "G21497-005"
					( Origin gFrontEnd )
				)
				( attribute "PHYS_PAGE" "146"
					( Origin gFrontEnd )
				)
				( attribute "ROOM" "BMC"
					( Origin gFrontEnd )
				)
				( attribute "ROT" "0"
					( Origin gFrontEnd )
				)
				( attribute "SEC" "1"
					( Origin gFrontEnd )
				)
				( attribute "SEC_TYPE" "0402"
					( Origin gFrontEnd )
				)
				( attribute "TOLERANCE" "5%"
					( Origin gFrontEnd )
				)
				( attribute "VALUE" "0.0"
					( Origin gFrontEnd )
				)
				( attribute "VER" "1"
					( Origin gFrontEnd )
				)
				( attribute "WATTAGE" "1/16W"
					( Origin gFrontEnd )
				)
				( attribute "XY" "(-6425,1750)"
					( Origin gFrontEnd )
				)
				( attribute "CHIPS_PART_NAME" "RES"
					( Origin gPackager )
				)
				( attribute "CDS_PART_NAME" "RES_0402-0.0,5%,1/16W,CHIP,G21A"
					( Origin gPackager )
				)
				( objectStatus "R25W74" )
				( pin "a"
					( attribute "PN" "1"
						( Origin gPackager )
					)
					( objectStatus "R25W74.1" )
				)
				( pin "b"
					( attribute "PN" "2"
						( Origin gPackager )
					)
					( objectStatus "R25W74.2" )
				)
			)
			( gate "@baseboard_fab2_lib.baseboard_fab2(sch_1):page146_i69"
				( attribute "BOM_COST" "SM_CONTROLLER"
					( Origin gFrontEnd )
				)
				( attribute "CDS_LIB" "mstr_discrete"
					( Origin gPackager )
				)
				( attribute "CDS_LOCATION" "R25W78"
					( Origin gPackager )
				)
				( attribute "LOCATION" "R25W78"
					( Origin gFrontEnd )
				)
				( attribute "MATERIAL" "CHIP"
					( Origin gFrontEnd )
				)
				( attribute "PACK_TYPE" "0402"
					( Origin gFrontEnd )
				)
				( attribute "PART_NUMBER" "G21796-250"
					( Origin gFrontEnd )
				)
				( attribute "PHYS_PAGE" "146"
					( Origin gFrontEnd )
				)
				( attribute "ROOM" "BMC"
					( Origin gFrontEnd )
				)
				( attribute "ROT" "0"
					( Origin gFrontEnd )
				)
				( attribute "SEC" "1"
					( Origin gFrontEnd )
				)
				( attribute "SEC_TYPE" "0402"
					( Origin gFrontEnd )
				)
				( attribute "TOLERANCE" "1.0%"
					( Origin gFrontEnd )
				)
				( attribute "VALUE" "22.1"
					( Origin gFrontEnd )
				)
				( attribute "VER" "1"
					( Origin gFrontEnd )
				)
				( attribute "WATTAGE" "1/16W"
					( Origin gFrontEnd )
				)
				( attribute "XY" "(-6550,2400)"
					( Origin gFrontEnd )
				)
				( attribute "CHIPS_PART_NAME" "RES"
					( Origin gPackager )
				)
				( attribute "CDS_PART_NAME" "RES_0402-22.1,1.0%,1/16W,CHIP,A"
					( Origin gPackager )
				)
				( attribute "CDS_SEC" "1"
					( Origin gPackager )
				)
				( objectStatus "R25W78" )
				( pin "a"
					( attribute "PN" "1"
						( Origin gPackager )
					)
					( objectStatus "R25W78.1" )
				)
				( pin "b"
					( attribute "PN" "2"
						( Origin gPackager )
					)
					( objectStatus "R25W78.2" )
				)
			)
			( gate "@baseboard_fab2_lib.baseboard_fab2(sch_1):page253_i10"
				( attribute "CHIPS_PART_NAME" "TTL1G07_A"
					( Origin gPackager )
				)
			)
			( gate "@baseboard_fab2_lib.baseboard_fab2(sch_1):page149_i160"
				( attribute "CDS_LIB" "w_hdl"
					( Origin gPackager )
				)
				( attribute "CDS_LMAN_SYM_OUTLINE" "-50,75,50,-75"
					( Origin gPackager )
				)
				( attribute "LOCATION" "R25W1"
					( Origin gFrontEnd )
				)
				( attribute "PACK_TYPE" "RCL_GP"
					( Origin gFrontEnd )
				)
				( attribute "PART_NUMBER" "64.12005.6DL"
					( Origin gFrontEnd )
				)
				( attribute "PHYS_PAGE" "149"
					( Origin gFrontEnd )
				)
				( attribute "ROT" "1"
					( Origin gFrontEnd )
				)
				( attribute "VALUE" "120R2F-GP"
					( Origin gFrontEnd )
				)
				( attribute "VER" "1"
					( Origin gFrontEnd )
				)
				( attribute "XY" "(-7525,4300)"
					( Origin gFrontEnd )
				)
				( attribute "CHIPS_PART_NAME" "120R2F-GP"
					( Origin gPackager )
				)
				( attribute "CDS_PART_NAME" "120R2F-GP_RCL_GP-120R2F-GP,64.A"
					( Origin gPackager )
				)
				( attribute "CDS_LOCATION" "R25W1"
					( Origin gPackager )
				)
				( attribute "CDS_SEC" "1"
					( Origin gPackager )
				)
				( attribute "SEC" "1"
					( Origin gPackager )
				)
				( objectStatus "R25W1" )
				( pin "\1\"
					( attribute "PN" "1"
						( Origin gPackager )
					)
					( objectStatus "R25W1.1" )
				)
				( pin "\2\"
					( attribute "PN" "2"
						( Origin gPackager )
					)
					( objectStatus "R25W1.2" )
				)
			)
			( gate "@baseboard_fab2_lib.baseboard_fab2(sch_1):page149_i162"
				( attribute "CDS_LIB" "w_hdl"
					( Origin gPackager )
				)
				( attribute "CDS_LMAN_SYM_OUTLINE" "-50,75,50,-75"
					( Origin gPackager )
				)
				( attribute "LOCATION" "R25W4"
					( Origin gFrontEnd )
				)
				( attribute "PACK_TYPE" "RCL_GP"
					( Origin gFrontEnd )
				)
				( attribute "PART_NUMBER" "64.12005.6DL"
					( Origin gFrontEnd )
				)
				( attribute "PHYS_PAGE" "149"
					( Origin gFrontEnd )
				)
				( attribute "ROT" "1"
					( Origin gFrontEnd )
				)
				( attribute "VALUE" "120R2F-GP"
					( Origin gFrontEnd )
				)
				( attribute "VER" "1"
					( Origin gFrontEnd )
				)
				( attribute "XY" "(-7525,4150)"
					( Origin gFrontEnd )
				)
				( attribute "CHIPS_PART_NAME" "120R2F-GP"
					( Origin gPackager )
				)
				( attribute "CDS_PART_NAME" "120R2F-GP_RCL_GP-120R2F-GP,64.A"
					( Origin gPackager )
				)
				( attribute "CDS_LOCATION" "R25W4"
					( Origin gPackager )
				)
				( attribute "CDS_SEC" "1"
					( Origin gPackager )
				)
				( attribute "SEC" "1"
					( Origin gPackager )
				)
				( objectStatus "R25W4" )
				( pin "\1\"
					( attribute "PN" "1"
						( Origin gPackager )
					)
					( objectStatus "R25W4.1" )
				)
				( pin "\2\"
					( attribute "PN" "2"
						( Origin gPackager )
					)
					( objectStatus "R25W4.2" )
				)
			)
			( gate "@baseboard_fab2_lib.baseboard_fab2(sch_1):page149_i163"
				( attribute "CDS_LIB" "w_hdl"
					( Origin gPackager )
				)
				( attribute "CDS_LMAN_SYM_OUTLINE" "-50,75,50,-75"
					( Origin gPackager )
				)
				( attribute "LOCATION" "R25W3"
					( Origin gFrontEnd )
				)
				( attribute "PACK_TYPE" "RCL_GP"
					( Origin gFrontEnd )
				)
				( attribute "PART_NUMBER" "64.12005.6DL"
					( Origin gFrontEnd )
				)
				( attribute "PHYS_PAGE" "149"
					( Origin gFrontEnd )
				)
				( attribute "ROT" "1"
					( Origin gFrontEnd )
				)
				( attribute "VALUE" "120R2F-GP"
					( Origin gFrontEnd )
				)
				( attribute "VER" "1"
					( Origin gFrontEnd )
				)
				( attribute "XY" "(-7525,4200)"
					( Origin gFrontEnd )
				)
				( attribute "CHIPS_PART_NAME" "120R2F-GP"
					( Origin gPackager )
				)
				( attribute "CDS_PART_NAME" "120R2F-GP_RCL_GP-120R2F-GP,64.A"
					( Origin gPackager )
				)
				( attribute "CDS_LOCATION" "R25W3"
					( Origin gPackager )
				)
				( attribute "CDS_SEC" "1"
					( Origin gPackager )
				)
				( attribute "SEC" "1"
					( Origin gPackager )
				)
				( objectStatus "R25W3" )
				( pin "\1\"
					( attribute "PN" "1"
						( Origin gPackager )
					)
					( objectStatus "R25W3.1" )
				)
				( pin "\2\"
					( attribute "PN" "2"
						( Origin gPackager )
					)
					( objectStatus "R25W3.2" )
				)
			)
			( gate "@baseboard_fab2_lib.baseboard_fab2(sch_1):page149_i164"
				( attribute "CDS_LIB" "w_hdl"
					( Origin gPackager )
				)
				( attribute "CDS_LMAN_SYM_OUTLINE" "-50,75,50,-75"
					( Origin gPackager )
				)
				( attribute "LOCATION" "R25W5"
					( Origin gFrontEnd )
				)
				( attribute "PACK_TYPE" "RCL_GP"
					( Origin gFrontEnd )
				)
				( attribute "PART_NUMBER" "64.12005.6DL"
					( Origin gFrontEnd )
				)
				( attribute "PHYS_PAGE" "149"
					( Origin gFrontEnd )
				)
				( attribute "ROT" "1"
					( Origin gFrontEnd )
				)
				( attribute "VALUE" "120R2F-GP"
					( Origin gFrontEnd )
				)
				( attribute "VER" "1"
					( Origin gFrontEnd )
				)
				( attribute "XY" "(-7525,4100)"
					( Origin gFrontEnd )
				)
				( attribute "CHIPS_PART_NAME" "120R2F-GP"
					( Origin gPackager )
				)
				( attribute "CDS_PART_NAME" "120R2F-GP_RCL_GP-120R2F-GP,64.A"
					( Origin gPackager )
				)
				( attribute "CDS_LOCATION" "R25W5"
					( Origin gPackager )
				)
				( attribute "CDS_SEC" "1"
					( Origin gPackager )
				)
				( attribute "SEC" "1"
					( Origin gPackager )
				)
				( objectStatus "R25W5" )
				( pin "\1\"
					( attribute "PN" "1"
						( Origin gPackager )
					)
					( objectStatus "R25W5.1" )
				)
				( pin "\2\"
					( attribute "PN" "2"
						( Origin gPackager )
					)
					( objectStatus "R25W5.2" )
				)
			)
			( gate "@baseboard_fab2_lib.baseboard_fab2(sch_1):page149_i165"
				( attribute "CDS_LIB" "w_hdl"
					( Origin gPackager )
				)
				( attribute "CDS_LMAN_SYM_OUTLINE" "-50,75,50,-75"
					( Origin gPackager )
				)
				( attribute "LOCATION" "R25W6"
					( Origin gFrontEnd )
				)
				( attribute "PACK_TYPE" "RCL_GP"
					( Origin gFrontEnd )
				)
				( attribute "PART_NUMBER" "64.12005.6DL"
					( Origin gFrontEnd )
				)
				( attribute "PHYS_PAGE" "149"
					( Origin gFrontEnd )
				)
				( attribute "ROT" "1"
					( Origin gFrontEnd )
				)
				( attribute "VALUE" "120R2F-GP"
					( Origin gFrontEnd )
				)
				( attribute "VER" "1"
					( Origin gFrontEnd )
				)
				( attribute "XY" "(-7525,4050)"
					( Origin gFrontEnd )
				)
				( attribute "CHIPS_PART_NAME" "120R2F-GP"
					( Origin gPackager )
				)
				( attribute "CDS_PART_NAME" "120R2F-GP_RCL_GP-120R2F-GP,64.A"
					( Origin gPackager )
				)
				( attribute "CDS_LOCATION" "R25W6"
					( Origin gPackager )
				)
				( attribute "CDS_SEC" "1"
					( Origin gPackager )
				)
				( attribute "SEC" "1"
					( Origin gPackager )
				)
				( objectStatus "R25W6" )
				( pin "\1\"
					( attribute "PN" "1"
						( Origin gPackager )
					)
					( objectStatus "R25W6.1" )
				)
				( pin "\2\"
					( attribute "PN" "2"
						( Origin gPackager )
					)
					( objectStatus "R25W6.2" )
				)
			)
			( gate "@baseboard_fab2_lib.baseboard_fab2(sch_1):page149_i166"
				( attribute "CDS_LIB" "w_hdl"
					( Origin gPackager )
				)
				( attribute "CDS_LMAN_SYM_OUTLINE" "-50,75,50,-75"
					( Origin gPackager )
				)
				( attribute "LOCATION" "R25W7"
					( Origin gFrontEnd )
				)
				( attribute "PACK_TYPE" "RCL_GP"
					( Origin gFrontEnd )
				)
				( attribute "PART_NUMBER" "64.12005.6DL"
					( Origin gFrontEnd )
				)
				( attribute "PHYS_PAGE" "149"
					( Origin gFrontEnd )
				)
				( attribute "ROT" "1"
					( Origin gFrontEnd )
				)
				( attribute "VALUE" "120R2F-GP"
					( Origin gFrontEnd )
				)
				( attribute "VER" "1"
					( Origin gFrontEnd )
				)
				( attribute "XY" "(-7525,4000)"
					( Origin gFrontEnd )
				)
				( attribute "CHIPS_PART_NAME" "120R2F-GP"
					( Origin gPackager )
				)
				( attribute "CDS_PART_NAME" "120R2F-GP_RCL_GP-120R2F-GP,64.A"
					( Origin gPackager )
				)
				( attribute "CDS_LOCATION" "R25W7"
					( Origin gPackager )
				)
				( attribute "CDS_SEC" "1"
					( Origin gPackager )
				)
				( attribute "SEC" "1"
					( Origin gPackager )
				)
				( objectStatus "R25W7" )
				( pin "\1\"
					( attribute "PN" "1"
						( Origin gPackager )
					)
					( objectStatus "R25W7.1" )
				)
				( pin "\2\"
					( attribute "PN" "2"
						( Origin gPackager )
					)
					( objectStatus "R25W7.2" )
				)
			)
			( gate "@baseboard_fab2_lib.baseboard_fab2(sch_1):page149_i167"
				( attribute "CDS_LIB" "w_hdl"
					( Origin gPackager )
				)
				( attribute "CDS_LMAN_SYM_OUTLINE" "-50,75,50,-75"
					( Origin gPackager )
				)
				( attribute "LOCATION" "R25W8"
					( Origin gFrontEnd )
				)
				( attribute "PACK_TYPE" "RCL_GP"
					( Origin gFrontEnd )
				)
				( attribute "PART_NUMBER" "64.12005.6DL"
					( Origin gFrontEnd )
				)
				( attribute "PHYS_PAGE" "149"
					( Origin gFrontEnd )
				)
				( attribute "ROT" "1"
					( Origin gFrontEnd )
				)
				( attribute "VALUE" "120R2F-GP"
					( Origin gFrontEnd )
				)
				( attribute "VER" "1"
					( Origin gFrontEnd )
				)
				( attribute "XY" "(-7525,3950)"
					( Origin gFrontEnd )
				)
				( attribute "CHIPS_PART_NAME" "120R2F-GP"
					( Origin gPackager )
				)
				( attribute "CDS_PART_NAME" "120R2F-GP_RCL_GP-120R2F-GP,64.A"
					( Origin gPackager )
				)
				( attribute "CDS_LOCATION" "R25W8"
					( Origin gPackager )
				)
				( attribute "CDS_SEC" "1"
					( Origin gPackager )
				)
				( attribute "SEC" "1"
					( Origin gPackager )
				)
				( objectStatus "R25W8" )
				( pin "\1\"
					( attribute "PN" "1"
						( Origin gPackager )
					)
					( objectStatus "R25W8.1" )
				)
				( pin "\2\"
					( attribute "PN" "2"
						( Origin gPackager )
					)
					( objectStatus "R25W8.2" )
				)
			)
			( gate "@baseboard_fab2_lib.baseboard_fab2(sch_1):page149_i168"
				( attribute "CDS_LIB" "w_hdl"
					( Origin gPackager )
				)
				( attribute "CDS_LMAN_SYM_OUTLINE" "-50,75,50,-75"
					( Origin gPackager )
				)
				( attribute "LOCATION" "R25W9"
					( Origin gFrontEnd )
				)
				( attribute "PACK_TYPE" "RCL_GP"
					( Origin gFrontEnd )
				)
				( attribute "PART_NUMBER" "64.12005.6DL"
					( Origin gFrontEnd )
				)
				( attribute "PHYS_PAGE" "149"
					( Origin gFrontEnd )
				)
				( attribute "ROT" "1"
					( Origin gFrontEnd )
				)
				( attribute "VALUE" "120R2F-GP"
					( Origin gFrontEnd )
				)
				( attribute "VER" "1"
					( Origin gFrontEnd )
				)
				( attribute "XY" "(-7525,3900)"
					( Origin gFrontEnd )
				)
				( attribute "CHIPS_PART_NAME" "120R2F-GP"
					( Origin gPackager )
				)
				( attribute "CDS_PART_NAME" "120R2F-GP_RCL_GP-120R2F-GP,64.A"
					( Origin gPackager )
				)
				( attribute "CDS_LOCATION" "R25W9"
					( Origin gPackager )
				)
				( attribute "CDS_SEC" "1"
					( Origin gPackager )
				)
				( attribute "SEC" "1"
					( Origin gPackager )
				)
				( objectStatus "R25W9" )
				( pin "\1\"
					( attribute "PN" "1"
						( Origin gPackager )
					)
					( objectStatus "R25W9.1" )
				)
				( pin "\2\"
					( attribute "PN" "2"
						( Origin gPackager )
					)
					( objectStatus "R25W9.2" )
				)
			)
			( gate "@baseboard_fab2_lib.baseboard_fab2(sch_1):page149_i169"
				( attribute "CDS_LIB" "w_hdl"
					( Origin gPackager )
				)
				( attribute "CDS_LMAN_SYM_OUTLINE" "-50,75,50,-75"
					( Origin gPackager )
				)
				( attribute "LOCATION" "R25W10"
					( Origin gFrontEnd )
				)
				( attribute "PACK_TYPE" "RCL_GP"
					( Origin gFrontEnd )
				)
				( attribute "PART_NUMBER" "64.12005.6DL"
					( Origin gFrontEnd )
				)
				( attribute "PHYS_PAGE" "149"
					( Origin gFrontEnd )
				)
				( attribute "ROT" "1"
					( Origin gFrontEnd )
				)
				( attribute "VALUE" "120R2F-GP"
					( Origin gFrontEnd )
				)
				( attribute "VER" "1"
					( Origin gFrontEnd )
				)
				( attribute "XY" "(-7525,3850)"
					( Origin gFrontEnd )
				)
				( attribute "CHIPS_PART_NAME" "120R2F-GP"
					( Origin gPackager )
				)
				( attribute "CDS_PART_NAME" "120R2F-GP_RCL_GP-120R2F-GP,64.A"
					( Origin gPackager )
				)
				( attribute "CDS_LOCATION" "R25W10"
					( Origin gPackager )
				)
				( attribute "CDS_SEC" "1"
					( Origin gPackager )
				)
				( attribute "SEC" "1"
					( Origin gPackager )
				)
				( objectStatus "R25W10" )
				( pin "\1\"
					( attribute "PN" "1"
						( Origin gPackager )
					)
					( objectStatus "R25W10.1" )
				)
				( pin "\2\"
					( attribute "PN" "2"
						( Origin gPackager )
					)
					( objectStatus "R25W10.2" )
				)
			)
			( gate "@baseboard_fab2_lib.baseboard_fab2(sch_1):page149_i170"
				( attribute "CDS_LIB" "w_hdl"
					( Origin gPackager )
				)
				( attribute "CDS_LMAN_SYM_OUTLINE" "-50,75,50,-75"
					( Origin gPackager )
				)
				( attribute "LOCATION" "R25W12"
					( Origin gFrontEnd )
				)
				( attribute "PACK_TYPE" "RCL_GP"
					( Origin gFrontEnd )
				)
				( attribute "PART_NUMBER" "64.12005.6DL"
					( Origin gFrontEnd )
				)
				( attribute "PHYS_PAGE" "149"
					( Origin gFrontEnd )
				)
				( attribute "ROT" "1"
					( Origin gFrontEnd )
				)
				( attribute "VALUE" "120R2F-GP"
					( Origin gFrontEnd )
				)
				( attribute "VER" "1"
					( Origin gFrontEnd )
				)
				( attribute "XY" "(-7525,3750)"
					( Origin gFrontEnd )
				)
				( attribute "CHIPS_PART_NAME" "120R2F-GP"
					( Origin gPackager )
				)
				( attribute "CDS_PART_NAME" "120R2F-GP_RCL_GP-120R2F-GP,64.A"
					( Origin gPackager )
				)
				( attribute "CDS_LOCATION" "R25W12"
					( Origin gPackager )
				)
				( attribute "CDS_SEC" "1"
					( Origin gPackager )
				)
				( attribute "SEC" "1"
					( Origin gPackager )
				)
				( objectStatus "R25W12" )
				( pin "\1\"
					( attribute "PN" "1"
						( Origin gPackager )
					)
					( objectStatus "R25W12.1" )
				)
				( pin "\2\"
					( attribute "PN" "2"
						( Origin gPackager )
					)
					( objectStatus "R25W12.2" )
				)
			)
			( gate "@baseboard_fab2_lib.baseboard_fab2(sch_1):page149_i171"
				( attribute "CDS_LIB" "w_hdl"
					( Origin gPackager )
				)
				( attribute "CDS_LMAN_SYM_OUTLINE" "-50,75,50,-75"
					( Origin gPackager )
				)
				( attribute "LOCATION" "R25W11"
					( Origin gFrontEnd )
				)
				( attribute "PACK_TYPE" "RCL_GP"
					( Origin gFrontEnd )
				)
				( attribute "PART_NUMBER" "64.12005.6DL"
					( Origin gFrontEnd )
				)
				( attribute "PHYS_PAGE" "149"
					( Origin gFrontEnd )
				)
				( attribute "ROT" "1"
					( Origin gFrontEnd )
				)
				( attribute "VALUE" "120R2F-GP"
					( Origin gFrontEnd )
				)
				( attribute "VER" "1"
					( Origin gFrontEnd )
				)
				( attribute "XY" "(-7525,3800)"
					( Origin gFrontEnd )
				)
				( attribute "CHIPS_PART_NAME" "120R2F-GP"
					( Origin gPackager )
				)
				( attribute "CDS_PART_NAME" "120R2F-GP_RCL_GP-120R2F-GP,64.A"
					( Origin gPackager )
				)
				( attribute "CDS_LOCATION" "R25W11"
					( Origin gPackager )
				)
				( attribute "CDS_SEC" "1"
					( Origin gPackager )
				)
				( attribute "SEC" "1"
					( Origin gPackager )
				)
				( objectStatus "R25W11" )
				( pin "\1\"
					( attribute "PN" "1"
						( Origin gPackager )
					)
					( objectStatus "R25W11.1" )
				)
				( pin "\2\"
					( attribute "PN" "2"
						( Origin gPackager )
					)
					( objectStatus "R25W11.2" )
				)
			)
			( gate "@baseboard_fab2_lib.baseboard_fab2(sch_1):page149_i172"
				( attribute "CDS_LIB" "w_hdl"
					( Origin gPackager )
				)
				( attribute "CDS_LMAN_SYM_OUTLINE" "-50,75,50,-75"
					( Origin gPackager )
				)
				( attribute "LOCATION" "R25W13"
					( Origin gFrontEnd )
				)
				( attribute "PACK_TYPE" "RCL_GP"
					( Origin gFrontEnd )
				)
				( attribute "PART_NUMBER" "64.12005.6DL"
					( Origin gFrontEnd )
				)
				( attribute "PHYS_PAGE" "149"
					( Origin gFrontEnd )
				)
				( attribute "ROT" "1"
					( Origin gFrontEnd )
				)
				( attribute "VALUE" "120R2F-GP"
					( Origin gFrontEnd )
				)
				( attribute "VER" "1"
					( Origin gFrontEnd )
				)
				( attribute "XY" "(-7525,3700)"
					( Origin gFrontEnd )
				)
				( attribute "CHIPS_PART_NAME" "120R2F-GP"
					( Origin gPackager )
				)
				( attribute "CDS_PART_NAME" "120R2F-GP_RCL_GP-120R2F-GP,64.A"
					( Origin gPackager )
				)
				( attribute "CDS_LOCATION" "R25W13"
					( Origin gPackager )
				)
				( attribute "CDS_SEC" "1"
					( Origin gPackager )
				)
				( attribute "SEC" "1"
					( Origin gPackager )
				)
				( objectStatus "R25W13" )
				( pin "\1\"
					( attribute "PN" "1"
						( Origin gPackager )
					)
					( objectStatus "R25W13.1" )
				)
				( pin "\2\"
					( attribute "PN" "2"
						( Origin gPackager )
					)
					( objectStatus "R25W13.2" )
				)
			)
			( gate "@baseboard_fab2_lib.baseboard_fab2(sch_1):page149_i173"
				( attribute "CDS_LIB" "w_hdl"
					( Origin gPackager )
				)
				( attribute "CDS_LMAN_SYM_OUTLINE" "-50,75,50,-75"
					( Origin gPackager )
				)
				( attribute "LOCATION" "R25W16"
					( Origin gFrontEnd )
				)
				( attribute "PACK_TYPE" "RCL_GP"
					( Origin gFrontEnd )
				)
				( attribute "PART_NUMBER" "64.12005.6DL"
					( Origin gFrontEnd )
				)
				( attribute "PHYS_PAGE" "149"
					( Origin gFrontEnd )
				)
				( attribute "ROT" "1"
					( Origin gFrontEnd )
				)
				( attribute "VALUE" "120R2F-GP"
					( Origin gFrontEnd )
				)
				( attribute "VER" "1"
					( Origin gFrontEnd )
				)
				( attribute "XY" "(-7525,3550)"
					( Origin gFrontEnd )
				)
				( attribute "CHIPS_PART_NAME" "120R2F-GP"
					( Origin gPackager )
				)
				( attribute "CDS_PART_NAME" "120R2F-GP_RCL_GP-120R2F-GP,64.A"
					( Origin gPackager )
				)
				( attribute "CDS_LOCATION" "R25W16"
					( Origin gPackager )
				)
				( attribute "CDS_SEC" "1"
					( Origin gPackager )
				)
				( attribute "SEC" "1"
					( Origin gPackager )
				)
				( objectStatus "R25W16" )
				( pin "\1\"
					( attribute "PN" "1"
						( Origin gPackager )
					)
					( objectStatus "R25W16.1" )
				)
				( pin "\2\"
					( attribute "PN" "2"
						( Origin gPackager )
					)
					( objectStatus "R25W16.2" )
				)
			)
			( gate "@baseboard_fab2_lib.baseboard_fab2(sch_1):page149_i174"
				( attribute "CDS_LIB" "w_hdl"
					( Origin gPackager )
				)
				( attribute "CDS_LMAN_SYM_OUTLINE" "-50,75,50,-75"
					( Origin gPackager )
				)
				( attribute "LOCATION" "R25W15"
					( Origin gFrontEnd )
				)
				( attribute "PACK_TYPE" "RCL_GP"
					( Origin gFrontEnd )
				)
				( attribute "PART_NUMBER" "64.12005.6DL"
					( Origin gFrontEnd )
				)
				( attribute "PHYS_PAGE" "149"
					( Origin gFrontEnd )
				)
				( attribute "ROT" "1"
					( Origin gFrontEnd )
				)
				( attribute "VALUE" "120R2F-GP"
					( Origin gFrontEnd )
				)
				( attribute "VER" "1"
					( Origin gFrontEnd )
				)
				( attribute "XY" "(-7525,3600)"
					( Origin gFrontEnd )
				)
				( attribute "CHIPS_PART_NAME" "120R2F-GP"
					( Origin gPackager )
				)
				( attribute "CDS_PART_NAME" "120R2F-GP_RCL_GP-120R2F-GP,64.A"
					( Origin gPackager )
				)
				( attribute "CDS_LOCATION" "R25W15"
					( Origin gPackager )
				)
				( attribute "CDS_SEC" "1"
					( Origin gPackager )
				)
				( attribute "SEC" "1"
					( Origin gPackager )
				)
				( objectStatus "R25W15" )
				( pin "\1\"
					( attribute "PN" "1"
						( Origin gPackager )
					)
					( objectStatus "R25W15.1" )
				)
				( pin "\2\"
					( attribute "PN" "2"
						( Origin gPackager )
					)
					( objectStatus "R25W15.2" )
				)
			)
			( gate "@baseboard_fab2_lib.baseboard_fab2(sch_1):page149_i175"
				( attribute "CDS_LIB" "w_hdl"
					( Origin gPackager )
				)
				( attribute "CDS_LMAN_SYM_OUTLINE" "-50,75,50,-75"
					( Origin gPackager )
				)
				( attribute "LOCATION" "R25W14"
					( Origin gFrontEnd )
				)
				( attribute "PACK_TYPE" "RCL_GP"
					( Origin gFrontEnd )
				)
				( attribute "PART_NUMBER" "64.12005.6DL"
					( Origin gFrontEnd )
				)
				( attribute "PHYS_PAGE" "149"
					( Origin gFrontEnd )
				)
				( attribute "ROT" "1"
					( Origin gFrontEnd )
				)
				( attribute "VALUE" "120R2F-GP"
					( Origin gFrontEnd )
				)
				( attribute "VER" "1"
					( Origin gFrontEnd )
				)
				( attribute "XY" "(-7525,3650)"
					( Origin gFrontEnd )
				)
				( attribute "CHIPS_PART_NAME" "120R2F-GP"
					( Origin gPackager )
				)
				( attribute "CDS_PART_NAME" "120R2F-GP_RCL_GP-120R2F-GP,64.A"
					( Origin gPackager )
				)
				( attribute "CDS_LOCATION" "R25W14"
					( Origin gPackager )
				)
				( attribute "CDS_SEC" "1"
					( Origin gPackager )
				)
				( attribute "SEC" "1"
					( Origin gPackager )
				)
				( objectStatus "R25W14" )
				( pin "\1\"
					( attribute "PN" "1"
						( Origin gPackager )
					)
					( objectStatus "R25W14.1" )
				)
				( pin "\2\"
					( attribute "PN" "2"
						( Origin gPackager )
					)
					( objectStatus "R25W14.2" )
				)
			)
			( gate "@baseboard_fab2_lib.baseboard_fab2(sch_1):page149_i176"
				( attribute "CDS_LIB" "w_hdl"
					( Origin gPackager )
				)
				( attribute "CDS_LMAN_SYM_OUTLINE" "-50,75,50,-75"
					( Origin gPackager )
				)
				( attribute "LOCATION" "R25W22"
					( Origin gFrontEnd )
				)
				( attribute "PACK_TYPE" "RCL_GP"
					( Origin gFrontEnd )
				)
				( attribute "PART_NUMBER" "64.12005.6DL"
					( Origin gFrontEnd )
				)
				( attribute "PHYS_PAGE" "149"
					( Origin gFrontEnd )
				)
				( attribute "ROT" "1"
					( Origin gFrontEnd )
				)
				( attribute "VALUE" "120R2F-GP"
					( Origin gFrontEnd )
				)
				( attribute "VER" "1"
					( Origin gFrontEnd )
				)
				( attribute "XY" "(-7525,3250)"
					( Origin gFrontEnd )
				)
				( attribute "CHIPS_PART_NAME" "120R2F-GP"
					( Origin gPackager )
				)
				( attribute "CDS_PART_NAME" "120R2F-GP_RCL_GP-120R2F-GP,64.A"
					( Origin gPackager )
				)
				( attribute "CDS_LOCATION" "R25W22"
					( Origin gPackager )
				)
				( attribute "CDS_SEC" "1"
					( Origin gPackager )
				)
				( attribute "SEC" "1"
					( Origin gPackager )
				)
				( objectStatus "R25W22" )
				( pin "\1\"
					( attribute "PN" "1"
						( Origin gPackager )
					)
					( objectStatus "R25W22.1" )
				)
				( pin "\2\"
					( attribute "PN" "2"
						( Origin gPackager )
					)
					( objectStatus "R25W22.2" )
				)
			)
			( gate "@baseboard_fab2_lib.baseboard_fab2(sch_1):page149_i177"
				( attribute "CDS_LIB" "w_hdl"
					( Origin gPackager )
				)
				( attribute "CDS_LMAN_SYM_OUTLINE" "-50,75,50,-75"
					( Origin gPackager )
				)
				( attribute "LOCATION" "R25W23"
					( Origin gFrontEnd )
				)
				( attribute "PACK_TYPE" "RCL_GP"
					( Origin gFrontEnd )
				)
				( attribute "PART_NUMBER" "64.12005.6DL"
					( Origin gFrontEnd )
				)
				( attribute "PHYS_PAGE" "149"
					( Origin gFrontEnd )
				)
				( attribute "ROT" "1"
					( Origin gFrontEnd )
				)
				( attribute "VALUE" "120R2F-GP"
					( Origin gFrontEnd )
				)
				( attribute "VER" "1"
					( Origin gFrontEnd )
				)
				( attribute "XY" "(-7525,3200)"
					( Origin gFrontEnd )
				)
				( attribute "CHIPS_PART_NAME" "120R2F-GP"
					( Origin gPackager )
				)
				( attribute "CDS_PART_NAME" "120R2F-GP_RCL_GP-120R2F-GP,64.A"
					( Origin gPackager )
				)
				( attribute "CDS_LOCATION" "R25W23"
					( Origin gPackager )
				)
				( attribute "CDS_SEC" "1"
					( Origin gPackager )
				)
				( attribute "SEC" "1"
					( Origin gPackager )
				)
				( objectStatus "R25W23" )
				( pin "\1\"
					( attribute "PN" "1"
						( Origin gPackager )
					)
					( objectStatus "R25W23.1" )
				)
				( pin "\2\"
					( attribute "PN" "2"
						( Origin gPackager )
					)
					( objectStatus "R25W23.2" )
				)
			)
			( gate "@baseboard_fab2_lib.baseboard_fab2(sch_1):page149_i178"
				( attribute "CDS_LIB" "w_hdl"
					( Origin gPackager )
				)
				( attribute "CDS_LMAN_SYM_OUTLINE" "-50,75,50,-75"
					( Origin gPackager )
				)
				( attribute "LOCATION" "R25W24"
					( Origin gFrontEnd )
				)
				( attribute "PACK_TYPE" "RCL_GP"
					( Origin gFrontEnd )
				)
				( attribute "PART_NUMBER" "64.12005.6DL"
					( Origin gFrontEnd )
				)
				( attribute "PHYS_PAGE" "149"
					( Origin gFrontEnd )
				)
				( attribute "ROT" "1"
					( Origin gFrontEnd )
				)
				( attribute "VALUE" "120R2F-GP"
					( Origin gFrontEnd )
				)
				( attribute "VER" "1"
					( Origin gFrontEnd )
				)
				( attribute "XY" "(-7525,3150)"
					( Origin gFrontEnd )
				)
				( attribute "CHIPS_PART_NAME" "120R2F-GP"
					( Origin gPackager )
				)
				( attribute "CDS_PART_NAME" "120R2F-GP_RCL_GP-120R2F-GP,64.A"
					( Origin gPackager )
				)
				( attribute "CDS_LOCATION" "R25W24"
					( Origin gPackager )
				)
				( attribute "CDS_SEC" "1"
					( Origin gPackager )
				)
				( attribute "SEC" "1"
					( Origin gPackager )
				)
				( objectStatus "R25W24" )
				( pin "\1\"
					( attribute "PN" "1"
						( Origin gPackager )
					)
					( objectStatus "R25W24.1" )
				)
				( pin "\2\"
					( attribute "PN" "2"
						( Origin gPackager )
					)
					( objectStatus "R25W24.2" )
				)
			)
			( gate "@baseboard_fab2_lib.baseboard_fab2(sch_1):page149_i179"
				( attribute "CDS_LIB" "w_hdl"
					( Origin gPackager )
				)
				( attribute "CDS_LMAN_SYM_OUTLINE" "-50,75,50,-75"
					( Origin gPackager )
				)
				( attribute "LOCATION" "R25W25"
					( Origin gFrontEnd )
				)
				( attribute "PACK_TYPE" "RCL_GP"
					( Origin gFrontEnd )
				)
				( attribute "PART_NUMBER" "64.12005.6DL"
					( Origin gFrontEnd )
				)
				( attribute "PHYS_PAGE" "149"
					( Origin gFrontEnd )
				)
				( attribute "ROT" "1"
					( Origin gFrontEnd )
				)
				( attribute "VALUE" "120R2F-GP"
					( Origin gFrontEnd )
				)
				( attribute "VER" "1"
					( Origin gFrontEnd )
				)
				( attribute "XY" "(-7525,3100)"
					( Origin gFrontEnd )
				)
				( attribute "CHIPS_PART_NAME" "120R2F-GP"
					( Origin gPackager )
				)
				( attribute "CDS_PART_NAME" "120R2F-GP_RCL_GP-120R2F-GP,64.A"
					( Origin gPackager )
				)
				( attribute "CDS_LOCATION" "R25W25"
					( Origin gPackager )
				)
				( attribute "CDS_SEC" "1"
					( Origin gPackager )
				)
				( attribute "SEC" "1"
					( Origin gPackager )
				)
				( objectStatus "R25W25" )
				( pin "\1\"
					( attribute "PN" "1"
						( Origin gPackager )
					)
					( objectStatus "R25W25.1" )
				)
				( pin "\2\"
					( attribute "PN" "2"
						( Origin gPackager )
					)
					( objectStatus "R25W25.2" )
				)
			)
			( gate "@baseboard_fab2_lib.baseboard_fab2(sch_1):page149_i180"
				( attribute "CDS_LIB" "w_hdl"
					( Origin gPackager )
				)
				( attribute "CDS_LMAN_SYM_OUTLINE" "-50,75,50,-75"
					( Origin gPackager )
				)
				( attribute "LOCATION" "R25W26"
					( Origin gFrontEnd )
				)
				( attribute "PACK_TYPE" "RCL_GP"
					( Origin gFrontEnd )
				)
				( attribute "PART_NUMBER" "64.12005.6DL"
					( Origin gFrontEnd )
				)
				( attribute "PHYS_PAGE" "149"
					( Origin gFrontEnd )
				)
				( attribute "ROT" "1"
					( Origin gFrontEnd )
				)
				( attribute "VALUE" "120R2F-GP"
					( Origin gFrontEnd )
				)
				( attribute "VER" "1"
					( Origin gFrontEnd )
				)
				( attribute "XY" "(-7525,3050)"
					( Origin gFrontEnd )
				)
				( attribute "CHIPS_PART_NAME" "120R2F-GP"
					( Origin gPackager )
				)
				( attribute "CDS_PART_NAME" "120R2F-GP_RCL_GP-120R2F-GP,64.A"
					( Origin gPackager )
				)
				( attribute "CDS_LOCATION" "R25W26"
					( Origin gPackager )
				)
				( attribute "CDS_SEC" "1"
					( Origin gPackager )
				)
				( attribute "SEC" "1"
					( Origin gPackager )
				)
				( objectStatus "R25W26" )
				( pin "\1\"
					( attribute "PN" "1"
						( Origin gPackager )
					)
					( objectStatus "R25W26.1" )
				)
				( pin "\2\"
					( attribute "PN" "2"
						( Origin gPackager )
					)
					( objectStatus "R25W26.2" )
				)
			)
			( gate "@baseboard_fab2_lib.baseboard_fab2(sch_1):page149_i181"
				( attribute "CDS_LIB" "w_hdl"
					( Origin gPackager )
				)
				( attribute "CDS_LMAN_SYM_OUTLINE" "-50,75,50,-75"
					( Origin gPackager )
				)
				( attribute "LOCATION" "R25W17"
					( Origin gFrontEnd )
				)
				( attribute "PACK_TYPE" "RCL_GP"
					( Origin gFrontEnd )
				)
				( attribute "PART_NUMBER" "64.12005.6DL"
					( Origin gFrontEnd )
				)
				( attribute "PHYS_PAGE" "149"
					( Origin gFrontEnd )
				)
				( attribute "ROT" "1"
					( Origin gFrontEnd )
				)
				( attribute "VALUE" "120R2F-GP"
					( Origin gFrontEnd )
				)
				( attribute "VER" "1"
					( Origin gFrontEnd )
				)
				( attribute "XY" "(-7525,3500)"
					( Origin gFrontEnd )
				)
				( attribute "CHIPS_PART_NAME" "120R2F-GP"
					( Origin gPackager )
				)
				( attribute "CDS_PART_NAME" "120R2F-GP_RCL_GP-120R2F-GP,64.A"
					( Origin gPackager )
				)
				( attribute "CDS_LOCATION" "R25W17"
					( Origin gPackager )
				)
				( attribute "CDS_SEC" "1"
					( Origin gPackager )
				)
				( attribute "SEC" "1"
					( Origin gPackager )
				)
				( objectStatus "R25W17" )
				( pin "\1\"
					( attribute "PN" "1"
						( Origin gPackager )
					)
					( objectStatus "R25W17.1" )
				)
				( pin "\2\"
					( attribute "PN" "2"
						( Origin gPackager )
					)
					( objectStatus "R25W17.2" )
				)
			)
			( gate "@baseboard_fab2_lib.baseboard_fab2(sch_1):page149_i182"
				( attribute "CDS_LIB" "w_hdl"
					( Origin gPackager )
				)
				( attribute "CDS_LMAN_SYM_OUTLINE" "-50,75,50,-75"
					( Origin gPackager )
				)
				( attribute "LOCATION" "R25W18"
					( Origin gFrontEnd )
				)
				( attribute "PACK_TYPE" "RCL_GP"
					( Origin gFrontEnd )
				)
				( attribute "PART_NUMBER" "64.12005.6DL"
					( Origin gFrontEnd )
				)
				( attribute "PHYS_PAGE" "149"
					( Origin gFrontEnd )
				)
				( attribute "ROT" "1"
					( Origin gFrontEnd )
				)
				( attribute "VALUE" "120R2F-GP"
					( Origin gFrontEnd )
				)
				( attribute "VER" "1"
					( Origin gFrontEnd )
				)
				( attribute "XY" "(-7525,3450)"
					( Origin gFrontEnd )
				)
				( attribute "CHIPS_PART_NAME" "120R2F-GP"
					( Origin gPackager )
				)
				( attribute "CDS_PART_NAME" "120R2F-GP_RCL_GP-120R2F-GP,64.A"
					( Origin gPackager )
				)
				( attribute "CDS_LOCATION" "R25W18"
					( Origin gPackager )
				)
				( attribute "CDS_SEC" "1"
					( Origin gPackager )
				)
				( attribute "SEC" "1"
					( Origin gPackager )
				)
				( objectStatus "R25W18" )
				( pin "\1\"
					( attribute "PN" "1"
						( Origin gPackager )
					)
					( objectStatus "R25W18.1" )
				)
				( pin "\2\"
					( attribute "PN" "2"
						( Origin gPackager )
					)
					( objectStatus "R25W18.2" )
				)
			)
			( gate "@baseboard_fab2_lib.baseboard_fab2(sch_1):page149_i183"
				( attribute "CDS_LIB" "w_hdl"
					( Origin gPackager )
				)
				( attribute "CDS_LMAN_SYM_OUTLINE" "-50,75,50,-75"
					( Origin gPackager )
				)
				( attribute "LOCATION" "R25W19"
					( Origin gFrontEnd )
				)
				( attribute "PACK_TYPE" "RCL_GP"
					( Origin gFrontEnd )
				)
				( attribute "PART_NUMBER" "64.12005.6DL"
					( Origin gFrontEnd )
				)
				( attribute "PHYS_PAGE" "149"
					( Origin gFrontEnd )
				)
				( attribute "ROT" "1"
					( Origin gFrontEnd )
				)
				( attribute "VALUE" "120R2F-GP"
					( Origin gFrontEnd )
				)
				( attribute "VER" "1"
					( Origin gFrontEnd )
				)
				( attribute "XY" "(-7525,3400)"
					( Origin gFrontEnd )
				)
				( attribute "CHIPS_PART_NAME" "120R2F-GP"
					( Origin gPackager )
				)
				( attribute "CDS_PART_NAME" "120R2F-GP_RCL_GP-120R2F-GP,64.A"
					( Origin gPackager )
				)
				( attribute "CDS_LOCATION" "R25W19"
					( Origin gPackager )
				)
				( attribute "CDS_SEC" "1"
					( Origin gPackager )
				)
				( attribute "SEC" "1"
					( Origin gPackager )
				)
				( objectStatus "R25W19" )
				( pin "\1\"
					( attribute "PN" "1"
						( Origin gPackager )
					)
					( objectStatus "R25W19.1" )
				)
				( pin "\2\"
					( attribute "PN" "2"
						( Origin gPackager )
					)
					( objectStatus "R25W19.2" )
				)
			)
			( gate "@baseboard_fab2_lib.baseboard_fab2(sch_1):page149_i184"
				( attribute "CDS_LIB" "w_hdl"
					( Origin gPackager )
				)
				( attribute "CDS_LMAN_SYM_OUTLINE" "-50,75,50,-75"
					( Origin gPackager )
				)
				( attribute "LOCATION" "R25W20"
					( Origin gFrontEnd )
				)
				( attribute "PACK_TYPE" "RCL_GP"
					( Origin gFrontEnd )
				)
				( attribute "PART_NUMBER" "64.12005.6DL"
					( Origin gFrontEnd )
				)
				( attribute "PHYS_PAGE" "149"
					( Origin gFrontEnd )
				)
				( attribute "ROT" "1"
					( Origin gFrontEnd )
				)
				( attribute "VALUE" "120R2F-GP"
					( Origin gFrontEnd )
				)
				( attribute "VER" "1"
					( Origin gFrontEnd )
				)
				( attribute "XY" "(-7525,3350)"
					( Origin gFrontEnd )
				)
				( attribute "CHIPS_PART_NAME" "120R2F-GP"
					( Origin gPackager )
				)
				( attribute "CDS_PART_NAME" "120R2F-GP_RCL_GP-120R2F-GP,64.A"
					( Origin gPackager )
				)
				( attribute "CDS_LOCATION" "R25W20"
					( Origin gPackager )
				)
				( attribute "CDS_SEC" "1"
					( Origin gPackager )
				)
				( attribute "SEC" "1"
					( Origin gPackager )
				)
				( objectStatus "R25W20" )
				( pin "\1\"
					( attribute "PN" "1"
						( Origin gPackager )
					)
					( objectStatus "R25W20.1" )
				)
				( pin "\2\"
					( attribute "PN" "2"
						( Origin gPackager )
					)
					( objectStatus "R25W20.2" )
				)
			)
			( gate "@baseboard_fab2_lib.baseboard_fab2(sch_1):page149_i185"
				( attribute "CDS_LIB" "w_hdl"
					( Origin gPackager )
				)
				( attribute "CDS_LMAN_SYM_OUTLINE" "-50,75,50,-75"
					( Origin gPackager )
				)
				( attribute "LOCATION" "R25W21"
					( Origin gFrontEnd )
				)
				( attribute "PACK_TYPE" "RCL_GP"
					( Origin gFrontEnd )
				)
				( attribute "PART_NUMBER" "64.12005.6DL"
					( Origin gFrontEnd )
				)
				( attribute "PHYS_PAGE" "149"
					( Origin gFrontEnd )
				)
				( attribute "ROT" "1"
					( Origin gFrontEnd )
				)
				( attribute "VALUE" "120R2F-GP"
					( Origin gFrontEnd )
				)
				( attribute "VER" "1"
					( Origin gFrontEnd )
				)
				( attribute "XY" "(-7525,3300)"
					( Origin gFrontEnd )
				)
				( attribute "CHIPS_PART_NAME" "120R2F-GP"
					( Origin gPackager )
				)
				( attribute "CDS_PART_NAME" "120R2F-GP_RCL_GP-120R2F-GP,64.A"
					( Origin gPackager )
				)
				( attribute "CDS_LOCATION" "R25W21"
					( Origin gPackager )
				)
				( attribute "CDS_SEC" "1"
					( Origin gPackager )
				)
				( attribute "SEC" "1"
					( Origin gPackager )
				)
				( objectStatus "R25W21" )
				( pin "\1\"
					( attribute "PN" "1"
						( Origin gPackager )
					)
					( objectStatus "R25W21.1" )
				)
				( pin "\2\"
					( attribute "PN" "2"
						( Origin gPackager )
					)
					( objectStatus "R25W21.2" )
				)
			)
			( gate "@baseboard_fab2_lib.baseboard_fab2(sch_1):page149_i211"
				( attribute "CDS_LIB" "w_hdl"
					( Origin gPackager )
				)
				( attribute "CDS_LMAN_SYM_OUTLINE" "-50,75,50,-75"
					( Origin gPackager )
				)
				( attribute "LOCATION" "R25W52"
					( Origin gFrontEnd )
				)
				( attribute "PACK_TYPE" "RCL_GP"
					( Origin gFrontEnd )
				)
				( attribute "PART_NUMBER" "64.12005.6DL"
					( Origin gFrontEnd )
				)
				( attribute "PHYS_PAGE" "149"
					( Origin gFrontEnd )
				)
				( attribute "ROT" "1"
					( Origin gFrontEnd )
				)
				( attribute "VALUE" "120R2F-GP"
					( Origin gFrontEnd )
				)
				( attribute "VER" "1"
					( Origin gFrontEnd )
				)
				( attribute "XY" "(-6150,3050)"
					( Origin gFrontEnd )
				)
				( attribute "CHIPS_PART_NAME" "120R2F-GP"
					( Origin gPackager )
				)
				( attribute "CDS_PART_NAME" "120R2F-GP_RCL_GP-120R2F-GP,64.A"
					( Origin gPackager )
				)
				( attribute "CDS_LOCATION" "R25W52"
					( Origin gPackager )
				)
				( attribute "CDS_SEC" "1"
					( Origin gPackager )
				)
				( attribute "SEC" "1"
					( Origin gPackager )
				)
				( objectStatus "R25W52" )
				( pin "\1\"
					( attribute "PN" "1"
						( Origin gPackager )
					)
					( objectStatus "R25W52.1" )
				)
				( pin "\2\"
					( attribute "PN" "2"
						( Origin gPackager )
					)
					( objectStatus "R25W52.2" )
				)
			)
			( gate "@baseboard_fab2_lib.baseboard_fab2(sch_1):page147_i75"
				( attribute "BOM_COST" "SM_CONTROLLER"
					( Origin gFrontEnd )
				)
				( attribute "CDS_LIB" "mstr_discrete"
					( Origin gPackager )
				)
				( attribute "LOCATION" "R2N13"
					( Origin gFrontEnd )
				)
				( attribute "MATERIAL" "CHIP"
					( Origin gFrontEnd )
				)
				( attribute "PACK_TYPE" "0402"
					( Origin gFrontEnd )
				)
				( attribute "PART_NUMBER" "G21796-016"
					( Origin gFrontEnd )
				)
				( attribute "PHYS_PAGE" "147"
					( Origin gFrontEnd )
				)
				( attribute "ROOM" "BMC"
					( Origin gFrontEnd )
				)
				( attribute "ROT" "0"
					( Origin gFrontEnd )
				)
				( attribute "TOLERANCE" "1%"
					( Origin gFrontEnd )
				)
				( attribute "VALUE" "10.0K"
					( Origin gFrontEnd )
				)
				( attribute "VER" "2"
					( Origin gFrontEnd )
				)
				( attribute "WATTAGE" "1/16W"
					( Origin gFrontEnd )
				)
				( attribute "XY" "(-100,1825)"
					( Origin gFrontEnd )
				)
				( attribute "CHIPS_PART_NAME" "RES"
					( Origin gPackager )
				)
				( attribute "CDS_PART_NAME" "RES_0402-10.0K,1%,1/16W,CHIP,GA"
					( Origin gPackager )
				)
				( attribute "CDS_LOCATION" "R2N13"
					( Origin gPackager )
				)
				( attribute "CDS_SEC" "1"
					( Origin gPackager )
				)
				( attribute "SEC" "1"
					( Origin gPackager )
				)
				( objectStatus "R2N13" )
				( pin "a"
					( attribute "PN" "1"
						( Origin gPackager )
					)
					( objectStatus "R2N13.1" )
				)
				( pin "b"
					( attribute "PN" "2"
						( Origin gPackager )
					)
					( objectStatus "R2N13.2" )
				)
			)
			( gate "@baseboard_fab2_lib.baseboard_fab2(sch_1):page144_i82"
				( attribute "CDS_LIB" "mstr_discrete"
					( Origin gPackager )
				)
				( attribute "CDS_LOCATION" "R1T24"
					( Origin gPackager )
				)
				( attribute "LOCATION" "R1T24"
					( Origin gFrontEnd )
				)
				( attribute "MATERIAL" "EMPTY"
					( Origin gFrontEnd )
				)
				( attribute "PACK_TYPE" "0402"
					( Origin gFrontEnd )
				)
				( attribute "PART_NUMBER" "G21497-005"
					( Origin gFrontEnd )
				)
				( attribute "PHYS_PAGE" "144"
					( Origin gFrontEnd )
				)
				( attribute "ROT" "0"
					( Origin gFrontEnd )
				)
				( attribute "SEC" "1"
					( Origin gFrontEnd )
				)
				( attribute "SEC_TYPE" "0402"
					( Origin gFrontEnd )
				)
				( attribute "TOLERANCE" "5%"
					( Origin gFrontEnd )
				)
				( attribute "VALUE" "0.0"
					( Origin gFrontEnd )
				)
				( attribute "VER" "1"
					( Origin gFrontEnd )
				)
				( attribute "WATTAGE" "1/16W"
					( Origin gFrontEnd )
				)
				( attribute "XY" "(-1350,-2600)"
					( Origin gFrontEnd )
				)
				( attribute "CHIPS_PART_NAME" "RES"
					( Origin gPackager )
				)
				( attribute "CDS_PART_NAME" "RES_0402-0.0,5%,1/16W,EMPTY,G2A"
					( Origin gPackager )
				)
				( attribute "CDS_SEC" "1"
					( Origin gPackager )
				)
				( objectStatus "R1T24" )
				( pin "a"
					( attribute "PN" "1"
						( Origin gPackager )
					)
					( objectStatus "R1T24.1" )
				)
				( pin "b"
					( attribute "PN" "2"
						( Origin gPackager )
					)
					( objectStatus "R1T24.2" )
				)
			)
			( gate "@baseboard_fab2_lib.baseboard_fab2(sch_1):page145_i100"
				( attribute "CDS_LIB" "mstr_discrete"
					( Origin gPackager )
				)
				( attribute "LOCATION" "R1T15"
					( Origin gFrontEnd )
				)
				( attribute "MATERIAL" "EMPTY"
					( Origin gFrontEnd )
				)
				( attribute "PACK_TYPE" "0402"
					( Origin gFrontEnd )
				)
				( attribute "PART_NUMBER" "G21497-005"
					( Origin gFrontEnd )
				)
				( attribute "PHYS_PAGE" "145"
					( Origin gFrontEnd )
				)
				( attribute "ROT" "0"
					( Origin gFrontEnd )
				)
				( attribute "TOLERANCE" "5%"
					( Origin gFrontEnd )
				)
				( attribute "VALUE" "0.0"
					( Origin gFrontEnd )
				)
				( attribute "VER" "1"
					( Origin gFrontEnd )
				)
				( attribute "WATTAGE" "1/16W"
					( Origin gFrontEnd )
				)
				( attribute "XY" "(-7450,-2400)"
					( Origin gFrontEnd )
				)
				( attribute "CHIPS_PART_NAME" "RES"
					( Origin gPackager )
				)
				( attribute "CDS_PART_NAME" "RES_0402-0.0,5%,1/16W,EMPTY,G2A"
					( Origin gPackager )
				)
				( attribute "CDS_LOCATION" "R1T15"
					( Origin gPackager )
				)
				( attribute "CDS_SEC" "1"
					( Origin gPackager )
				)
				( attribute "SEC" "1"
					( Origin gPackager )
				)
				( objectStatus "R1T15" )
				( pin "a"
					( attribute "PN" "1"
						( Origin gPackager )
					)
					( objectStatus "R1T15.1" )
				)
				( pin "b"
					( attribute "PN" "2"
						( Origin gPackager )
					)
					( objectStatus "R1T15.2" )
				)
			)
			( gate "@baseboard_fab2_lib.baseboard_fab2(sch_1):page145_i101"
				( attribute "CDS_LIB" "mstr_discrete"
					( Origin gPackager )
				)
				( attribute "LOCATION" "R1T23"
					( Origin gFrontEnd )
				)
				( attribute "MATERIAL" "EMPTY"
					( Origin gFrontEnd )
				)
				( attribute "PACK_TYPE" "0402"
					( Origin gFrontEnd )
				)
				( attribute "PART_NUMBER" "G21497-005"
					( Origin gFrontEnd )
				)
				( attribute "PHYS_PAGE" "145"
					( Origin gFrontEnd )
				)
				( attribute "ROT" "5"
					( Origin gFrontEnd )
				)
				( attribute "TOLERANCE" "5%"
					( Origin gFrontEnd )
				)
				( attribute "VALUE" "0.0"
					( Origin gFrontEnd )
				)
				( attribute "VER" "1"
					( Origin gFrontEnd )
				)
				( attribute "WATTAGE" "1/16W"
					( Origin gFrontEnd )
				)
				( attribute "XY" "(-7000,-2650)"
					( Origin gFrontEnd )
				)
				( attribute "CHIPS_PART_NAME" "RES"
					( Origin gPackager )
				)
				( attribute "CDS_PART_NAME" "RES_0402-0.0,5%,1/16W,EMPTY,G2A"
					( Origin gPackager )
				)
				( attribute "CDS_LOCATION" "R1T23"
					( Origin gPackager )
				)
				( attribute "CDS_SEC" "1"
					( Origin gPackager )
				)
				( attribute "SEC" "1"
					( Origin gPackager )
				)
				( objectStatus "R1T23" )
				( pin "a"
					( attribute "PN" "1"
						( Origin gPackager )
					)
					( objectStatus "R1T23.1" )
				)
				( pin "b"
					( attribute "PN" "2"
						( Origin gPackager )
					)
					( objectStatus "R1T23.2" )
				)
			)
			( gate "@baseboard_fab2_lib.baseboard_fab2(sch_1):page247_i81"
				( attribute "BOM_COST" "SM_THERM"
					( Origin gFrontEnd )
				)
				( attribute "CDS_LIB" "mstr_discrete"
					( Origin gPackager )
				)
				( attribute "LOCATION" "C6W2"
					( Origin gFrontEnd )
				)
				( attribute "MATERIAL" "X7R"
					( Origin gFrontEnd )
				)
				( attribute "PACK_TYPE" "0402LF"
					( Origin gFrontEnd )
				)
				( attribute "PART_NUMBER" "A36096-030"
					( Origin gFrontEnd )
				)
				( attribute "PHYS_PAGE" "247"
					( Origin gFrontEnd )
				)
				( attribute "ROOM" "CPUFANS"
					( Origin gFrontEnd )
				)
				( attribute "ROT" "0"
					( Origin gFrontEnd )
				)
				( attribute "TOLERANCE" "10%"
					( Origin gFrontEnd )
				)
				( attribute "VALUE" "0.1UF"
					( Origin gFrontEnd )
				)
				( attribute "VER" "1"
					( Origin gFrontEnd )
				)
				( attribute "VOLTAGE" "16V"
					( Units "uVoltage" "V" 1.000000)
					( Origin gFrontEnd )
				)
				( attribute "XY" "(-5900,2075)"
					( Origin gFrontEnd )
				)
				( attribute "CHIPS_PART_NAME" "CAP"
					( Origin gPackager )
				)
				( attribute "CDS_PART_NAME" "CAP_0402LF-0.1UF,16V,10%,X7R,AA"
					( Origin gPackager )
				)
				( attribute "CDS_LOCATION" "C6W2"
					( Origin gPackager )
				)
				( attribute "CDS_SEC" "1"
					( Origin gPackager )
				)
				( attribute "SEC" "1"
					( Origin gPackager )
				)
				( objectStatus "C6W2" )
				( pin "a"
					( attribute "PN" "1"
						( Origin gPackager )
					)
					( objectStatus "C6W2.1" )
				)
				( pin "b"
					( attribute "PN" "2"
						( Origin gPackager )
					)
					( objectStatus "C6W2.2" )
				)
			)
			( gate "@baseboard_fab2_lib.baseboard_fab2(sch_1):page247_i77"
				( attribute "CDS_LIB" "w_hdl"
					( Origin gPackager )
				)
				( attribute "CDS_LMAN_SYM_OUTLINE" "-225,175,225,-175"
					( Origin gPackager )
				)
				( attribute "LOCATION" "U6W2"
					( Origin gFrontEnd )
				)
				( attribute "PACK_TYPE" "DISCRET-G5"
					( Origin gFrontEnd )
				)
				( attribute "PART_NUMBER" "71.09515.F0W"
					( Origin gFrontEnd )
				)
				( attribute "PHYS_PAGE" "247"
					( Origin gFrontEnd )
				)
				( attribute "ROT" "0"
					( Origin gFrontEnd )
				)
				( attribute "VALUE" "PCA9515ADGKR-1-GP"
					( Origin gFrontEnd )
				)
				( attribute "VER" "1"
					( Origin gFrontEnd )
				)
				( attribute "XY" "(-6475,1625)"
					( Origin gFrontEnd )
				)
				( attribute "CHIPS_PART_NAME" "PCA9515ADGKR-1-GP"
					( Origin gPackager )
				)
				( attribute "CDS_PART_NAME" "PCA9515ADGKR-1-GP_DISCRET-G5-PA"
					( Origin gPackager )
				)
				( attribute "CDS_LOCATION" "U6W2"
					( Origin gPackager )
				)
				( attribute "CDS_SEC" "1"
					( Origin gPackager )
				)
				( attribute "SEC" "1"
					( Origin gPackager )
				)
				( objectStatus "U6W2" )
				( pin "en"
					( attribute "PN" "5"
						( Origin gPackager )
					)
					( objectStatus "U6W2.5" )
				)
				( pin "gnd"
					( attribute "PN" "4"
						( Origin gPackager )
					)
					( objectStatus "U6W2.4" )
				)
				( pin "\nc#1\"
					( attribute "PN" "1"
						( Origin gPackager )
					)
					( objectStatus "U6W2.1" )
				)
				( pin "scl0"
					( attribute "PN" "2"
						( Origin gPackager )
					)
					( objectStatus "U6W2.2" )
				)
				( pin "scl1"
					( attribute "PN" "7"
						( Origin gPackager )
					)
					( objectStatus "U6W2.7" )
				)
				( pin "sda0"
					( attribute "PN" "3"
						( Origin gPackager )
					)
					( objectStatus "U6W2.3" )
				)
				( pin "sda1"
					( attribute "PN" "6"
						( Origin gPackager )
					)
					( objectStatus "U6W2.6" )
				)
				( pin "vcc"
					( attribute "PN" "8"
						( Origin gPackager )
					)
					( objectStatus "U6W2.8" )
				)
			)
			( gate "@baseboard_fab2_lib.baseboard_fab2(sch_1):page247_i85"
				( attribute "BOM_COST" "SM_THERM"
					( Origin gFrontEnd )
				)
				( attribute "CDS_LIB" "dev_discrete"
					( Origin gPackager )
				)
				( attribute "CDS_LOCATION" "C6W3"
					( Origin gPackager )
				)
				( attribute "CDS_SEC" "1"
					( Origin gPackager )
				)
				( attribute "LOCATION" "C6W3"
					( Origin gFrontEnd )
				)
				( attribute "MATERIAL" "X7R"
					( Origin gFrontEnd )
				)
				( attribute "PACK_TYPE" "0402V"
					( Origin gFrontEnd )
				)
				( attribute "PART_NUMBER" "A36096-030"
					( Origin gFrontEnd )
				)
				( attribute "PHYS_PAGE" "247"
					( Origin gFrontEnd )
				)
				( attribute "ROOM" "TEMP_SENSORS"
					( Origin gFrontEnd )
				)
				( attribute "ROT" "0"
					( Origin gFrontEnd )
				)
				( attribute "SEC" "1"
					( Origin gFrontEnd )
				)
				( attribute "SEC_TYPE" "0402V"
					( Origin gFrontEnd )
				)
				( attribute "TOLERANCE" "10%"
					( Origin gFrontEnd )
				)
				( attribute "VALUE" "0.1UF"
					( Origin gFrontEnd )
				)
				( attribute "VER" "1"
					( Origin gFrontEnd )
				)
				( attribute "VOLTAGE" "16V"
					( Units "uVoltage" "V" 1.000000)
					( Origin gFrontEnd )
				)
				( attribute "XY" "(-1775,2300)"
					( Origin gFrontEnd )
				)
				( attribute "CHIPS_PART_NAME" "CAP_A"
					( Origin gPackager )
				)
				( attribute "CDS_PART_NAME" "CAP_A_0402V-0.1UF,16V,10%,X7R,A"
					( Origin gPackager )
				)
				( objectStatus "C6W3" )
				( pin "a"
					( attribute "PN" "1"
						( Origin gPackager )
					)
					( objectStatus "C6W3.1" )
				)
				( pin "b"
					( attribute "PN" "2"
						( Origin gPackager )
					)
					( objectStatus "C6W3.2" )
				)
			)
			( gate "@baseboard_fab2_lib.baseboard_fab2(sch_1):page247_i87"
				( attribute "BOM_COST" "SM_THERM"
					( Origin gFrontEnd )
				)
				( attribute "CDS_LIB" "mstr_discrete"
					( Origin gPackager )
				)
				( attribute "CDS_LOCATION" "R6W20"
					( Origin gPackager )
				)
				( attribute "CDS_SEC" "1"
					( Origin gPackager )
				)
				( attribute "LOCATION" "R6W20"
					( Origin gFrontEnd )
				)
				( attribute "MATERIAL" "CHIP"
					( Origin gFrontEnd )
				)
				( attribute "PACK_TYPE" "0402"
					( Origin gFrontEnd )
				)
				( attribute "PART_NUMBER" "G21796-173"
					( Origin gFrontEnd )
				)
				( attribute "PHYS_PAGE" "247"
					( Origin gFrontEnd )
				)
				( attribute "ROOM" "TEMP_SENSORS"
					( Origin gFrontEnd )
				)
				( attribute "ROT" "0"
					( Origin gFrontEnd )
				)
				( attribute "SEC" "1"
					( Origin gPackager )
				)
				( attribute "TOLERANCE" "1%"
					( Origin gFrontEnd )
				)
				( attribute "VALUE" "20.0"
					( Origin gFrontEnd )
				)
				( attribute "VER" "1"
					( Origin gFrontEnd )
				)
				( attribute "WATTAGE" "1/16W"
					( Origin gFrontEnd )
				)
				( attribute "XY" "(-1050,1750)"
					( Origin gFrontEnd )
				)
				( attribute "CHIPS_PART_NAME" "RES"
					( Origin gPackager )
				)
				( attribute "CDS_PART_NAME" "RES_0402-20.0,1%,1/16W,CHIP,G2A"
					( Origin gPackager )
				)
				( objectStatus "R6W20" )
				( pin "a"
					( attribute "PN" "1"
						( Origin gPackager )
					)
					( objectStatus "R6W20.1" )
				)
				( pin "b"
					( attribute "PN" "2"
						( Origin gPackager )
					)
					( objectStatus "R6W20.2" )
				)
			)
			( gate "@baseboard_fab2_lib.baseboard_fab2(sch_1):page247_i89"
				( attribute "BOM_COST" "SM_THERM"
					( Origin gFrontEnd )
				)
				( attribute "CDS_LIB" "mstr_memory"
					( Origin gPackager )
				)
				( attribute "CDS_LOCATION" "U6W3"
					( Origin gPackager )
				)
				( attribute "LOCATION" "U6W3"
					( Origin gFrontEnd )
				)
				( attribute "MATERIAL" "IC"
					( Origin gFrontEnd )
				)
				( attribute "PACK_TYPE" "SOICLF"
					( Origin gFrontEnd )
				)
				( attribute "PART_NUMBER" "C47049-001"
					( Origin gFrontEnd )
				)
				( attribute "PHYS_PAGE" "247"
					( Origin gFrontEnd )
				)
				( attribute "ROOM" "TEMP_SENSORS"
					( Origin gFrontEnd )
				)
				( attribute "ROT" "0"
					( Origin gFrontEnd )
				)
				( attribute "SEC" "1"
					( Origin gFrontEnd )
				)
				( attribute "SEC_TYPE" "SOICLF"
					( Origin gFrontEnd )
				)
				( attribute "VER" "1"
					( Origin gFrontEnd )
				)
				( attribute "XY" "(-2200,1850)"
					( Origin gFrontEnd )
				)
				( attribute "CHIPS_PART_NAME" "AT24C64"
					( Origin gPackager )
				)
				( attribute "CDS_PART_NAME" "AT24C64_SOICLF-IC,C47049-001-VA"
					( Origin gPackager )
				)
				( attribute "CDS_SEC" "1"
					( Origin gPackager )
				)
				( objectStatus "U6W3" )
				( pin "a0"
					( attribute "PN" "1"
						( Origin gPackager )
					)
					( objectStatus "U6W3.1" )
				)
				( pin "a1"
					( attribute "PN" "2"
						( Origin gPackager )
					)
					( objectStatus "U6W3.2" )
				)
				( pin "a2"
					( attribute "PN" "3"
						( Origin gPackager )
					)
					( objectStatus "U6W3.3" )
				)
				( pin "scl"
					( attribute "PN" "6"
						( Origin gPackager )
					)
					( objectStatus "U6W3.6" )
				)
				( pin "sda"
					( attribute "PN" "5"
						( Origin gPackager )
					)
					( objectStatus "U6W3.5" )
				)
				( pin "wp"
					( attribute "PN" "7"
						( Origin gPackager )
					)
					( objectStatus "U6W3.7" )
				)
			)
			( gate "@baseboard_fab2_lib.baseboard_fab2(sch_1):page247_i90"
				( attribute "BOM_COST" "SM_THERM"
					( Origin gFrontEnd )
				)
				( attribute "CDS_LIB" "mstr_discrete"
					( Origin gPackager )
				)
				( attribute "CDS_LOCATION" "R6W21"
					( Origin gPackager )
				)
				( attribute "CDS_SEC" "1"
					( Origin gPackager )
				)
				( attribute "LOCATION" "R6W21"
					( Origin gFrontEnd )
				)
				( attribute "MATERIAL" "CHIP"
					( Origin gFrontEnd )
				)
				( attribute "PACK_TYPE" "0402"
					( Origin gFrontEnd )
				)
				( attribute "PART_NUMBER" "G21796-026"
					( Origin gFrontEnd )
				)
				( attribute "PHYS_PAGE" "247"
					( Origin gFrontEnd )
				)
				( attribute "ROOM" "TEMP_SENSORS"
					( Origin gFrontEnd )
				)
				( attribute "ROT" "0"
					( Origin gFrontEnd )
				)
				( attribute "SEC" "1"
					( Origin gFrontEnd )
				)
				( attribute "SEC_TYPE" "0402"
					( Origin gFrontEnd )
				)
				( attribute "TOLERANCE" "1%"
					( Origin gFrontEnd )
				)
				( attribute "VALUE" "1.00K"
					( Origin gFrontEnd )
				)
				( attribute "VER" "2"
					( Origin gFrontEnd )
				)
				( attribute "WATTAGE" "1/16W"
					( Origin gFrontEnd )
				)
				( attribute "XY" "(-3000,2200)"
					( Origin gFrontEnd )
				)
				( attribute "CHIPS_PART_NAME" "RES"
					( Origin gPackager )
				)
				( attribute "CDS_PART_NAME" "RES_0402-1.00K,1%,1/16W,CHIP,GA"
					( Origin gPackager )
				)
				( objectStatus "R6W21" )
				( pin "a"
					( attribute "PN" "1"
						( Origin gPackager )
					)
					( objectStatus "R6W21.1" )
				)
				( pin "b"
					( attribute "PN" "2"
						( Origin gPackager )
					)
					( objectStatus "R6W21.2" )
				)
			)
			( gate "@baseboard_fab2_lib.baseboard_fab2(sch_1):page247_i92"
				( attribute "BOM_COST" "SM_THERM"
					( Origin gFrontEnd )
				)
				( attribute "CDS_LIB" "mstr_discrete"
					( Origin gPackager )
				)
				( attribute "CDS_LOCATION" "R6W23"
					( Origin gPackager )
				)
				( attribute "CDS_SEC" "1"
					( Origin gPackager )
				)
				( attribute "LOCATION" "R6W23"
					( Origin gFrontEnd )
				)
				( attribute "MATERIAL" "CHIP"
					( Origin gFrontEnd )
				)
				( attribute "PACK_TYPE" "0402"
					( Origin gFrontEnd )
				)
				( attribute "PART_NUMBER" "G21796-026"
					( Origin gFrontEnd )
				)
				( attribute "PHYS_PAGE" "247"
					( Origin gFrontEnd )
				)
				( attribute "ROOM" "TEMP_SENSORS"
					( Origin gFrontEnd )
				)
				( attribute "ROT" "0"
					( Origin gFrontEnd )
				)
				( attribute "SEC" "1"
					( Origin gFrontEnd )
				)
				( attribute "SEC_TYPE" "0402"
					( Origin gFrontEnd )
				)
				( attribute "TOLERANCE" "1%"
					( Origin gFrontEnd )
				)
				( attribute "VALUE" "1.00K"
					( Origin gFrontEnd )
				)
				( attribute "VER" "2"
					( Origin gFrontEnd )
				)
				( attribute "WATTAGE" "1/16W"
					( Origin gFrontEnd )
				)
				( attribute "XY" "(-3000,1525)"
					( Origin gFrontEnd )
				)
				( attribute "CHIPS_PART_NAME" "RES"
					( Origin gPackager )
				)
				( attribute "CDS_PART_NAME" "RES_0402-1.00K,1%,1/16W,CHIP,GA"
					( Origin gPackager )
				)
				( objectStatus "R6W23" )
				( pin "a"
					( attribute "PN" "1"
						( Origin gPackager )
					)
					( objectStatus "R6W23.1" )
				)
				( pin "b"
					( attribute "PN" "2"
						( Origin gPackager )
					)
					( objectStatus "R6W23.2" )
				)
			)
			( gate "@baseboard_fab2_lib.baseboard_fab2(sch_1):page247_i94"
				( attribute "BOM_COST" "SM_THERM"
					( Origin gFrontEnd )
				)
				( attribute "CDS_LIB" "mstr_discrete"
					( Origin gPackager )
				)
				( attribute "CDS_LOCATION" "R6W22"
					( Origin gPackager )
				)
				( attribute "CDS_SEC" "1"
					( Origin gPackager )
				)
				( attribute "LOCATION" "R6W22"
					( Origin gFrontEnd )
				)
				( attribute "MATERIAL" "CHIP"
					( Origin gFrontEnd )
				)
				( attribute "PACK_TYPE" "0402"
					( Origin gFrontEnd )
				)
				( attribute "PART_NUMBER" "G21796-173"
					( Origin gFrontEnd )
				)
				( attribute "PHYS_PAGE" "247"
					( Origin gFrontEnd )
				)
				( attribute "ROOM" "TEMP_SENSORS"
					( Origin gFrontEnd )
				)
				( attribute "ROT" "0"
					( Origin gFrontEnd )
				)
				( attribute "SEC" "1"
					( Origin gFrontEnd )
				)
				( attribute "SEC_TYPE" "0402"
					( Origin gFrontEnd )
				)
				( attribute "TOLERANCE" "1%"
					( Origin gFrontEnd )
				)
				( attribute "VALUE" "20.0"
					( Origin gFrontEnd )
				)
				( attribute "VER" "1"
					( Origin gFrontEnd )
				)
				( attribute "WATTAGE" "1/16W"
					( Origin gFrontEnd )
				)
				( attribute "XY" "(-3425,1750)"
					( Origin gFrontEnd )
				)
				( attribute "CHIPS_PART_NAME" "RES"
					( Origin gPackager )
				)
				( attribute "CDS_PART_NAME" "RES_0402-20.0,1%,1/16W,CHIP,G2A"
					( Origin gPackager )
				)
				( objectStatus "R6W22" )
				( pin "a"
					( attribute "PN" "1"
						( Origin gPackager )
					)
					( objectStatus "R6W22.1" )
				)
				( pin "b"
					( attribute "PN" "2"
						( Origin gPackager )
					)
					( objectStatus "R6W22.2" )
				)
			)
			( gate "@baseboard_fab2_lib.baseboard_fab2(sch_1):page143_i63"
				( attribute "CDS_LIB" "w_hdl"
					( Origin gPackager )
				)
				( attribute "CDS_LMAN_SYM_OUTLINE" "-575,1050,575,-1050"
					( Origin gPackager )
				)
				( attribute "LOCATION" "U25W4"
					( Origin gFrontEnd )
				)
				( attribute "PACK_TYPE" "ASIC2-GB1"
					( Origin gFrontEnd )
				)
				( attribute "PART_NUMBER" "071.2520A.M001"
					( Origin gFrontEnd )
				)
				( attribute "PHYS_PAGE" "143"
					( Origin gFrontEnd )
				)
				( attribute "ROT" "0"
					( Origin gFrontEnd )
				)
				( attribute "VALUE" "AST2520A1-GP-GP"
					( Origin gFrontEnd )
				)
				( attribute "VER" "1"
					( Origin gFrontEnd )
				)
				( attribute "XY" "(-12850,-1850)"
					( Origin gFrontEnd )
				)
				( attribute "CHIPS_PART_NAME" "AST2520A1-GP-GP"
					( Origin gPackager )
				)
				( attribute "CDS_PART_NAME" "AST2520A1-GP-GP_ASIC2-GB1-AST2A"
					( Origin gPackager )
				)
				( attribute "CDS_LOCATION" "U25W4"
					( Origin gPackager )
				)
				( attribute "CDS_SEC" "1"
					( Origin gPackager )
				)
				( attribute "SEC" "1"
					( Origin gPackager )
				)
				( objectStatus "U25W4" )
				( pin "ma0"
					( attribute "PN" "V13"
						( Origin gPackager )
					)
					( objectStatus "U25W4.V13" )
				)
				( pin "ma1"
					( attribute "PN" "AB14"
						( Origin gPackager )
					)
					( objectStatus "U25W4.AB14" )
				)
				( pin "ma2"
					( attribute "PN" "W14"
						( Origin gPackager )
					)
					( objectStatus "U25W4.W14" )
				)
				( pin "ma3"
					( attribute "PN" "U14"
						( Origin gPackager )
					)
					( objectStatus "U25W4.U14" )
				)
				( pin "ma4"
					( attribute "PN" "W15"
						( Origin gPackager )
					)
					( objectStatus "U25W4.W15" )
				)
				( pin "ma5"
					( attribute "PN" "V15"
						( Origin gPackager )
					)
					( objectStatus "U25W4.V15" )
				)
				( pin "ma6"
					( attribute "PN" "AB16"
						( Origin gPackager )
					)
					( objectStatus "U25W4.AB16" )
				)
				( pin "ma7"
					( attribute "PN" "AA16"
						( Origin gPackager )
					)
					( objectStatus "U25W4.AA16" )
				)
				( pin "ma8"
					( attribute "PN" "W16"
						( Origin gPackager )
					)
					( objectStatus "U25W4.W16" )
				)
				( pin "ma9"
					( attribute "PN" "Y16"
						( Origin gPackager )
					)
					( objectStatus "U25W4.Y16" )
				)
				( pin "ma10"
					( attribute "PN" "U13"
						( Origin gPackager )
					)
					( objectStatus "U25W4.U13" )
				)
				( pin "ma11"
					( attribute "PN" "AA14"
						( Origin gPackager )
					)
					( objectStatus "U25W4.AA14" )
				)
				( pin "ma12"
					( attribute "PN" "Y14"
						( Origin gPackager )
					)
					( objectStatus "U25W4.Y14" )
				)
				( pin "ma13"
					( attribute "PN" "AB15"
						( Origin gPackager )
					)
					( objectStatus "U25W4.AB15" )
				)
				( pin "\ma14_mact#\"
					( attribute "PN" "Y15"
						( Origin gPackager )
					)
					( objectStatus "U25W4.Y15" )
				)
				( pin "ma15"
					( attribute "PN" "U15"
						( Origin gPackager )
					)
					( objectStatus "U25W4.U15" )
				)
				( pin "mba0"
					( attribute "PN" "U12"
						( Origin gPackager )
					)
					( objectStatus "U25W4.U12" )
				)
				( pin "mba1"
					( attribute "PN" "Y13"
						( Origin gPackager )
					)
					( objectStatus "U25W4.Y13" )
				)
				( pin "mba2_mbg0"
					( attribute "PN" "W13"
						( Origin gPackager )
					)
					( objectStatus "U25W4.W13" )
				)
				( pin "\mcas#\"
					( attribute "PN" "AB13"
						( Origin gPackager )
					)
					( objectStatus "U25W4.AB13" )
				)
				( pin "mcke"
					( attribute "PN" "Y11"
						( Origin gPackager )
					)
					( objectStatus "U25W4.Y11" )
				)
				( pin "mckn"
					( attribute "PN" "AB12"
						( Origin gPackager )
					)
					( objectStatus "U25W4.AB12" )
				)
				( pin "mckp"
					( attribute "PN" "AB11"
						( Origin gPackager )
					)
					( objectStatus "U25W4.AB11" )
				)
				( pin "\mcs#\"
					( attribute "PN" "AA12"
						( Origin gPackager )
					)
					( objectStatus "U25W4.AA12" )
				)
				( pin "mdm0"
					( attribute "PN" "U8"
						( Origin gPackager )
					)
					( objectStatus "U25W4.U8" )
				)
				( pin "mdm1"
					( attribute "PN" "AB8"
						( Origin gPackager )
					)
					( objectStatus "U25W4.AB8" )
				)
				( pin "mdq0"
					( attribute "PN" "U10"
						( Origin gPackager )
					)
					( objectStatus "U25W4.U10" )
				)
				( pin "mdq1"
					( attribute "PN" "W10"
						( Origin gPackager )
					)
					( objectStatus "U25W4.W10" )
				)
				( pin "mdq2"
					( attribute "PN" "Y10"
						( Origin gPackager )
					)
					( objectStatus "U25W4.Y10" )
				)
				( pin "mdq3"
					( attribute "PN" "AA10"
						( Origin gPackager )
					)
					( objectStatus "U25W4.AA10" )
				)
				( pin "mdq4"
					( attribute "PN" "U9"
						( Origin gPackager )
					)
					( objectStatus "U25W4.U9" )
				)
				( pin "mdq5"
					( attribute "PN" "Y9"
						( Origin gPackager )
					)
					( objectStatus "U25W4.Y9" )
				)
				( pin "mdq6"
					( attribute "PN" "W9"
						( Origin gPackager )
					)
					( objectStatus "U25W4.W9" )
				)
				( pin "mdq7"
					( attribute "PN" "V9"
						( Origin gPackager )
					)
					( objectStatus "U25W4.V9" )
				)
				( pin "mdq8"
					( attribute "PN" "AA8"
						( Origin gPackager )
					)
					( objectStatus "U25W4.AA8" )
				)
				( pin "mdq9"
					( attribute "PN" "Y8"
						( Origin gPackager )
					)
					( objectStatus "U25W4.Y8" )
				)
				( pin "mdq10"
					( attribute "PN" "Y7"
						( Origin gPackager )
					)
					( objectStatus "U25W4.Y7" )
				)
				( pin "mdq11"
					( attribute "PN" "W8"
						( Origin gPackager )
					)
					( objectStatus "U25W4.W8" )
				)
				( pin "mdq12"
					( attribute "PN" "AA6"
						( Origin gPackager )
					)
					( objectStatus "U25W4.AA6" )
				)
				( pin "mdq13"
					( attribute "PN" "W7"
						( Origin gPackager )
					)
					( objectStatus "U25W4.W7" )
				)
				( pin "mdq14"
					( attribute "PN" "V7"
						( Origin gPackager )
					)
					( objectStatus "U25W4.V7" )
				)
				( pin "mdq15"
					( attribute "PN" "U7"
						( Origin gPackager )
					)
					( objectStatus "U25W4.U7" )
				)
				( pin "mdqs0n"
					( attribute "PN" "AB10"
						( Origin gPackager )
					)
					( objectStatus "U25W4.AB10" )
				)
				( pin "mdqs0p"
					( attribute "PN" "AB9"
						( Origin gPackager )
					)
					( objectStatus "U25W4.AB9" )
				)
				( pin "mdqs1n"
					( attribute "PN" "AB6"
						( Origin gPackager )
					)
					( objectStatus "U25W4.AB6" )
				)
				( pin "mdqs1p"
					( attribute "PN" "AB7"
						( Origin gPackager )
					)
					( objectStatus "U25W4.AB7" )
				)
				( pin "mioz"
					( attribute "PN" "W11"
						( Origin gPackager )
					)
					( objectStatus "U25W4.W11" )
				)
				( pin "modt"
					( attribute "PN" "V11"
						( Origin gPackager )
					)
					( objectStatus "U25W4.V11" )
				)
				( pin "\mras#\"
					( attribute "PN" "W12"
						( Origin gPackager )
					)
					( objectStatus "U25W4.W12" )
				)
				( pin "mvref"
					( attribute "PN" "T9"
						( Origin gPackager )
					)
					( objectStatus "U25W4.T9" )
				)
				( pin "\mwe#\"
					( attribute "PN" "Y12"
						( Origin gPackager )
					)
					( objectStatus "U25W4.Y12" )
				)
			)
			( gate "@baseboard_fab2_lib.baseboard_fab2(sch_1):page146_i105"
				( attribute "CDS_LIB" "w_hdl"
					( Origin gPackager )
				)
				( attribute "CDS_LMAN_SYM_OUTLINE" "-1325,950,1325,-950"
					( Origin gPackager )
				)
				( attribute "LOCATION" "U25W4"
					( Origin gFrontEnd )
				)
				( attribute "PACK_TYPE" "ASIC2-GB1"
					( Origin gFrontEnd )
				)
				( attribute "PART_NUMBER" "071.2520A.M001"
					( Origin gFrontEnd )
				)
				( attribute "PHYS_PAGE" "146"
					( Origin gFrontEnd )
				)
				( attribute "ROT" "0"
					( Origin gFrontEnd )
				)
				( attribute "VALUE" "AST2520A1-GP-GP"
					( Origin gFrontEnd )
				)
				( attribute "VER" "5"
					( Origin gFrontEnd )
				)
				( attribute "XY" "(-4100,1850)"
					( Origin gFrontEnd )
				)
				( attribute "CHIPS_PART_NAME" "AST2520A1-GP-GP"
					( Origin gPackager )
				)
				( attribute "CDS_PART_NAME" "AST2520A1-GP-GP_ASIC2-GB1-AST2A"
					( Origin gPackager )
				)
				( attribute "CDS_LOCATION" "U25W4"
					( Origin gPackager )
				)
				( attribute "CDS_SEC" "5"
					( Origin gPackager )
				)
				( attribute "SEC" "5"
					( Origin gPackager )
				)
				( objectStatus "U25W4" )
				( pin "entest"
					( attribute "PN" "K3"
						( Origin gPackager )
					)
					( objectStatus "U25W4.K3" )
				)
				( pin "\extrst#\"
					( attribute "PN" "V18"
						( Origin gPackager )
					)
					( objectStatus "U25W4.V18" )
				)
				( pin "fwspick"
					( attribute "PN" "AA18"
						( Origin gPackager )
					)
					( objectStatus "U25W4.AA18" )
				)
				( pin "\fwspics0#\"
					( attribute "PN" "AB19"
						( Origin gPackager )
					)
					( objectStatus "U25W4.AB19" )
				)
				( pin "fwspimiso"
					( attribute "PN" "T18"
						( Origin gPackager )
					)
					( objectStatus "U25W4.T18" )
				)
				( pin "fwspimosi"
					( attribute "PN" "U17"
						( Origin gPackager )
					)
					( objectStatus "U25W4.U17" )
				)
				( pin "\gpioab0_vpode_noroe#\"
					( attribute "PN" "N19"
						( Origin gPackager )
					)
					( objectStatus "U25W4.N19" )
				)
				( pin "\gpioab1_vpohs_norwe#\"
					( attribute "PN" "T21"
						( Origin gPackager )
					)
					( objectStatus "U25W4.T21" )
				)
				( pin "gpioab2_vpovs_wdtrst1"
					( attribute "PN" "T22"
						( Origin gPackager )
					)
					( objectStatus "U25W4.T22" )
				)
				( pin "gpioab3_vpoclk_wdtrst2"
					( attribute "PN" "R20"
						( Origin gPackager )
					)
					( objectStatus "U25W4.R20" )
				)
				( pin "gpioac0_espid0_lad0"
					( attribute "PN" "G21"
						( Origin gPackager )
					)
					( objectStatus "U25W4.G21" )
				)
				( pin "gpioac1_espid1_lad1"
					( attribute "PN" "G20"
						( Origin gPackager )
					)
					( objectStatus "U25W4.G20" )
				)
				( pin "gpioac2_espid2_lad2"
					( attribute "PN" "D22"
						( Origin gPackager )
					)
					( objectStatus "U25W4.D22" )
				)
				( pin "gpioac3_espid3_lad3"
					( attribute "PN" "E22"
						( Origin gPackager )
					)
					( objectStatus "U25W4.E22" )
				)
				( pin "gpioac4_espick_lclk"
					( attribute "PN" "C22"
						( Origin gPackager )
					)
					( objectStatus "U25W4.C22" )
				)
				( pin "\gpioac5_espics#_lframe#\"
					( attribute "PN" "F21"
						( Origin gPackager )
					)
					( objectStatus "U25W4.F21" )
				)
				( pin "\gpioac6_espialt#_lsirq#\"
					( attribute "PN" "F22"
						( Origin gPackager )
					)
					( objectStatus "U25W4.F22" )
				)
				( pin "\gpioac7_espirst#_lpcrst#\"
					( attribute "PN" "G22"
						( Origin gPackager )
					)
					( objectStatus "U25W4.G22" )
				)
				( pin "gpioj4_vgahs"
					( attribute "PN" "N5"
						( Origin gPackager )
					)
					( objectStatus "U25W4.N5" )
				)
				( pin "gpioj5_vgavs"
					( attribute "PN" "R4"
						( Origin gPackager )
					)
					( objectStatus "U25W4.R4" )
				)
				( pin "gpioj6_ddcclk"
					( attribute "PN" "R3"
						( Origin gPackager )
					)
					( objectStatus "U25W4.R3" )
				)
				( pin "gpioj7_ddcdat"
					( attribute "PN" "T3"
						( Origin gPackager )
					)
					( objectStatus "U25W4.T3" )
				)
				( pin "gpioq6_oscclk"
					( attribute "PN" "B10"
						( Origin gPackager )
					)
					( objectStatus "U25W4.B10" )
				)
				( pin "\gpioq7_pewake#\"
					( attribute "PN" "N20"
						( Origin gPackager )
					)
					( objectStatus "U25W4.N20" )
				)
				( pin "\gpior0_fwspics1#\"
					( attribute "PN" "AA19"
						( Origin gPackager )
					)
					( objectStatus "U25W4.AA19" )
				)
				( pin "\gpior1_fwspics2#\"
					( attribute "PN" "T19"
						( Origin gPackager )
					)
					( objectStatus "U25W4.T19" )
				)
				( pin "\gpior2_spi2cs0#\"
					( attribute "PN" "T17"
						( Origin gPackager )
					)
					( objectStatus "U25W4.T17" )
				)
				( pin "gpior3_spi2ck"
					( attribute "PN" "Y19"
						( Origin gPackager )
					)
					( objectStatus "U25W4.Y19" )
				)
				( pin "gpior4_spi2mosi"
					( attribute "PN" "W19"
						( Origin gPackager )
					)
					( objectStatus "U25W4.W19" )
				)
				( pin "gpior5_spi2miso"
					( attribute "PN" "V19"
						( Origin gPackager )
					)
					( objectStatus "U25W4.V19" )
				)
				( pin "\hbled#\"
					( attribute "PN" "Y18"
						( Origin gPackager )
					)
					( objectStatus "U25W4.Y18" )
				)
				( pin "\malert#\"
					( attribute "PN" "U16"
						( Origin gPackager )
					)
					( objectStatus "U25W4.U16" )
				)
				( pin "\mreset#\"
					( attribute "PN" "AB17"
						( Origin gPackager )
					)
					( objectStatus "U25W4.AB17" )
				)
			)
			( gate "@baseboard_fab2_lib.baseboard_fab2(sch_1):page247_i97"
				( attribute "CDS_LIB" "w_hdl"
					( Origin gPackager )
				)
				( attribute "CDS_LMAN_SYM_OUTLINE" "-200,550,200,-550"
					( Origin gPackager )
				)
				( attribute "LOCATION" "U6W1"
					( Origin gFrontEnd )
				)
				( attribute "PACK_TYPE" "DISCRET-G5"
					( Origin gFrontEnd )
				)
				( attribute "PART_NUMBER" "71.09555.B0W"
					( Origin gFrontEnd )
				)
				( attribute "PHYS_PAGE" "247"
					( Origin gFrontEnd )
				)
				( attribute "ROT" "0"
					( Origin gFrontEnd )
				)
				( attribute "VALUE" "PCA9555PWRG4-GP"
					( Origin gFrontEnd )
				)
				( attribute "VER" "1"
					( Origin gFrontEnd )
				)
				( attribute "XY" "(-2400,3600)"
					( Origin gFrontEnd )
				)
				( attribute "CHIPS_PART_NAME" "PCA9555PWRG4-GP"
					( Origin gPackager )
				)
				( attribute "CDS_PART_NAME" "PCA9555PWRG4-GP_DISCRET-G5-PCAA"
					( Origin gPackager )
				)
				( attribute "CDS_LOCATION" "U6W1"
					( Origin gPackager )
				)
				( attribute "CDS_SEC" "1"
					( Origin gPackager )
				)
				( attribute "SEC" "1"
					( Origin gPackager )
				)
				( objectStatus "U6W1" )
				( pin "a0"
					( attribute "PN" "21"
						( Origin gPackager )
					)
					( objectStatus "U6W1.21" )
				)
				( pin "a1"
					( attribute "PN" "2"
						( Origin gPackager )
					)
					( objectStatus "U6W1.2" )
				)
				( pin "a2"
					( attribute "PN" "3"
						( Origin gPackager )
					)
					( objectStatus "U6W1.3" )
				)
				( pin "gnd"
					( attribute "PN" "12"
						( Origin gPackager )
					)
					( objectStatus "U6W1.12" )
				)
				( pin "\int#\"
					( attribute "PN" "1"
						( Origin gPackager )
					)
					( objectStatus "U6W1.1" )
				)
				( pin "p0"
					( attribute "PN" "4"
						( Origin gPackager )
					)
					( objectStatus "U6W1.4" )
				)
				( pin "p1"
					( attribute "PN" "5"
						( Origin gPackager )
					)
					( objectStatus "U6W1.5" )
				)
				( pin "p2"
					( attribute "PN" "6"
						( Origin gPackager )
					)
					( objectStatus "U6W1.6" )
				)
				( pin "p3"
					( attribute "PN" "7"
						( Origin gPackager )
					)
					( objectStatus "U6W1.7" )
				)
				( pin "p4"
					( attribute "PN" "8"
						( Origin gPackager )
					)
					( objectStatus "U6W1.8" )
				)
				( pin "p5"
					( attribute "PN" "9"
						( Origin gPackager )
					)
					( objectStatus "U6W1.9" )
				)
				( pin "p6"
					( attribute "PN" "10"
						( Origin gPackager )
					)
					( objectStatus "U6W1.10" )
				)
				( pin "p7"
					( attribute "PN" "11"
						( Origin gPackager )
					)
					( objectStatus "U6W1.11" )
				)
				( pin "p10"
					( attribute "PN" "13"
						( Origin gPackager )
					)
					( objectStatus "U6W1.13" )
				)
				( pin "p11"
					( attribute "PN" "14"
						( Origin gPackager )
					)
					( objectStatus "U6W1.14" )
				)
				( pin "p12"
					( attribute "PN" "15"
						( Origin gPackager )
					)
					( objectStatus "U6W1.15" )
				)
				( pin "p13"
					( attribute "PN" "16"
						( Origin gPackager )
					)
					( objectStatus "U6W1.16" )
				)
				( pin "p14"
					( attribute "PN" "17"
						( Origin gPackager )
					)
					( objectStatus "U6W1.17" )
				)
				( pin "p15"
					( attribute "PN" "18"
						( Origin gPackager )
					)
					( objectStatus "U6W1.18" )
				)
				( pin "p16"
					( attribute "PN" "19"
						( Origin gPackager )
					)
					( objectStatus "U6W1.19" )
				)
				( pin "p17"
					( attribute "PN" "20"
						( Origin gPackager )
					)
					( objectStatus "U6W1.20" )
				)
				( pin "scl"
					( attribute "PN" "22"
						( Origin gPackager )
					)
					( objectStatus "U6W1.22" )
				)
				( pin "sda"
					( attribute "PN" "23"
						( Origin gPackager )
					)
					( objectStatus "U6W1.23" )
				)
				( pin "vcc"
					( attribute "PN" "24"
						( Origin gPackager )
					)
					( objectStatus "U6W1.24" )
				)
			)
			( bus "@baseboard_fab2_lib.baseboard_fab2(sch_1):m_a_ba"
				( memberType ( signal ) )
				( member ( signalRef "@baseboard_fab2_lib.baseboard_fab2(sch_1):m_a_ba(0)") )
				( member ( signalRef "@baseboard_fab2_lib.baseboard_fab2(sch_1):m_a_ba(1)") )
				( objectStatus "M_A_BA" )
			)
			( bus "@baseboard_fab2_lib.baseboard_fab2(sch_1):m_a_bg"
				( memberType ( signal ) )
				( member ( signalRef "@baseboard_fab2_lib.baseboard_fab2(sch_1):m_a_bg(0)") )
				( member ( signalRef "@baseboard_fab2_lib.baseboard_fab2(sch_1):m_a_bg(1)") )
				( objectStatus "M_A_BG" )
			)
			( bus "@baseboard_fab2_lib.baseboard_fab2(sch_1):m_a_c"
				( memberType ( signal ) )
				( member ( signalRef "@baseboard_fab2_lib.baseboard_fab2(sch_1):m_a_c(2)") )
				( objectStatus "M_A_C" )
			)
			( bus "@baseboard_fab2_lib.baseboard_fab2(sch_1):m_a_cke"
				( memberType ( signal ) )
				( member ( signalRef "@baseboard_fab2_lib.baseboard_fab2(sch_1):m_a_cke(0)") )
				( member ( signalRef "@baseboard_fab2_lib.baseboard_fab2(sch_1):m_a_cke(1)") )
				( member ( signalRef "@baseboard_fab2_lib.baseboard_fab2(sch_1):m_a_cke(2)") )
				( member ( signalRef "@baseboard_fab2_lib.baseboard_fab2(sch_1):m_a_cke(3)") )
				( objectStatus "M_A_CKE" )
			)
			( bus "@baseboard_fab2_lib.baseboard_fab2(sch_1):m_a_clk_dn"
				( memberType ( signal ) )
				( member ( signalRef "@baseboard_fab2_lib.baseboard_fab2(sch_1):m_a_clk_dn(0)") )
				( member ( signalRef "@baseboard_fab2_lib.baseboard_fab2(sch_1):m_a_clk_dn(1)") )
				( member ( signalRef "@baseboard_fab2_lib.baseboard_fab2(sch_1):m_a_clk_dn(2)") )
				( member ( signalRef "@baseboard_fab2_lib.baseboard_fab2(sch_1):m_a_clk_dn(3)") )
				( objectStatus "M_A_CLK_DN" )
			)
			( bus "@baseboard_fab2_lib.baseboard_fab2(sch_1):m_a_clk_dp"
				( memberType ( signal ) )
				( member ( signalRef "@baseboard_fab2_lib.baseboard_fab2(sch_1):m_a_clk_dp(0)") )
				( member ( signalRef "@baseboard_fab2_lib.baseboard_fab2(sch_1):m_a_clk_dp(1)") )
				( member ( signalRef "@baseboard_fab2_lib.baseboard_fab2(sch_1):m_a_clk_dp(2)") )
				( member ( signalRef "@baseboard_fab2_lib.baseboard_fab2(sch_1):m_a_clk_dp(3)") )
				( objectStatus "M_A_CLK_DP" )
			)
			( bus "@baseboard_fab2_lib.baseboard_fab2(sch_1):m_a_cs_n"
				( memberType ( signal ) )
				( member ( signalRef "@baseboard_fab2_lib.baseboard_fab2(sch_1):m_a_cs_n(0)") )
				( member ( signalRef "@baseboard_fab2_lib.baseboard_fab2(sch_1):m_a_cs_n(1)") )
				( member ( signalRef "@baseboard_fab2_lib.baseboard_fab2(sch_1):m_a_cs_n(2)") )
				( member ( signalRef "@baseboard_fab2_lib.baseboard_fab2(sch_1):m_a_cs_n(3)") )
				( member ( signalRef "@baseboard_fab2_lib.baseboard_fab2(sch_1):m_a_cs_n(4)") )
				( member ( signalRef "@baseboard_fab2_lib.baseboard_fab2(sch_1):m_a_cs_n(5)") )
				( member ( signalRef "@baseboard_fab2_lib.baseboard_fab2(sch_1):m_a_cs_n(6)") )
				( member ( signalRef "@baseboard_fab2_lib.baseboard_fab2(sch_1):m_a_cs_n(7)") )
				( objectStatus "M_A_CS_N" )
			)
			( bus "@baseboard_fab2_lib.baseboard_fab2(sch_1):m_a_dq"
				( memberType ( signal ) )
				( member ( signalRef "@baseboard_fab2_lib.baseboard_fab2(sch_1):m_a_dq(0)") )
				( member ( signalRef "@baseboard_fab2_lib.baseboard_fab2(sch_1):m_a_dq(1)") )
				( member ( signalRef "@baseboard_fab2_lib.baseboard_fab2(sch_1):m_a_dq(2)") )
				( member ( signalRef "@baseboard_fab2_lib.baseboard_fab2(sch_1):m_a_dq(3)") )
				( member ( signalRef "@baseboard_fab2_lib.baseboard_fab2(sch_1):m_a_dq(4)") )
				( member ( signalRef "@baseboard_fab2_lib.baseboard_fab2(sch_1):m_a_dq(5)") )
				( member ( signalRef "@baseboard_fab2_lib.baseboard_fab2(sch_1):m_a_dq(6)") )
				( member ( signalRef "@baseboard_fab2_lib.baseboard_fab2(sch_1):m_a_dq(7)") )
				( member ( signalRef "@baseboard_fab2_lib.baseboard_fab2(sch_1):m_a_dq(8)") )
				( member ( signalRef "@baseboard_fab2_lib.baseboard_fab2(sch_1):m_a_dq(9)") )
				( member ( signalRef "@baseboard_fab2_lib.baseboard_fab2(sch_1):m_a_dq(10)") )
				( member ( signalRef "@baseboard_fab2_lib.baseboard_fab2(sch_1):m_a_dq(11)") )
				( member ( signalRef "@baseboard_fab2_lib.baseboard_fab2(sch_1):m_a_dq(12)") )
				( member ( signalRef "@baseboard_fab2_lib.baseboard_fab2(sch_1):m_a_dq(13)") )
				( member ( signalRef "@baseboard_fab2_lib.baseboard_fab2(sch_1):m_a_dq(14)") )
				( member ( signalRef "@baseboard_fab2_lib.baseboard_fab2(sch_1):m_a_dq(15)") )
				( member ( signalRef "@baseboard_fab2_lib.baseboard_fab2(sch_1):m_a_dq(16)") )
				( member ( signalRef "@baseboard_fab2_lib.baseboard_fab2(sch_1):m_a_dq(17)") )
				( member ( signalRef "@baseboard_fab2_lib.baseboard_fab2(sch_1):m_a_dq(18)") )
				( member ( signalRef "@baseboard_fab2_lib.baseboard_fab2(sch_1):m_a_dq(19)") )
				( member ( signalRef "@baseboard_fab2_lib.baseboard_fab2(sch_1):m_a_dq(20)") )
				( member ( signalRef "@baseboard_fab2_lib.baseboard_fab2(sch_1):m_a_dq(21)") )
				( member ( signalRef "@baseboard_fab2_lib.baseboard_fab2(sch_1):m_a_dq(22)") )
				( member ( signalRef "@baseboard_fab2_lib.baseboard_fab2(sch_1):m_a_dq(23)") )
				( member ( signalRef "@baseboard_fab2_lib.baseboard_fab2(sch_1):m_a_dq(24)") )
				( member ( signalRef "@baseboard_fab2_lib.baseboard_fab2(sch_1):m_a_dq(25)") )
				( member ( signalRef "@baseboard_fab2_lib.baseboard_fab2(sch_1):m_a_dq(26)") )
				( member ( signalRef "@baseboard_fab2_lib.baseboard_fab2(sch_1):m_a_dq(27)") )
				( member ( signalRef "@baseboard_fab2_lib.baseboard_fab2(sch_1):m_a_dq(28)") )
				( member ( signalRef "@baseboard_fab2_lib.baseboard_fab2(sch_1):m_a_dq(29)") )
				( member ( signalRef "@baseboard_fab2_lib.baseboard_fab2(sch_1):m_a_dq(30)") )
				( member ( signalRef "@baseboard_fab2_lib.baseboard_fab2(sch_1):m_a_dq(31)") )
				( member ( signalRef "@baseboard_fab2_lib.baseboard_fab2(sch_1):m_a_dq(32)") )
				( member ( signalRef "@baseboard_fab2_lib.baseboard_fab2(sch_1):m_a_dq(33)") )
				( member ( signalRef "@baseboard_fab2_lib.baseboard_fab2(sch_1):m_a_dq(34)") )
				( member ( signalRef "@baseboard_fab2_lib.baseboard_fab2(sch_1):m_a_dq(35)") )
				( member ( signalRef "@baseboard_fab2_lib.baseboard_fab2(sch_1):m_a_dq(36)") )
				( member ( signalRef "@baseboard_fab2_lib.baseboard_fab2(sch_1):m_a_dq(37)") )
				( member ( signalRef "@baseboard_fab2_lib.baseboard_fab2(sch_1):m_a_dq(38)") )
				( member ( signalRef "@baseboard_fab2_lib.baseboard_fab2(sch_1):m_a_dq(39)") )
				( member ( signalRef "@baseboard_fab2_lib.baseboard_fab2(sch_1):m_a_dq(40)") )
				( member ( signalRef "@baseboard_fab2_lib.baseboard_fab2(sch_1):m_a_dq(41)") )
				( member ( signalRef "@baseboard_fab2_lib.baseboard_fab2(sch_1):m_a_dq(42)") )
				( member ( signalRef "@baseboard_fab2_lib.baseboard_fab2(sch_1):m_a_dq(43)") )
				( member ( signalRef "@baseboard_fab2_lib.baseboard_fab2(sch_1):m_a_dq(44)") )
				( member ( signalRef "@baseboard_fab2_lib.baseboard_fab2(sch_1):m_a_dq(45)") )
				( member ( signalRef "@baseboard_fab2_lib.baseboard_fab2(sch_1):m_a_dq(46)") )
				( member ( signalRef "@baseboard_fab2_lib.baseboard_fab2(sch_1):m_a_dq(47)") )
				( member ( signalRef "@baseboard_fab2_lib.baseboard_fab2(sch_1):m_a_dq(48)") )
				( member ( signalRef "@baseboard_fab2_lib.baseboard_fab2(sch_1):m_a_dq(49)") )
				( member ( signalRef "@baseboard_fab2_lib.baseboard_fab2(sch_1):m_a_dq(50)") )
				( member ( signalRef "@baseboard_fab2_lib.baseboard_fab2(sch_1):m_a_dq(51)") )
				( member ( signalRef "@baseboard_fab2_lib.baseboard_fab2(sch_1):m_a_dq(52)") )
				( member ( signalRef "@baseboard_fab2_lib.baseboard_fab2(sch_1):m_a_dq(53)") )
				( member ( signalRef "@baseboard_fab2_lib.baseboard_fab2(sch_1):m_a_dq(54)") )
				( member ( signalRef "@baseboard_fab2_lib.baseboard_fab2(sch_1):m_a_dq(55)") )
				( member ( signalRef "@baseboard_fab2_lib.baseboard_fab2(sch_1):m_a_dq(56)") )
				( member ( signalRef "@baseboard_fab2_lib.baseboard_fab2(sch_1):m_a_dq(57)") )
				( member ( signalRef "@baseboard_fab2_lib.baseboard_fab2(sch_1):m_a_dq(58)") )
				( member ( signalRef "@baseboard_fab2_lib.baseboard_fab2(sch_1):m_a_dq(59)") )
				( member ( signalRef "@baseboard_fab2_lib.baseboard_fab2(sch_1):m_a_dq(60)") )
				( member ( signalRef "@baseboard_fab2_lib.baseboard_fab2(sch_1):m_a_dq(61)") )
				( member ( signalRef "@baseboard_fab2_lib.baseboard_fab2(sch_1):m_a_dq(62)") )
				( member ( signalRef "@baseboard_fab2_lib.baseboard_fab2(sch_1):m_a_dq(63)") )
				( objectStatus "M_A_DQ" )
			)
			( bus "@baseboard_fab2_lib.baseboard_fab2(sch_1):m_a_dqs_dn"
				( memberType ( signal ) )
				( member ( signalRef "@baseboard_fab2_lib.baseboard_fab2(sch_1):m_a_dqs_dn(0)") )
				( member ( signalRef "@baseboard_fab2_lib.baseboard_fab2(sch_1):m_a_dqs_dn(1)") )
				( member ( signalRef "@baseboard_fab2_lib.baseboard_fab2(sch_1):m_a_dqs_dn(2)") )
				( member ( signalRef "@baseboard_fab2_lib.baseboard_fab2(sch_1):m_a_dqs_dn(3)") )
				( member ( signalRef "@baseboard_fab2_lib.baseboard_fab2(sch_1):m_a_dqs_dn(4)") )
				( member ( signalRef "@baseboard_fab2_lib.baseboard_fab2(sch_1):m_a_dqs_dn(5)") )
				( member ( signalRef "@baseboard_fab2_lib.baseboard_fab2(sch_1):m_a_dqs_dn(6)") )
				( member ( signalRef "@baseboard_fab2_lib.baseboard_fab2(sch_1):m_a_dqs_dn(7)") )
				( member ( signalRef "@baseboard_fab2_lib.baseboard_fab2(sch_1):m_a_dqs_dn(8)") )
				( member ( signalRef "@baseboard_fab2_lib.baseboard_fab2(sch_1):m_a_dqs_dn(9)") )
				( member ( signalRef "@baseboard_fab2_lib.baseboard_fab2(sch_1):m_a_dqs_dn(10)") )
				( member ( signalRef "@baseboard_fab2_lib.baseboard_fab2(sch_1):m_a_dqs_dn(11)") )
				( member ( signalRef "@baseboard_fab2_lib.baseboard_fab2(sch_1):m_a_dqs_dn(12)") )
				( member ( signalRef "@baseboard_fab2_lib.baseboard_fab2(sch_1):m_a_dqs_dn(13)") )
				( member ( signalRef "@baseboard_fab2_lib.baseboard_fab2(sch_1):m_a_dqs_dn(14)") )
				( member ( signalRef "@baseboard_fab2_lib.baseboard_fab2(sch_1):m_a_dqs_dn(15)") )
				( member ( signalRef "@baseboard_fab2_lib.baseboard_fab2(sch_1):m_a_dqs_dn(16)") )
				( member ( signalRef "@baseboard_fab2_lib.baseboard_fab2(sch_1):m_a_dqs_dn(17)") )
				( objectStatus "M_A_DQS_DN" )
			)
			( bus "@baseboard_fab2_lib.baseboard_fab2(sch_1):m_a_dqs_dp"
				( memberType ( signal ) )
				( member ( signalRef "@baseboard_fab2_lib.baseboard_fab2(sch_1):m_a_dqs_dp(0)") )
				( member ( signalRef "@baseboard_fab2_lib.baseboard_fab2(sch_1):m_a_dqs_dp(1)") )
				( member ( signalRef "@baseboard_fab2_lib.baseboard_fab2(sch_1):m_a_dqs_dp(2)") )
				( member ( signalRef "@baseboard_fab2_lib.baseboard_fab2(sch_1):m_a_dqs_dp(3)") )
				( member ( signalRef "@baseboard_fab2_lib.baseboard_fab2(sch_1):m_a_dqs_dp(4)") )
				( member ( signalRef "@baseboard_fab2_lib.baseboard_fab2(sch_1):m_a_dqs_dp(5)") )
				( member ( signalRef "@baseboard_fab2_lib.baseboard_fab2(sch_1):m_a_dqs_dp(6)") )
				( member ( signalRef "@baseboard_fab2_lib.baseboard_fab2(sch_1):m_a_dqs_dp(7)") )
				( member ( signalRef "@baseboard_fab2_lib.baseboard_fab2(sch_1):m_a_dqs_dp(8)") )
				( member ( signalRef "@baseboard_fab2_lib.baseboard_fab2(sch_1):m_a_dqs_dp(9)") )
				( member ( signalRef "@baseboard_fab2_lib.baseboard_fab2(sch_1):m_a_dqs_dp(10)") )
				( member ( signalRef "@baseboard_fab2_lib.baseboard_fab2(sch_1):m_a_dqs_dp(11)") )
				( member ( signalRef "@baseboard_fab2_lib.baseboard_fab2(sch_1):m_a_dqs_dp(12)") )
				( member ( signalRef "@baseboard_fab2_lib.baseboard_fab2(sch_1):m_a_dqs_dp(13)") )
				( member ( signalRef "@baseboard_fab2_lib.baseboard_fab2(sch_1):m_a_dqs_dp(14)") )
				( member ( signalRef "@baseboard_fab2_lib.baseboard_fab2(sch_1):m_a_dqs_dp(15)") )
				( member ( signalRef "@baseboard_fab2_lib.baseboard_fab2(sch_1):m_a_dqs_dp(16)") )
				( member ( signalRef "@baseboard_fab2_lib.baseboard_fab2(sch_1):m_a_dqs_dp(17)") )
				( objectStatus "M_A_DQS_DP" )
			)
			( bus "@baseboard_fab2_lib.baseboard_fab2(sch_1):m_a_ecc"
				( memberType ( signal ) )
				( member ( signalRef "@baseboard_fab2_lib.baseboard_fab2(sch_1):m_a_ecc(0)") )
				( member ( signalRef "@baseboard_fab2_lib.baseboard_fab2(sch_1):m_a_ecc(1)") )
				( member ( signalRef "@baseboard_fab2_lib.baseboard_fab2(sch_1):m_a_ecc(2)") )
				( member ( signalRef "@baseboard_fab2_lib.baseboard_fab2(sch_1):m_a_ecc(3)") )
				( member ( signalRef "@baseboard_fab2_lib.baseboard_fab2(sch_1):m_a_ecc(4)") )
				( member ( signalRef "@baseboard_fab2_lib.baseboard_fab2(sch_1):m_a_ecc(5)") )
				( member ( signalRef "@baseboard_fab2_lib.baseboard_fab2(sch_1):m_a_ecc(6)") )
				( member ( signalRef "@baseboard_fab2_lib.baseboard_fab2(sch_1):m_a_ecc(7)") )
				( objectStatus "M_A_ECC" )
			)
			( bus "@baseboard_fab2_lib.baseboard_fab2(sch_1):m_a_ma"
				( memberType ( signal ) )
				( member ( signalRef "@baseboard_fab2_lib.baseboard_fab2(sch_1):m_a_ma(0)") )
				( member ( signalRef "@baseboard_fab2_lib.baseboard_fab2(sch_1):m_a_ma(1)") )
				( member ( signalRef "@baseboard_fab2_lib.baseboard_fab2(sch_1):m_a_ma(2)") )
				( member ( signalRef "@baseboard_fab2_lib.baseboard_fab2(sch_1):m_a_ma(3)") )
				( member ( signalRef "@baseboard_fab2_lib.baseboard_fab2(sch_1):m_a_ma(4)") )
				( member ( signalRef "@baseboard_fab2_lib.baseboard_fab2(sch_1):m_a_ma(5)") )
				( member ( signalRef "@baseboard_fab2_lib.baseboard_fab2(sch_1):m_a_ma(6)") )
				( member ( signalRef "@baseboard_fab2_lib.baseboard_fab2(sch_1):m_a_ma(7)") )
				( member ( signalRef "@baseboard_fab2_lib.baseboard_fab2(sch_1):m_a_ma(8)") )
				( member ( signalRef "@baseboard_fab2_lib.baseboard_fab2(sch_1):m_a_ma(9)") )
				( member ( signalRef "@baseboard_fab2_lib.baseboard_fab2(sch_1):m_a_ma(10)") )
				( member ( signalRef "@baseboard_fab2_lib.baseboard_fab2(sch_1):m_a_ma(11)") )
				( member ( signalRef "@baseboard_fab2_lib.baseboard_fab2(sch_1):m_a_ma(12)") )
				( member ( signalRef "@baseboard_fab2_lib.baseboard_fab2(sch_1):m_a_ma(13)") )
				( member ( signalRef "@baseboard_fab2_lib.baseboard_fab2(sch_1):m_a_ma(14)") )
				( member ( signalRef "@baseboard_fab2_lib.baseboard_fab2(sch_1):m_a_ma(15)") )
				( member ( signalRef "@baseboard_fab2_lib.baseboard_fab2(sch_1):m_a_ma(16)") )
				( member ( signalRef "@baseboard_fab2_lib.baseboard_fab2(sch_1):m_a_ma(17)") )
				( objectStatus "M_A_MA" )
			)
			( bus "@baseboard_fab2_lib.baseboard_fab2(sch_1):m_a_odt"
				( memberType ( signal ) )
				( member ( signalRef "@baseboard_fab2_lib.baseboard_fab2(sch_1):m_a_odt(0)") )
				( member ( signalRef "@baseboard_fab2_lib.baseboard_fab2(sch_1):m_a_odt(1)") )
				( member ( signalRef "@baseboard_fab2_lib.baseboard_fab2(sch_1):m_a_odt(2)") )
				( member ( signalRef "@baseboard_fab2_lib.baseboard_fab2(sch_1):m_a_odt(3)") )
				( objectStatus "M_A_ODT" )
			)
			( bus "@baseboard_fab2_lib.baseboard_fab2(sch_1):m_b_ba"
				( memberType ( signal ) )
				( member ( signalRef "@baseboard_fab2_lib.baseboard_fab2(sch_1):m_b_ba(0)") )
				( member ( signalRef "@baseboard_fab2_lib.baseboard_fab2(sch_1):m_b_ba(1)") )
				( objectStatus "M_B_BA" )
			)
			( bus "@baseboard_fab2_lib.baseboard_fab2(sch_1):m_b_bg"
				( memberType ( signal ) )
				( member ( signalRef "@baseboard_fab2_lib.baseboard_fab2(sch_1):m_b_bg(0)") )
				( member ( signalRef "@baseboard_fab2_lib.baseboard_fab2(sch_1):m_b_bg(1)") )
				( objectStatus "M_B_BG" )
			)
			( bus "@baseboard_fab2_lib.baseboard_fab2(sch_1):m_b_c"
				( memberType ( signal ) )
				( member ( signalRef "@baseboard_fab2_lib.baseboard_fab2(sch_1):m_b_c(2)") )
				( objectStatus "M_B_C" )
			)
			( bus "@baseboard_fab2_lib.baseboard_fab2(sch_1):m_b_cke"
				( memberType ( signal ) )
				( member ( signalRef "@baseboard_fab2_lib.baseboard_fab2(sch_1):m_b_cke(0)") )
				( member ( signalRef "@baseboard_fab2_lib.baseboard_fab2(sch_1):m_b_cke(1)") )
				( member ( signalRef "@baseboard_fab2_lib.baseboard_fab2(sch_1):m_b_cke(2)") )
				( member ( signalRef "@baseboard_fab2_lib.baseboard_fab2(sch_1):m_b_cke(3)") )
				( objectStatus "M_B_CKE" )
			)
			( bus "@baseboard_fab2_lib.baseboard_fab2(sch_1):m_b_clk_dn"
				( memberType ( signal ) )
				( member ( signalRef "@baseboard_fab2_lib.baseboard_fab2(sch_1):m_b_clk_dn(0)") )
				( member ( signalRef "@baseboard_fab2_lib.baseboard_fab2(sch_1):m_b_clk_dn(1)") )
				( member ( signalRef "@baseboard_fab2_lib.baseboard_fab2(sch_1):m_b_clk_dn(2)") )
				( member ( signalRef "@baseboard_fab2_lib.baseboard_fab2(sch_1):m_b_clk_dn(3)") )
				( objectStatus "M_B_CLK_DN" )
			)
			( bus "@baseboard_fab2_lib.baseboard_fab2(sch_1):m_b_clk_dp"
				( memberType ( signal ) )
				( member ( signalRef "@baseboard_fab2_lib.baseboard_fab2(sch_1):m_b_clk_dp(0)") )
				( member ( signalRef "@baseboard_fab2_lib.baseboard_fab2(sch_1):m_b_clk_dp(1)") )
				( member ( signalRef "@baseboard_fab2_lib.baseboard_fab2(sch_1):m_b_clk_dp(2)") )
				( member ( signalRef "@baseboard_fab2_lib.baseboard_fab2(sch_1):m_b_clk_dp(3)") )
				( objectStatus "M_B_CLK_DP" )
			)
			( bus "@baseboard_fab2_lib.baseboard_fab2(sch_1):m_b_cs_n"
				( memberType ( signal ) )
				( member ( signalRef "@baseboard_fab2_lib.baseboard_fab2(sch_1):m_b_cs_n(0)") )
				( member ( signalRef "@baseboard_fab2_lib.baseboard_fab2(sch_1):m_b_cs_n(1)") )
				( member ( signalRef "@baseboard_fab2_lib.baseboard_fab2(sch_1):m_b_cs_n(2)") )
				( member ( signalRef "@baseboard_fab2_lib.baseboard_fab2(sch_1):m_b_cs_n(3)") )
				( member ( signalRef "@baseboard_fab2_lib.baseboard_fab2(sch_1):m_b_cs_n(4)") )
				( member ( signalRef "@baseboard_fab2_lib.baseboard_fab2(sch_1):m_b_cs_n(5)") )
				( member ( signalRef "@baseboard_fab2_lib.baseboard_fab2(sch_1):m_b_cs_n(6)") )
				( member ( signalRef "@baseboard_fab2_lib.baseboard_fab2(sch_1):m_b_cs_n(7)") )
				( objectStatus "M_B_CS_N" )
			)
			( bus "@baseboard_fab2_lib.baseboard_fab2(sch_1):m_b_dq"
				( memberType ( signal ) )
				( member ( signalRef "@baseboard_fab2_lib.baseboard_fab2(sch_1):m_b_dq(0)") )
				( member ( signalRef "@baseboard_fab2_lib.baseboard_fab2(sch_1):m_b_dq(1)") )
				( member ( signalRef "@baseboard_fab2_lib.baseboard_fab2(sch_1):m_b_dq(2)") )
				( member ( signalRef "@baseboard_fab2_lib.baseboard_fab2(sch_1):m_b_dq(3)") )
				( member ( signalRef "@baseboard_fab2_lib.baseboard_fab2(sch_1):m_b_dq(4)") )
				( member ( signalRef "@baseboard_fab2_lib.baseboard_fab2(sch_1):m_b_dq(5)") )
				( member ( signalRef "@baseboard_fab2_lib.baseboard_fab2(sch_1):m_b_dq(6)") )
				( member ( signalRef "@baseboard_fab2_lib.baseboard_fab2(sch_1):m_b_dq(7)") )
				( member ( signalRef "@baseboard_fab2_lib.baseboard_fab2(sch_1):m_b_dq(8)") )
				( member ( signalRef "@baseboard_fab2_lib.baseboard_fab2(sch_1):m_b_dq(9)") )
				( member ( signalRef "@baseboard_fab2_lib.baseboard_fab2(sch_1):m_b_dq(10)") )
				( member ( signalRef "@baseboard_fab2_lib.baseboard_fab2(sch_1):m_b_dq(11)") )
				( member ( signalRef "@baseboard_fab2_lib.baseboard_fab2(sch_1):m_b_dq(12)") )
				( member ( signalRef "@baseboard_fab2_lib.baseboard_fab2(sch_1):m_b_dq(13)") )
				( member ( signalRef "@baseboard_fab2_lib.baseboard_fab2(sch_1):m_b_dq(14)") )
				( member ( signalRef "@baseboard_fab2_lib.baseboard_fab2(sch_1):m_b_dq(15)") )
				( member ( signalRef "@baseboard_fab2_lib.baseboard_fab2(sch_1):m_b_dq(16)") )
				( member ( signalRef "@baseboard_fab2_lib.baseboard_fab2(sch_1):m_b_dq(17)") )
				( member ( signalRef "@baseboard_fab2_lib.baseboard_fab2(sch_1):m_b_dq(18)") )
				( member ( signalRef "@baseboard_fab2_lib.baseboard_fab2(sch_1):m_b_dq(19)") )
				( member ( signalRef "@baseboard_fab2_lib.baseboard_fab2(sch_1):m_b_dq(20)") )
				( member ( signalRef "@baseboard_fab2_lib.baseboard_fab2(sch_1):m_b_dq(21)") )
				( member ( signalRef "@baseboard_fab2_lib.baseboard_fab2(sch_1):m_b_dq(22)") )
				( member ( signalRef "@baseboard_fab2_lib.baseboard_fab2(sch_1):m_b_dq(23)") )
				( member ( signalRef "@baseboard_fab2_lib.baseboard_fab2(sch_1):m_b_dq(24)") )
				( member ( signalRef "@baseboard_fab2_lib.baseboard_fab2(sch_1):m_b_dq(25)") )
				( member ( signalRef "@baseboard_fab2_lib.baseboard_fab2(sch_1):m_b_dq(26)") )
				( member ( signalRef "@baseboard_fab2_lib.baseboard_fab2(sch_1):m_b_dq(27)") )
				( member ( signalRef "@baseboard_fab2_lib.baseboard_fab2(sch_1):m_b_dq(28)") )
				( member ( signalRef "@baseboard_fab2_lib.baseboard_fab2(sch_1):m_b_dq(29)") )
				( member ( signalRef "@baseboard_fab2_lib.baseboard_fab2(sch_1):m_b_dq(30)") )
				( member ( signalRef "@baseboard_fab2_lib.baseboard_fab2(sch_1):m_b_dq(31)") )
				( member ( signalRef "@baseboard_fab2_lib.baseboard_fab2(sch_1):m_b_dq(32)") )
				( member ( signalRef "@baseboard_fab2_lib.baseboard_fab2(sch_1):m_b_dq(33)") )
				( member ( signalRef "@baseboard_fab2_lib.baseboard_fab2(sch_1):m_b_dq(34)") )
				( member ( signalRef "@baseboard_fab2_lib.baseboard_fab2(sch_1):m_b_dq(35)") )
				( member ( signalRef "@baseboard_fab2_lib.baseboard_fab2(sch_1):m_b_dq(36)") )
				( member ( signalRef "@baseboard_fab2_lib.baseboard_fab2(sch_1):m_b_dq(37)") )
				( member ( signalRef "@baseboard_fab2_lib.baseboard_fab2(sch_1):m_b_dq(38)") )
				( member ( signalRef "@baseboard_fab2_lib.baseboard_fab2(sch_1):m_b_dq(39)") )
				( member ( signalRef "@baseboard_fab2_lib.baseboard_fab2(sch_1):m_b_dq(40)") )
				( member ( signalRef "@baseboard_fab2_lib.baseboard_fab2(sch_1):m_b_dq(41)") )
				( member ( signalRef "@baseboard_fab2_lib.baseboard_fab2(sch_1):m_b_dq(42)") )
				( member ( signalRef "@baseboard_fab2_lib.baseboard_fab2(sch_1):m_b_dq(43)") )
				( member ( signalRef "@baseboard_fab2_lib.baseboard_fab2(sch_1):m_b_dq(44)") )
				( member ( signalRef "@baseboard_fab2_lib.baseboard_fab2(sch_1):m_b_dq(45)") )
				( member ( signalRef "@baseboard_fab2_lib.baseboard_fab2(sch_1):m_b_dq(46)") )
				( member ( signalRef "@baseboard_fab2_lib.baseboard_fab2(sch_1):m_b_dq(47)") )
				( member ( signalRef "@baseboard_fab2_lib.baseboard_fab2(sch_1):m_b_dq(48)") )
				( member ( signalRef "@baseboard_fab2_lib.baseboard_fab2(sch_1):m_b_dq(49)") )
				( member ( signalRef "@baseboard_fab2_lib.baseboard_fab2(sch_1):m_b_dq(50)") )
				( member ( signalRef "@baseboard_fab2_lib.baseboard_fab2(sch_1):m_b_dq(51)") )
				( member ( signalRef "@baseboard_fab2_lib.baseboard_fab2(sch_1):m_b_dq(52)") )
				( member ( signalRef "@baseboard_fab2_lib.baseboard_fab2(sch_1):m_b_dq(53)") )
				( member ( signalRef "@baseboard_fab2_lib.baseboard_fab2(sch_1):m_b_dq(54)") )
				( member ( signalRef "@baseboard_fab2_lib.baseboard_fab2(sch_1):m_b_dq(55)") )
				( member ( signalRef "@baseboard_fab2_lib.baseboard_fab2(sch_1):m_b_dq(56)") )
				( member ( signalRef "@baseboard_fab2_lib.baseboard_fab2(sch_1):m_b_dq(57)") )
				( member ( signalRef "@baseboard_fab2_lib.baseboard_fab2(sch_1):m_b_dq(58)") )
				( member ( signalRef "@baseboard_fab2_lib.baseboard_fab2(sch_1):m_b_dq(59)") )
				( member ( signalRef "@baseboard_fab2_lib.baseboard_fab2(sch_1):m_b_dq(60)") )
				( member ( signalRef "@baseboard_fab2_lib.baseboard_fab2(sch_1):m_b_dq(61)") )
				( member ( signalRef "@baseboard_fab2_lib.baseboard_fab2(sch_1):m_b_dq(62)") )
				( member ( signalRef "@baseboard_fab2_lib.baseboard_fab2(sch_1):m_b_dq(63)") )
				( objectStatus "M_B_DQ" )
			)
			( bus "@baseboard_fab2_lib.baseboard_fab2(sch_1):m_b_dqs_dn"
				( memberType ( signal ) )
				( member ( signalRef "@baseboard_fab2_lib.baseboard_fab2(sch_1):m_b_dqs_dn(0)") )
				( member ( signalRef "@baseboard_fab2_lib.baseboard_fab2(sch_1):m_b_dqs_dn(1)") )
				( member ( signalRef "@baseboard_fab2_lib.baseboard_fab2(sch_1):m_b_dqs_dn(2)") )
				( member ( signalRef "@baseboard_fab2_lib.baseboard_fab2(sch_1):m_b_dqs_dn(3)") )
				( member ( signalRef "@baseboard_fab2_lib.baseboard_fab2(sch_1):m_b_dqs_dn(4)") )
				( member ( signalRef "@baseboard_fab2_lib.baseboard_fab2(sch_1):m_b_dqs_dn(5)") )
				( member ( signalRef "@baseboard_fab2_lib.baseboard_fab2(sch_1):m_b_dqs_dn(6)") )
				( member ( signalRef "@baseboard_fab2_lib.baseboard_fab2(sch_1):m_b_dqs_dn(7)") )
				( member ( signalRef "@baseboard_fab2_lib.baseboard_fab2(sch_1):m_b_dqs_dn(8)") )
				( member ( signalRef "@baseboard_fab2_lib.baseboard_fab2(sch_1):m_b_dqs_dn(9)") )
				( member ( signalRef "@baseboard_fab2_lib.baseboard_fab2(sch_1):m_b_dqs_dn(10)") )
				( member ( signalRef "@baseboard_fab2_lib.baseboard_fab2(sch_1):m_b_dqs_dn(11)") )
				( member ( signalRef "@baseboard_fab2_lib.baseboard_fab2(sch_1):m_b_dqs_dn(12)") )
				( member ( signalRef "@baseboard_fab2_lib.baseboard_fab2(sch_1):m_b_dqs_dn(13)") )
				( member ( signalRef "@baseboard_fab2_lib.baseboard_fab2(sch_1):m_b_dqs_dn(14)") )
				( member ( signalRef "@baseboard_fab2_lib.baseboard_fab2(sch_1):m_b_dqs_dn(15)") )
				( member ( signalRef "@baseboard_fab2_lib.baseboard_fab2(sch_1):m_b_dqs_dn(16)") )
				( member ( signalRef "@baseboard_fab2_lib.baseboard_fab2(sch_1):m_b_dqs_dn(17)") )
				( objectStatus "M_B_DQS_DN" )
			)
			( bus "@baseboard_fab2_lib.baseboard_fab2(sch_1):m_b_dqs_dp"
				( memberType ( signal ) )
				( member ( signalRef "@baseboard_fab2_lib.baseboard_fab2(sch_1):m_b_dqs_dp(0)") )
				( member ( signalRef "@baseboard_fab2_lib.baseboard_fab2(sch_1):m_b_dqs_dp(1)") )
				( member ( signalRef "@baseboard_fab2_lib.baseboard_fab2(sch_1):m_b_dqs_dp(2)") )
				( member ( signalRef "@baseboard_fab2_lib.baseboard_fab2(sch_1):m_b_dqs_dp(3)") )
				( member ( signalRef "@baseboard_fab2_lib.baseboard_fab2(sch_1):m_b_dqs_dp(4)") )
				( member ( signalRef "@baseboard_fab2_lib.baseboard_fab2(sch_1):m_b_dqs_dp(5)") )
				( member ( signalRef "@baseboard_fab2_lib.baseboard_fab2(sch_1):m_b_dqs_dp(6)") )
				( member ( signalRef "@baseboard_fab2_lib.baseboard_fab2(sch_1):m_b_dqs_dp(7)") )
				( member ( signalRef "@baseboard_fab2_lib.baseboard_fab2(sch_1):m_b_dqs_dp(8)") )
				( member ( signalRef "@baseboard_fab2_lib.baseboard_fab2(sch_1):m_b_dqs_dp(9)") )
				( member ( signalRef "@baseboard_fab2_lib.baseboard_fab2(sch_1):m_b_dqs_dp(10)") )
				( member ( signalRef "@baseboard_fab2_lib.baseboard_fab2(sch_1):m_b_dqs_dp(11)") )
				( member ( signalRef "@baseboard_fab2_lib.baseboard_fab2(sch_1):m_b_dqs_dp(12)") )
				( member ( signalRef "@baseboard_fab2_lib.baseboard_fab2(sch_1):m_b_dqs_dp(13)") )
				( member ( signalRef "@baseboard_fab2_lib.baseboard_fab2(sch_1):m_b_dqs_dp(14)") )
				( member ( signalRef "@baseboard_fab2_lib.baseboard_fab2(sch_1):m_b_dqs_dp(15)") )
				( member ( signalRef "@baseboard_fab2_lib.baseboard_fab2(sch_1):m_b_dqs_dp(16)") )
				( member ( signalRef "@baseboard_fab2_lib.baseboard_fab2(sch_1):m_b_dqs_dp(17)") )
				( objectStatus "M_B_DQS_DP" )
			)
			( bus "@baseboard_fab2_lib.baseboard_fab2(sch_1):m_b_ecc"
				( memberType ( signal ) )
				( member ( signalRef "@baseboard_fab2_lib.baseboard_fab2(sch_1):m_b_ecc(0)") )
				( member ( signalRef "@baseboard_fab2_lib.baseboard_fab2(sch_1):m_b_ecc(1)") )
				( member ( signalRef "@baseboard_fab2_lib.baseboard_fab2(sch_1):m_b_ecc(2)") )
				( member ( signalRef "@baseboard_fab2_lib.baseboard_fab2(sch_1):m_b_ecc(3)") )
				( member ( signalRef "@baseboard_fab2_lib.baseboard_fab2(sch_1):m_b_ecc(4)") )
				( member ( signalRef "@baseboard_fab2_lib.baseboard_fab2(sch_1):m_b_ecc(5)") )
				( member ( signalRef "@baseboard_fab2_lib.baseboard_fab2(sch_1):m_b_ecc(6)") )
				( member ( signalRef "@baseboard_fab2_lib.baseboard_fab2(sch_1):m_b_ecc(7)") )
				( objectStatus "M_B_ECC" )
			)
			( bus "@baseboard_fab2_lib.baseboard_fab2(sch_1):m_b_ma"
				( memberType ( signal ) )
				( member ( signalRef "@baseboard_fab2_lib.baseboard_fab2(sch_1):m_b_ma(0)") )
				( member ( signalRef "@baseboard_fab2_lib.baseboard_fab2(sch_1):m_b_ma(1)") )
				( member ( signalRef "@baseboard_fab2_lib.baseboard_fab2(sch_1):m_b_ma(2)") )
				( member ( signalRef "@baseboard_fab2_lib.baseboard_fab2(sch_1):m_b_ma(3)") )
				( member ( signalRef "@baseboard_fab2_lib.baseboard_fab2(sch_1):m_b_ma(4)") )
				( member ( signalRef "@baseboard_fab2_lib.baseboard_fab2(sch_1):m_b_ma(5)") )
				( member ( signalRef "@baseboard_fab2_lib.baseboard_fab2(sch_1):m_b_ma(6)") )
				( member ( signalRef "@baseboard_fab2_lib.baseboard_fab2(sch_1):m_b_ma(7)") )
				( member ( signalRef "@baseboard_fab2_lib.baseboard_fab2(sch_1):m_b_ma(8)") )
				( member ( signalRef "@baseboard_fab2_lib.baseboard_fab2(sch_1):m_b_ma(9)") )
				( member ( signalRef "@baseboard_fab2_lib.baseboard_fab2(sch_1):m_b_ma(10)") )
				( member ( signalRef "@baseboard_fab2_lib.baseboard_fab2(sch_1):m_b_ma(11)") )
				( member ( signalRef "@baseboard_fab2_lib.baseboard_fab2(sch_1):m_b_ma(12)") )
				( member ( signalRef "@baseboard_fab2_lib.baseboard_fab2(sch_1):m_b_ma(13)") )
				( member ( signalRef "@baseboard_fab2_lib.baseboard_fab2(sch_1):m_b_ma(14)") )
				( member ( signalRef "@baseboard_fab2_lib.baseboard_fab2(sch_1):m_b_ma(15)") )
				( member ( signalRef "@baseboard_fab2_lib.baseboard_fab2(sch_1):m_b_ma(16)") )
				( member ( signalRef "@baseboard_fab2_lib.baseboard_fab2(sch_1):m_b_ma(17)") )
				( objectStatus "M_B_MA" )
			)
			( bus "@baseboard_fab2_lib.baseboard_fab2(sch_1):m_b_odt"
				( memberType ( signal ) )
				( member ( signalRef "@baseboard_fab2_lib.baseboard_fab2(sch_1):m_b_odt(0)") )
				( member ( signalRef "@baseboard_fab2_lib.baseboard_fab2(sch_1):m_b_odt(1)") )
				( member ( signalRef "@baseboard_fab2_lib.baseboard_fab2(sch_1):m_b_odt(2)") )
				( member ( signalRef "@baseboard_fab2_lib.baseboard_fab2(sch_1):m_b_odt(3)") )
				( objectStatus "M_B_ODT" )
			)
			( bus "@baseboard_fab2_lib.baseboard_fab2(sch_1):m_c_ba"
				( memberType ( signal ) )
				( member ( signalRef "@baseboard_fab2_lib.baseboard_fab2(sch_1):m_c_ba(0)") )
				( member ( signalRef "@baseboard_fab2_lib.baseboard_fab2(sch_1):m_c_ba(1)") )
				( objectStatus "M_C_BA" )
			)
			( bus "@baseboard_fab2_lib.baseboard_fab2(sch_1):m_c_bg"
				( memberType ( signal ) )
				( member ( signalRef "@baseboard_fab2_lib.baseboard_fab2(sch_1):m_c_bg(0)") )
				( member ( signalRef "@baseboard_fab2_lib.baseboard_fab2(sch_1):m_c_bg(1)") )
				( objectStatus "M_C_BG" )
			)
			( bus "@baseboard_fab2_lib.baseboard_fab2(sch_1):m_c_c"
				( memberType ( signal ) )
				( member ( signalRef "@baseboard_fab2_lib.baseboard_fab2(sch_1):m_c_c(2)") )
				( objectStatus "M_C_C" )
			)
			( bus "@baseboard_fab2_lib.baseboard_fab2(sch_1):m_c_cke"
				( memberType ( signal ) )
				( member ( signalRef "@baseboard_fab2_lib.baseboard_fab2(sch_1):m_c_cke(0)") )
				( member ( signalRef "@baseboard_fab2_lib.baseboard_fab2(sch_1):m_c_cke(1)") )
				( member ( signalRef "@baseboard_fab2_lib.baseboard_fab2(sch_1):m_c_cke(2)") )
				( member ( signalRef "@baseboard_fab2_lib.baseboard_fab2(sch_1):m_c_cke(3)") )
				( objectStatus "M_C_CKE" )
			)
			( bus "@baseboard_fab2_lib.baseboard_fab2(sch_1):m_c_clk_dn"
				( memberType ( signal ) )
				( member ( signalRef "@baseboard_fab2_lib.baseboard_fab2(sch_1):m_c_clk_dn(0)") )
				( member ( signalRef "@baseboard_fab2_lib.baseboard_fab2(sch_1):m_c_clk_dn(1)") )
				( member ( signalRef "@baseboard_fab2_lib.baseboard_fab2(sch_1):m_c_clk_dn(2)") )
				( member ( signalRef "@baseboard_fab2_lib.baseboard_fab2(sch_1):m_c_clk_dn(3)") )
				( objectStatus "M_C_CLK_DN" )
			)
			( bus "@baseboard_fab2_lib.baseboard_fab2(sch_1):m_c_clk_dp"
				( memberType ( signal ) )
				( member ( signalRef "@baseboard_fab2_lib.baseboard_fab2(sch_1):m_c_clk_dp(0)") )
				( member ( signalRef "@baseboard_fab2_lib.baseboard_fab2(sch_1):m_c_clk_dp(1)") )
				( member ( signalRef "@baseboard_fab2_lib.baseboard_fab2(sch_1):m_c_clk_dp(2)") )
				( member ( signalRef "@baseboard_fab2_lib.baseboard_fab2(sch_1):m_c_clk_dp(3)") )
				( objectStatus "M_C_CLK_DP" )
			)
			( bus "@baseboard_fab2_lib.baseboard_fab2(sch_1):m_c_cs_n"
				( memberType ( signal ) )
				( member ( signalRef "@baseboard_fab2_lib.baseboard_fab2(sch_1):m_c_cs_n(0)") )
				( member ( signalRef "@baseboard_fab2_lib.baseboard_fab2(sch_1):m_c_cs_n(1)") )
				( member ( signalRef "@baseboard_fab2_lib.baseboard_fab2(sch_1):m_c_cs_n(2)") )
				( member ( signalRef "@baseboard_fab2_lib.baseboard_fab2(sch_1):m_c_cs_n(3)") )
				( member ( signalRef "@baseboard_fab2_lib.baseboard_fab2(sch_1):m_c_cs_n(4)") )
				( member ( signalRef "@baseboard_fab2_lib.baseboard_fab2(sch_1):m_c_cs_n(5)") )
				( member ( signalRef "@baseboard_fab2_lib.baseboard_fab2(sch_1):m_c_cs_n(6)") )
				( member ( signalRef "@baseboard_fab2_lib.baseboard_fab2(sch_1):m_c_cs_n(7)") )
				( objectStatus "M_C_CS_N" )
			)
			( bus "@baseboard_fab2_lib.baseboard_fab2(sch_1):m_c_dq"
				( memberType ( signal ) )
				( member ( signalRef "@baseboard_fab2_lib.baseboard_fab2(sch_1):m_c_dq(0)") )
				( member ( signalRef "@baseboard_fab2_lib.baseboard_fab2(sch_1):m_c_dq(1)") )
				( member ( signalRef "@baseboard_fab2_lib.baseboard_fab2(sch_1):m_c_dq(2)") )
				( member ( signalRef "@baseboard_fab2_lib.baseboard_fab2(sch_1):m_c_dq(3)") )
				( member ( signalRef "@baseboard_fab2_lib.baseboard_fab2(sch_1):m_c_dq(4)") )
				( member ( signalRef "@baseboard_fab2_lib.baseboard_fab2(sch_1):m_c_dq(5)") )
				( member ( signalRef "@baseboard_fab2_lib.baseboard_fab2(sch_1):m_c_dq(6)") )
				( member ( signalRef "@baseboard_fab2_lib.baseboard_fab2(sch_1):m_c_dq(7)") )
				( member ( signalRef "@baseboard_fab2_lib.baseboard_fab2(sch_1):m_c_dq(8)") )
				( member ( signalRef "@baseboard_fab2_lib.baseboard_fab2(sch_1):m_c_dq(9)") )
				( member ( signalRef "@baseboard_fab2_lib.baseboard_fab2(sch_1):m_c_dq(10)") )
				( member ( signalRef "@baseboard_fab2_lib.baseboard_fab2(sch_1):m_c_dq(11)") )
				( member ( signalRef "@baseboard_fab2_lib.baseboard_fab2(sch_1):m_c_dq(12)") )
				( member ( signalRef "@baseboard_fab2_lib.baseboard_fab2(sch_1):m_c_dq(13)") )
				( member ( signalRef "@baseboard_fab2_lib.baseboard_fab2(sch_1):m_c_dq(14)") )
				( member ( signalRef "@baseboard_fab2_lib.baseboard_fab2(sch_1):m_c_dq(15)") )
				( member ( signalRef "@baseboard_fab2_lib.baseboard_fab2(sch_1):m_c_dq(16)") )
				( member ( signalRef "@baseboard_fab2_lib.baseboard_fab2(sch_1):m_c_dq(17)") )
				( member ( signalRef "@baseboard_fab2_lib.baseboard_fab2(sch_1):m_c_dq(18)") )
				( member ( signalRef "@baseboard_fab2_lib.baseboard_fab2(sch_1):m_c_dq(19)") )
				( member ( signalRef "@baseboard_fab2_lib.baseboard_fab2(sch_1):m_c_dq(20)") )
				( member ( signalRef "@baseboard_fab2_lib.baseboard_fab2(sch_1):m_c_dq(21)") )
				( member ( signalRef "@baseboard_fab2_lib.baseboard_fab2(sch_1):m_c_dq(22)") )
				( member ( signalRef "@baseboard_fab2_lib.baseboard_fab2(sch_1):m_c_dq(23)") )
				( member ( signalRef "@baseboard_fab2_lib.baseboard_fab2(sch_1):m_c_dq(24)") )
				( member ( signalRef "@baseboard_fab2_lib.baseboard_fab2(sch_1):m_c_dq(25)") )
				( member ( signalRef "@baseboard_fab2_lib.baseboard_fab2(sch_1):m_c_dq(26)") )
				( member ( signalRef "@baseboard_fab2_lib.baseboard_fab2(sch_1):m_c_dq(27)") )
				( member ( signalRef "@baseboard_fab2_lib.baseboard_fab2(sch_1):m_c_dq(28)") )
				( member ( signalRef "@baseboard_fab2_lib.baseboard_fab2(sch_1):m_c_dq(29)") )
				( member ( signalRef "@baseboard_fab2_lib.baseboard_fab2(sch_1):m_c_dq(30)") )
				( member ( signalRef "@baseboard_fab2_lib.baseboard_fab2(sch_1):m_c_dq(31)") )
				( member ( signalRef "@baseboard_fab2_lib.baseboard_fab2(sch_1):m_c_dq(32)") )
				( member ( signalRef "@baseboard_fab2_lib.baseboard_fab2(sch_1):m_c_dq(33)") )
				( member ( signalRef "@baseboard_fab2_lib.baseboard_fab2(sch_1):m_c_dq(34)") )
				( member ( signalRef "@baseboard_fab2_lib.baseboard_fab2(sch_1):m_c_dq(35)") )
				( member ( signalRef "@baseboard_fab2_lib.baseboard_fab2(sch_1):m_c_dq(36)") )
				( member ( signalRef "@baseboard_fab2_lib.baseboard_fab2(sch_1):m_c_dq(37)") )
				( member ( signalRef "@baseboard_fab2_lib.baseboard_fab2(sch_1):m_c_dq(38)") )
				( member ( signalRef "@baseboard_fab2_lib.baseboard_fab2(sch_1):m_c_dq(39)") )
				( member ( signalRef "@baseboard_fab2_lib.baseboard_fab2(sch_1):m_c_dq(40)") )
				( member ( signalRef "@baseboard_fab2_lib.baseboard_fab2(sch_1):m_c_dq(41)") )
				( member ( signalRef "@baseboard_fab2_lib.baseboard_fab2(sch_1):m_c_dq(42)") )
				( member ( signalRef "@baseboard_fab2_lib.baseboard_fab2(sch_1):m_c_dq(43)") )
				( member ( signalRef "@baseboard_fab2_lib.baseboard_fab2(sch_1):m_c_dq(44)") )
				( member ( signalRef "@baseboard_fab2_lib.baseboard_fab2(sch_1):m_c_dq(45)") )
				( member ( signalRef "@baseboard_fab2_lib.baseboard_fab2(sch_1):m_c_dq(46)") )
				( member ( signalRef "@baseboard_fab2_lib.baseboard_fab2(sch_1):m_c_dq(47)") )
				( member ( signalRef "@baseboard_fab2_lib.baseboard_fab2(sch_1):m_c_dq(48)") )
				( member ( signalRef "@baseboard_fab2_lib.baseboard_fab2(sch_1):m_c_dq(49)") )
				( member ( signalRef "@baseboard_fab2_lib.baseboard_fab2(sch_1):m_c_dq(50)") )
				( member ( signalRef "@baseboard_fab2_lib.baseboard_fab2(sch_1):m_c_dq(51)") )
				( member ( signalRef "@baseboard_fab2_lib.baseboard_fab2(sch_1):m_c_dq(52)") )
				( member ( signalRef "@baseboard_fab2_lib.baseboard_fab2(sch_1):m_c_dq(53)") )
				( member ( signalRef "@baseboard_fab2_lib.baseboard_fab2(sch_1):m_c_dq(54)") )
				( member ( signalRef "@baseboard_fab2_lib.baseboard_fab2(sch_1):m_c_dq(55)") )
				( member ( signalRef "@baseboard_fab2_lib.baseboard_fab2(sch_1):m_c_dq(56)") )
				( member ( signalRef "@baseboard_fab2_lib.baseboard_fab2(sch_1):m_c_dq(57)") )
				( member ( signalRef "@baseboard_fab2_lib.baseboard_fab2(sch_1):m_c_dq(58)") )
				( member ( signalRef "@baseboard_fab2_lib.baseboard_fab2(sch_1):m_c_dq(59)") )
				( member ( signalRef "@baseboard_fab2_lib.baseboard_fab2(sch_1):m_c_dq(60)") )
				( member ( signalRef "@baseboard_fab2_lib.baseboard_fab2(sch_1):m_c_dq(61)") )
				( member ( signalRef "@baseboard_fab2_lib.baseboard_fab2(sch_1):m_c_dq(62)") )
				( member ( signalRef "@baseboard_fab2_lib.baseboard_fab2(sch_1):m_c_dq(63)") )
				( objectStatus "M_C_DQ" )
			)
			( bus "@baseboard_fab2_lib.baseboard_fab2(sch_1):m_c_dqs_dn"
				( memberType ( signal ) )
				( member ( signalRef "@baseboard_fab2_lib.baseboard_fab2(sch_1):m_c_dqs_dn(0)") )
				( member ( signalRef "@baseboard_fab2_lib.baseboard_fab2(sch_1):m_c_dqs_dn(1)") )
				( member ( signalRef "@baseboard_fab2_lib.baseboard_fab2(sch_1):m_c_dqs_dn(2)") )
				( member ( signalRef "@baseboard_fab2_lib.baseboard_fab2(sch_1):m_c_dqs_dn(3)") )
				( member ( signalRef "@baseboard_fab2_lib.baseboard_fab2(sch_1):m_c_dqs_dn(4)") )
				( member ( signalRef "@baseboard_fab2_lib.baseboard_fab2(sch_1):m_c_dqs_dn(5)") )
				( member ( signalRef "@baseboard_fab2_lib.baseboard_fab2(sch_1):m_c_dqs_dn(6)") )
				( member ( signalRef "@baseboard_fab2_lib.baseboard_fab2(sch_1):m_c_dqs_dn(7)") )
				( member ( signalRef "@baseboard_fab2_lib.baseboard_fab2(sch_1):m_c_dqs_dn(8)") )
				( member ( signalRef "@baseboard_fab2_lib.baseboard_fab2(sch_1):m_c_dqs_dn(9)") )
				( member ( signalRef "@baseboard_fab2_lib.baseboard_fab2(sch_1):m_c_dqs_dn(10)") )
				( member ( signalRef "@baseboard_fab2_lib.baseboard_fab2(sch_1):m_c_dqs_dn(11)") )
				( member ( signalRef "@baseboard_fab2_lib.baseboard_fab2(sch_1):m_c_dqs_dn(12)") )
				( member ( signalRef "@baseboard_fab2_lib.baseboard_fab2(sch_1):m_c_dqs_dn(13)") )
				( member ( signalRef "@baseboard_fab2_lib.baseboard_fab2(sch_1):m_c_dqs_dn(14)") )
				( member ( signalRef "@baseboard_fab2_lib.baseboard_fab2(sch_1):m_c_dqs_dn(15)") )
				( member ( signalRef "@baseboard_fab2_lib.baseboard_fab2(sch_1):m_c_dqs_dn(16)") )
				( member ( signalRef "@baseboard_fab2_lib.baseboard_fab2(sch_1):m_c_dqs_dn(17)") )
				( objectStatus "M_C_DQS_DN" )
			)
			( bus "@baseboard_fab2_lib.baseboard_fab2(sch_1):m_c_dqs_dp"
				( memberType ( signal ) )
				( member ( signalRef "@baseboard_fab2_lib.baseboard_fab2(sch_1):m_c_dqs_dp(0)") )
				( member ( signalRef "@baseboard_fab2_lib.baseboard_fab2(sch_1):m_c_dqs_dp(1)") )
				( member ( signalRef "@baseboard_fab2_lib.baseboard_fab2(sch_1):m_c_dqs_dp(2)") )
				( member ( signalRef "@baseboard_fab2_lib.baseboard_fab2(sch_1):m_c_dqs_dp(3)") )
				( member ( signalRef "@baseboard_fab2_lib.baseboard_fab2(sch_1):m_c_dqs_dp(4)") )
				( member ( signalRef "@baseboard_fab2_lib.baseboard_fab2(sch_1):m_c_dqs_dp(5)") )
				( member ( signalRef "@baseboard_fab2_lib.baseboard_fab2(sch_1):m_c_dqs_dp(6)") )
				( member ( signalRef "@baseboard_fab2_lib.baseboard_fab2(sch_1):m_c_dqs_dp(7)") )
				( member ( signalRef "@baseboard_fab2_lib.baseboard_fab2(sch_1):m_c_dqs_dp(8)") )
				( member ( signalRef "@baseboard_fab2_lib.baseboard_fab2(sch_1):m_c_dqs_dp(9)") )
				( member ( signalRef "@baseboard_fab2_lib.baseboard_fab2(sch_1):m_c_dqs_dp(10)") )
				( member ( signalRef "@baseboard_fab2_lib.baseboard_fab2(sch_1):m_c_dqs_dp(11)") )
				( member ( signalRef "@baseboard_fab2_lib.baseboard_fab2(sch_1):m_c_dqs_dp(12)") )
				( member ( signalRef "@baseboard_fab2_lib.baseboard_fab2(sch_1):m_c_dqs_dp(13)") )
				( member ( signalRef "@baseboard_fab2_lib.baseboard_fab2(sch_1):m_c_dqs_dp(14)") )
				( member ( signalRef "@baseboard_fab2_lib.baseboard_fab2(sch_1):m_c_dqs_dp(15)") )
				( member ( signalRef "@baseboard_fab2_lib.baseboard_fab2(sch_1):m_c_dqs_dp(16)") )
				( member ( signalRef "@baseboard_fab2_lib.baseboard_fab2(sch_1):m_c_dqs_dp(17)") )
				( objectStatus "M_C_DQS_DP" )
			)
			( bus "@baseboard_fab2_lib.baseboard_fab2(sch_1):m_c_ecc"
				( memberType ( signal ) )
				( member ( signalRef "@baseboard_fab2_lib.baseboard_fab2(sch_1):m_c_ecc(0)") )
				( member ( signalRef "@baseboard_fab2_lib.baseboard_fab2(sch_1):m_c_ecc(1)") )
				( member ( signalRef "@baseboard_fab2_lib.baseboard_fab2(sch_1):m_c_ecc(2)") )
				( member ( signalRef "@baseboard_fab2_lib.baseboard_fab2(sch_1):m_c_ecc(3)") )
				( member ( signalRef "@baseboard_fab2_lib.baseboard_fab2(sch_1):m_c_ecc(4)") )
				( member ( signalRef "@baseboard_fab2_lib.baseboard_fab2(sch_1):m_c_ecc(5)") )
				( member ( signalRef "@baseboard_fab2_lib.baseboard_fab2(sch_1):m_c_ecc(6)") )
				( member ( signalRef "@baseboard_fab2_lib.baseboard_fab2(sch_1):m_c_ecc(7)") )
				( objectStatus "M_C_ECC" )
			)
			( bus "@baseboard_fab2_lib.baseboard_fab2(sch_1):m_c_ma"
				( memberType ( signal ) )
				( member ( signalRef "@baseboard_fab2_lib.baseboard_fab2(sch_1):m_c_ma(0)") )
				( member ( signalRef "@baseboard_fab2_lib.baseboard_fab2(sch_1):m_c_ma(1)") )
				( member ( signalRef "@baseboard_fab2_lib.baseboard_fab2(sch_1):m_c_ma(2)") )
				( member ( signalRef "@baseboard_fab2_lib.baseboard_fab2(sch_1):m_c_ma(3)") )
				( member ( signalRef "@baseboard_fab2_lib.baseboard_fab2(sch_1):m_c_ma(4)") )
				( member ( signalRef "@baseboard_fab2_lib.baseboard_fab2(sch_1):m_c_ma(5)") )
				( member ( signalRef "@baseboard_fab2_lib.baseboard_fab2(sch_1):m_c_ma(6)") )
				( member ( signalRef "@baseboard_fab2_lib.baseboard_fab2(sch_1):m_c_ma(7)") )
				( member ( signalRef "@baseboard_fab2_lib.baseboard_fab2(sch_1):m_c_ma(8)") )
				( member ( signalRef "@baseboard_fab2_lib.baseboard_fab2(sch_1):m_c_ma(9)") )
				( member ( signalRef "@baseboard_fab2_lib.baseboard_fab2(sch_1):m_c_ma(10)") )
				( member ( signalRef "@baseboard_fab2_lib.baseboard_fab2(sch_1):m_c_ma(11)") )
				( member ( signalRef "@baseboard_fab2_lib.baseboard_fab2(sch_1):m_c_ma(12)") )
				( member ( signalRef "@baseboard_fab2_lib.baseboard_fab2(sch_1):m_c_ma(13)") )
				( member ( signalRef "@baseboard_fab2_lib.baseboard_fab2(sch_1):m_c_ma(14)") )
				( member ( signalRef "@baseboard_fab2_lib.baseboard_fab2(sch_1):m_c_ma(15)") )
				( member ( signalRef "@baseboard_fab2_lib.baseboard_fab2(sch_1):m_c_ma(16)") )
				( member ( signalRef "@baseboard_fab2_lib.baseboard_fab2(sch_1):m_c_ma(17)") )
				( objectStatus "M_C_MA" )
			)
			( bus "@baseboard_fab2_lib.baseboard_fab2(sch_1):m_c_odt"
				( memberType ( signal ) )
				( member ( signalRef "@baseboard_fab2_lib.baseboard_fab2(sch_1):m_c_odt(0)") )
				( member ( signalRef "@baseboard_fab2_lib.baseboard_fab2(sch_1):m_c_odt(1)") )
				( member ( signalRef "@baseboard_fab2_lib.baseboard_fab2(sch_1):m_c_odt(2)") )
				( member ( signalRef "@baseboard_fab2_lib.baseboard_fab2(sch_1):m_c_odt(3)") )
				( objectStatus "M_C_ODT" )
			)
			( bus "@baseboard_fab2_lib.baseboard_fab2(sch_1):m_d_ba"
				( memberType ( signal ) )
				( member ( signalRef "@baseboard_fab2_lib.baseboard_fab2(sch_1):m_d_ba(0)") )
				( member ( signalRef "@baseboard_fab2_lib.baseboard_fab2(sch_1):m_d_ba(1)") )
				( objectStatus "M_D_BA" )
			)
			( bus "@baseboard_fab2_lib.baseboard_fab2(sch_1):m_d_bg"
				( memberType ( signal ) )
				( member ( signalRef "@baseboard_fab2_lib.baseboard_fab2(sch_1):m_d_bg(0)") )
				( member ( signalRef "@baseboard_fab2_lib.baseboard_fab2(sch_1):m_d_bg(1)") )
				( objectStatus "M_D_BG" )
			)
			( bus "@baseboard_fab2_lib.baseboard_fab2(sch_1):m_d_c"
				( memberType ( signal ) )
				( member ( signalRef "@baseboard_fab2_lib.baseboard_fab2(sch_1):m_d_c(2)") )
				( objectStatus "M_D_C" )
			)
			( bus "@baseboard_fab2_lib.baseboard_fab2(sch_1):m_d_cke"
				( memberType ( signal ) )
				( member ( signalRef "@baseboard_fab2_lib.baseboard_fab2(sch_1):m_d_cke(0)") )
				( member ( signalRef "@baseboard_fab2_lib.baseboard_fab2(sch_1):m_d_cke(1)") )
				( member ( signalRef "@baseboard_fab2_lib.baseboard_fab2(sch_1):m_d_cke(2)") )
				( member ( signalRef "@baseboard_fab2_lib.baseboard_fab2(sch_1):m_d_cke(3)") )
				( objectStatus "M_D_CKE" )
			)
			( bus "@baseboard_fab2_lib.baseboard_fab2(sch_1):m_d_clk_dn"
				( memberType ( signal ) )
				( member ( signalRef "@baseboard_fab2_lib.baseboard_fab2(sch_1):m_d_clk_dn(0)") )
				( member ( signalRef "@baseboard_fab2_lib.baseboard_fab2(sch_1):m_d_clk_dn(1)") )
				( member ( signalRef "@baseboard_fab2_lib.baseboard_fab2(sch_1):m_d_clk_dn(2)") )
				( member ( signalRef "@baseboard_fab2_lib.baseboard_fab2(sch_1):m_d_clk_dn(3)") )
				( objectStatus "M_D_CLK_DN" )
			)
			( bus "@baseboard_fab2_lib.baseboard_fab2(sch_1):m_d_clk_dp"
				( memberType ( signal ) )
				( member ( signalRef "@baseboard_fab2_lib.baseboard_fab2(sch_1):m_d_clk_dp(0)") )
				( member ( signalRef "@baseboard_fab2_lib.baseboard_fab2(sch_1):m_d_clk_dp(1)") )
				( member ( signalRef "@baseboard_fab2_lib.baseboard_fab2(sch_1):m_d_clk_dp(2)") )
				( member ( signalRef "@baseboard_fab2_lib.baseboard_fab2(sch_1):m_d_clk_dp(3)") )
				( objectStatus "M_D_CLK_DP" )
			)
			( bus "@baseboard_fab2_lib.baseboard_fab2(sch_1):m_d_cs_n"
				( memberType ( signal ) )
				( member ( signalRef "@baseboard_fab2_lib.baseboard_fab2(sch_1):m_d_cs_n(0)") )
				( member ( signalRef "@baseboard_fab2_lib.baseboard_fab2(sch_1):m_d_cs_n(1)") )
				( member ( signalRef "@baseboard_fab2_lib.baseboard_fab2(sch_1):m_d_cs_n(2)") )
				( member ( signalRef "@baseboard_fab2_lib.baseboard_fab2(sch_1):m_d_cs_n(3)") )
				( member ( signalRef "@baseboard_fab2_lib.baseboard_fab2(sch_1):m_d_cs_n(4)") )
				( member ( signalRef "@baseboard_fab2_lib.baseboard_fab2(sch_1):m_d_cs_n(5)") )
				( member ( signalRef "@baseboard_fab2_lib.baseboard_fab2(sch_1):m_d_cs_n(6)") )
				( member ( signalRef "@baseboard_fab2_lib.baseboard_fab2(sch_1):m_d_cs_n(7)") )
				( objectStatus "M_D_CS_N" )
			)
			( bus "@baseboard_fab2_lib.baseboard_fab2(sch_1):m_d_dq"
				( memberType ( signal ) )
				( member ( signalRef "@baseboard_fab2_lib.baseboard_fab2(sch_1):m_d_dq(0)") )
				( member ( signalRef "@baseboard_fab2_lib.baseboard_fab2(sch_1):m_d_dq(1)") )
				( member ( signalRef "@baseboard_fab2_lib.baseboard_fab2(sch_1):m_d_dq(2)") )
				( member ( signalRef "@baseboard_fab2_lib.baseboard_fab2(sch_1):m_d_dq(3)") )
				( member ( signalRef "@baseboard_fab2_lib.baseboard_fab2(sch_1):m_d_dq(4)") )
				( member ( signalRef "@baseboard_fab2_lib.baseboard_fab2(sch_1):m_d_dq(5)") )
				( member ( signalRef "@baseboard_fab2_lib.baseboard_fab2(sch_1):m_d_dq(6)") )
				( member ( signalRef "@baseboard_fab2_lib.baseboard_fab2(sch_1):m_d_dq(7)") )
				( member ( signalRef "@baseboard_fab2_lib.baseboard_fab2(sch_1):m_d_dq(8)") )
				( member ( signalRef "@baseboard_fab2_lib.baseboard_fab2(sch_1):m_d_dq(9)") )
				( member ( signalRef "@baseboard_fab2_lib.baseboard_fab2(sch_1):m_d_dq(10)") )
				( member ( signalRef "@baseboard_fab2_lib.baseboard_fab2(sch_1):m_d_dq(11)") )
				( member ( signalRef "@baseboard_fab2_lib.baseboard_fab2(sch_1):m_d_dq(12)") )
				( member ( signalRef "@baseboard_fab2_lib.baseboard_fab2(sch_1):m_d_dq(13)") )
				( member ( signalRef "@baseboard_fab2_lib.baseboard_fab2(sch_1):m_d_dq(14)") )
				( member ( signalRef "@baseboard_fab2_lib.baseboard_fab2(sch_1):m_d_dq(15)") )
				( member ( signalRef "@baseboard_fab2_lib.baseboard_fab2(sch_1):m_d_dq(16)") )
				( member ( signalRef "@baseboard_fab2_lib.baseboard_fab2(sch_1):m_d_dq(17)") )
				( member ( signalRef "@baseboard_fab2_lib.baseboard_fab2(sch_1):m_d_dq(18)") )
				( member ( signalRef "@baseboard_fab2_lib.baseboard_fab2(sch_1):m_d_dq(19)") )
				( member ( signalRef "@baseboard_fab2_lib.baseboard_fab2(sch_1):m_d_dq(20)") )
				( member ( signalRef "@baseboard_fab2_lib.baseboard_fab2(sch_1):m_d_dq(21)") )
				( member ( signalRef "@baseboard_fab2_lib.baseboard_fab2(sch_1):m_d_dq(22)") )
				( member ( signalRef "@baseboard_fab2_lib.baseboard_fab2(sch_1):m_d_dq(23)") )
				( member ( signalRef "@baseboard_fab2_lib.baseboard_fab2(sch_1):m_d_dq(24)") )
				( member ( signalRef "@baseboard_fab2_lib.baseboard_fab2(sch_1):m_d_dq(25)") )
				( member ( signalRef "@baseboard_fab2_lib.baseboard_fab2(sch_1):m_d_dq(26)") )
				( member ( signalRef "@baseboard_fab2_lib.baseboard_fab2(sch_1):m_d_dq(27)") )
				( member ( signalRef "@baseboard_fab2_lib.baseboard_fab2(sch_1):m_d_dq(28)") )
				( member ( signalRef "@baseboard_fab2_lib.baseboard_fab2(sch_1):m_d_dq(29)") )
				( member ( signalRef "@baseboard_fab2_lib.baseboard_fab2(sch_1):m_d_dq(30)") )
				( member ( signalRef "@baseboard_fab2_lib.baseboard_fab2(sch_1):m_d_dq(31)") )
				( member ( signalRef "@baseboard_fab2_lib.baseboard_fab2(sch_1):m_d_dq(32)") )
				( member ( signalRef "@baseboard_fab2_lib.baseboard_fab2(sch_1):m_d_dq(33)") )
				( member ( signalRef "@baseboard_fab2_lib.baseboard_fab2(sch_1):m_d_dq(34)") )
				( member ( signalRef "@baseboard_fab2_lib.baseboard_fab2(sch_1):m_d_dq(35)") )
				( member ( signalRef "@baseboard_fab2_lib.baseboard_fab2(sch_1):m_d_dq(36)") )
				( member ( signalRef "@baseboard_fab2_lib.baseboard_fab2(sch_1):m_d_dq(37)") )
				( member ( signalRef "@baseboard_fab2_lib.baseboard_fab2(sch_1):m_d_dq(38)") )
				( member ( signalRef "@baseboard_fab2_lib.baseboard_fab2(sch_1):m_d_dq(39)") )
				( member ( signalRef "@baseboard_fab2_lib.baseboard_fab2(sch_1):m_d_dq(40)") )
				( member ( signalRef "@baseboard_fab2_lib.baseboard_fab2(sch_1):m_d_dq(41)") )
				( member ( signalRef "@baseboard_fab2_lib.baseboard_fab2(sch_1):m_d_dq(42)") )
				( member ( signalRef "@baseboard_fab2_lib.baseboard_fab2(sch_1):m_d_dq(43)") )
				( member ( signalRef "@baseboard_fab2_lib.baseboard_fab2(sch_1):m_d_dq(44)") )
				( member ( signalRef "@baseboard_fab2_lib.baseboard_fab2(sch_1):m_d_dq(45)") )
				( member ( signalRef "@baseboard_fab2_lib.baseboard_fab2(sch_1):m_d_dq(46)") )
				( member ( signalRef "@baseboard_fab2_lib.baseboard_fab2(sch_1):m_d_dq(47)") )
				( member ( signalRef "@baseboard_fab2_lib.baseboard_fab2(sch_1):m_d_dq(48)") )
				( member ( signalRef "@baseboard_fab2_lib.baseboard_fab2(sch_1):m_d_dq(49)") )
				( member ( signalRef "@baseboard_fab2_lib.baseboard_fab2(sch_1):m_d_dq(50)") )
				( member ( signalRef "@baseboard_fab2_lib.baseboard_fab2(sch_1):m_d_dq(51)") )
				( member ( signalRef "@baseboard_fab2_lib.baseboard_fab2(sch_1):m_d_dq(52)") )
				( member ( signalRef "@baseboard_fab2_lib.baseboard_fab2(sch_1):m_d_dq(53)") )
				( member ( signalRef "@baseboard_fab2_lib.baseboard_fab2(sch_1):m_d_dq(54)") )
				( member ( signalRef "@baseboard_fab2_lib.baseboard_fab2(sch_1):m_d_dq(55)") )
				( member ( signalRef "@baseboard_fab2_lib.baseboard_fab2(sch_1):m_d_dq(56)") )
				( member ( signalRef "@baseboard_fab2_lib.baseboard_fab2(sch_1):m_d_dq(57)") )
				( member ( signalRef "@baseboard_fab2_lib.baseboard_fab2(sch_1):m_d_dq(58)") )
				( member ( signalRef "@baseboard_fab2_lib.baseboard_fab2(sch_1):m_d_dq(59)") )
				( member ( signalRef "@baseboard_fab2_lib.baseboard_fab2(sch_1):m_d_dq(60)") )
				( member ( signalRef "@baseboard_fab2_lib.baseboard_fab2(sch_1):m_d_dq(61)") )
				( member ( signalRef "@baseboard_fab2_lib.baseboard_fab2(sch_1):m_d_dq(62)") )
				( member ( signalRef "@baseboard_fab2_lib.baseboard_fab2(sch_1):m_d_dq(63)") )
				( objectStatus "M_D_DQ" )
			)
			( bus "@baseboard_fab2_lib.baseboard_fab2(sch_1):m_d_dqs_dn"
				( memberType ( signal ) )
				( member ( signalRef "@baseboard_fab2_lib.baseboard_fab2(sch_1):m_d_dqs_dn(0)") )
				( member ( signalRef "@baseboard_fab2_lib.baseboard_fab2(sch_1):m_d_dqs_dn(1)") )
				( member ( signalRef "@baseboard_fab2_lib.baseboard_fab2(sch_1):m_d_dqs_dn(2)") )
				( member ( signalRef "@baseboard_fab2_lib.baseboard_fab2(sch_1):m_d_dqs_dn(3)") )
				( member ( signalRef "@baseboard_fab2_lib.baseboard_fab2(sch_1):m_d_dqs_dn(4)") )
				( member ( signalRef "@baseboard_fab2_lib.baseboard_fab2(sch_1):m_d_dqs_dn(5)") )
				( member ( signalRef "@baseboard_fab2_lib.baseboard_fab2(sch_1):m_d_dqs_dn(6)") )
				( member ( signalRef "@baseboard_fab2_lib.baseboard_fab2(sch_1):m_d_dqs_dn(7)") )
				( member ( signalRef "@baseboard_fab2_lib.baseboard_fab2(sch_1):m_d_dqs_dn(8)") )
				( member ( signalRef "@baseboard_fab2_lib.baseboard_fab2(sch_1):m_d_dqs_dn(9)") )
				( member ( signalRef "@baseboard_fab2_lib.baseboard_fab2(sch_1):m_d_dqs_dn(10)") )
				( member ( signalRef "@baseboard_fab2_lib.baseboard_fab2(sch_1):m_d_dqs_dn(11)") )
				( member ( signalRef "@baseboard_fab2_lib.baseboard_fab2(sch_1):m_d_dqs_dn(12)") )
				( member ( signalRef "@baseboard_fab2_lib.baseboard_fab2(sch_1):m_d_dqs_dn(13)") )
				( member ( signalRef "@baseboard_fab2_lib.baseboard_fab2(sch_1):m_d_dqs_dn(14)") )
				( member ( signalRef "@baseboard_fab2_lib.baseboard_fab2(sch_1):m_d_dqs_dn(15)") )
				( member ( signalRef "@baseboard_fab2_lib.baseboard_fab2(sch_1):m_d_dqs_dn(16)") )
				( member ( signalRef "@baseboard_fab2_lib.baseboard_fab2(sch_1):m_d_dqs_dn(17)") )
				( objectStatus "M_D_DQS_DN" )
			)
			( bus "@baseboard_fab2_lib.baseboard_fab2(sch_1):m_d_dqs_dp"
				( memberType ( signal ) )
				( member ( signalRef "@baseboard_fab2_lib.baseboard_fab2(sch_1):m_d_dqs_dp(0)") )
				( member ( signalRef "@baseboard_fab2_lib.baseboard_fab2(sch_1):m_d_dqs_dp(1)") )
				( member ( signalRef "@baseboard_fab2_lib.baseboard_fab2(sch_1):m_d_dqs_dp(2)") )
				( member ( signalRef "@baseboard_fab2_lib.baseboard_fab2(sch_1):m_d_dqs_dp(3)") )
				( member ( signalRef "@baseboard_fab2_lib.baseboard_fab2(sch_1):m_d_dqs_dp(4)") )
				( member ( signalRef "@baseboard_fab2_lib.baseboard_fab2(sch_1):m_d_dqs_dp(5)") )
				( member ( signalRef "@baseboard_fab2_lib.baseboard_fab2(sch_1):m_d_dqs_dp(6)") )
				( member ( signalRef "@baseboard_fab2_lib.baseboard_fab2(sch_1):m_d_dqs_dp(7)") )
				( member ( signalRef "@baseboard_fab2_lib.baseboard_fab2(sch_1):m_d_dqs_dp(8)") )
				( member ( signalRef "@baseboard_fab2_lib.baseboard_fab2(sch_1):m_d_dqs_dp(9)") )
				( member ( signalRef "@baseboard_fab2_lib.baseboard_fab2(sch_1):m_d_dqs_dp(10)") )
				( member ( signalRef "@baseboard_fab2_lib.baseboard_fab2(sch_1):m_d_dqs_dp(11)") )
				( member ( signalRef "@baseboard_fab2_lib.baseboard_fab2(sch_1):m_d_dqs_dp(12)") )
				( member ( signalRef "@baseboard_fab2_lib.baseboard_fab2(sch_1):m_d_dqs_dp(13)") )
				( member ( signalRef "@baseboard_fab2_lib.baseboard_fab2(sch_1):m_d_dqs_dp(14)") )
				( member ( signalRef "@baseboard_fab2_lib.baseboard_fab2(sch_1):m_d_dqs_dp(15)") )
				( member ( signalRef "@baseboard_fab2_lib.baseboard_fab2(sch_1):m_d_dqs_dp(16)") )
				( member ( signalRef "@baseboard_fab2_lib.baseboard_fab2(sch_1):m_d_dqs_dp(17)") )
				( objectStatus "M_D_DQS_DP" )
			)
			( bus "@baseboard_fab2_lib.baseboard_fab2(sch_1):m_d_ecc"
				( memberType ( signal ) )
				( member ( signalRef "@baseboard_fab2_lib.baseboard_fab2(sch_1):m_d_ecc(0)") )
				( member ( signalRef "@baseboard_fab2_lib.baseboard_fab2(sch_1):m_d_ecc(1)") )
				( member ( signalRef "@baseboard_fab2_lib.baseboard_fab2(sch_1):m_d_ecc(2)") )
				( member ( signalRef "@baseboard_fab2_lib.baseboard_fab2(sch_1):m_d_ecc(3)") )
				( member ( signalRef "@baseboard_fab2_lib.baseboard_fab2(sch_1):m_d_ecc(4)") )
				( member ( signalRef "@baseboard_fab2_lib.baseboard_fab2(sch_1):m_d_ecc(5)") )
				( member ( signalRef "@baseboard_fab2_lib.baseboard_fab2(sch_1):m_d_ecc(6)") )
				( member ( signalRef "@baseboard_fab2_lib.baseboard_fab2(sch_1):m_d_ecc(7)") )
				( objectStatus "M_D_ECC" )
			)
			( bus "@baseboard_fab2_lib.baseboard_fab2(sch_1):m_d_ma"
				( memberType ( signal ) )
				( member ( signalRef "@baseboard_fab2_lib.baseboard_fab2(sch_1):m_d_ma(0)") )
				( member ( signalRef "@baseboard_fab2_lib.baseboard_fab2(sch_1):m_d_ma(1)") )
				( member ( signalRef "@baseboard_fab2_lib.baseboard_fab2(sch_1):m_d_ma(2)") )
				( member ( signalRef "@baseboard_fab2_lib.baseboard_fab2(sch_1):m_d_ma(3)") )
				( member ( signalRef "@baseboard_fab2_lib.baseboard_fab2(sch_1):m_d_ma(4)") )
				( member ( signalRef "@baseboard_fab2_lib.baseboard_fab2(sch_1):m_d_ma(5)") )
				( member ( signalRef "@baseboard_fab2_lib.baseboard_fab2(sch_1):m_d_ma(6)") )
				( member ( signalRef "@baseboard_fab2_lib.baseboard_fab2(sch_1):m_d_ma(7)") )
				( member ( signalRef "@baseboard_fab2_lib.baseboard_fab2(sch_1):m_d_ma(8)") )
				( member ( signalRef "@baseboard_fab2_lib.baseboard_fab2(sch_1):m_d_ma(9)") )
				( member ( signalRef "@baseboard_fab2_lib.baseboard_fab2(sch_1):m_d_ma(10)") )
				( member ( signalRef "@baseboard_fab2_lib.baseboard_fab2(sch_1):m_d_ma(11)") )
				( member ( signalRef "@baseboard_fab2_lib.baseboard_fab2(sch_1):m_d_ma(12)") )
				( member ( signalRef "@baseboard_fab2_lib.baseboard_fab2(sch_1):m_d_ma(13)") )
				( member ( signalRef "@baseboard_fab2_lib.baseboard_fab2(sch_1):m_d_ma(14)") )
				( member ( signalRef "@baseboard_fab2_lib.baseboard_fab2(sch_1):m_d_ma(15)") )
				( member ( signalRef "@baseboard_fab2_lib.baseboard_fab2(sch_1):m_d_ma(16)") )
				( member ( signalRef "@baseboard_fab2_lib.baseboard_fab2(sch_1):m_d_ma(17)") )
				( objectStatus "M_D_MA" )
			)
			( bus "@baseboard_fab2_lib.baseboard_fab2(sch_1):m_d_odt"
				( memberType ( signal ) )
				( member ( signalRef "@baseboard_fab2_lib.baseboard_fab2(sch_1):m_d_odt(0)") )
				( member ( signalRef "@baseboard_fab2_lib.baseboard_fab2(sch_1):m_d_odt(1)") )
				( member ( signalRef "@baseboard_fab2_lib.baseboard_fab2(sch_1):m_d_odt(2)") )
				( member ( signalRef "@baseboard_fab2_lib.baseboard_fab2(sch_1):m_d_odt(3)") )
				( objectStatus "M_D_ODT" )
			)
			( bus "@baseboard_fab2_lib.baseboard_fab2(sch_1):m_e_ba"
				( memberType ( signal ) )
				( member ( signalRef "@baseboard_fab2_lib.baseboard_fab2(sch_1):m_e_ba(0)") )
				( member ( signalRef "@baseboard_fab2_lib.baseboard_fab2(sch_1):m_e_ba(1)") )
				( objectStatus "M_E_BA" )
			)
			( bus "@baseboard_fab2_lib.baseboard_fab2(sch_1):m_e_bg"
				( memberType ( signal ) )
				( member ( signalRef "@baseboard_fab2_lib.baseboard_fab2(sch_1):m_e_bg(0)") )
				( member ( signalRef "@baseboard_fab2_lib.baseboard_fab2(sch_1):m_e_bg(1)") )
				( objectStatus "M_E_BG" )
			)
			( bus "@baseboard_fab2_lib.baseboard_fab2(sch_1):m_e_c"
				( memberType ( signal ) )
				( member ( signalRef "@baseboard_fab2_lib.baseboard_fab2(sch_1):m_e_c(2)") )
				( objectStatus "M_E_C" )
			)
			( bus "@baseboard_fab2_lib.baseboard_fab2(sch_1):m_e_cke"
				( memberType ( signal ) )
				( member ( signalRef "@baseboard_fab2_lib.baseboard_fab2(sch_1):m_e_cke(0)") )
				( member ( signalRef "@baseboard_fab2_lib.baseboard_fab2(sch_1):m_e_cke(1)") )
				( member ( signalRef "@baseboard_fab2_lib.baseboard_fab2(sch_1):m_e_cke(2)") )
				( member ( signalRef "@baseboard_fab2_lib.baseboard_fab2(sch_1):m_e_cke(3)") )
				( objectStatus "M_E_CKE" )
			)
			( bus "@baseboard_fab2_lib.baseboard_fab2(sch_1):m_e_clk_dn"
				( memberType ( signal ) )
				( member ( signalRef "@baseboard_fab2_lib.baseboard_fab2(sch_1):m_e_clk_dn(0)") )
				( member ( signalRef "@baseboard_fab2_lib.baseboard_fab2(sch_1):m_e_clk_dn(1)") )
				( member ( signalRef "@baseboard_fab2_lib.baseboard_fab2(sch_1):m_e_clk_dn(2)") )
				( member ( signalRef "@baseboard_fab2_lib.baseboard_fab2(sch_1):m_e_clk_dn(3)") )
				( objectStatus "M_E_CLK_DN" )
			)
			( bus "@baseboard_fab2_lib.baseboard_fab2(sch_1):m_e_clk_dp"
				( memberType ( signal ) )
				( member ( signalRef "@baseboard_fab2_lib.baseboard_fab2(sch_1):m_e_clk_dp(0)") )
				( member ( signalRef "@baseboard_fab2_lib.baseboard_fab2(sch_1):m_e_clk_dp(1)") )
				( member ( signalRef "@baseboard_fab2_lib.baseboard_fab2(sch_1):m_e_clk_dp(2)") )
				( member ( signalRef "@baseboard_fab2_lib.baseboard_fab2(sch_1):m_e_clk_dp(3)") )
				( objectStatus "M_E_CLK_DP" )
			)
			( bus "@baseboard_fab2_lib.baseboard_fab2(sch_1):m_e_cs_n"
				( memberType ( signal ) )
				( member ( signalRef "@baseboard_fab2_lib.baseboard_fab2(sch_1):m_e_cs_n(0)") )
				( member ( signalRef "@baseboard_fab2_lib.baseboard_fab2(sch_1):m_e_cs_n(1)") )
				( member ( signalRef "@baseboard_fab2_lib.baseboard_fab2(sch_1):m_e_cs_n(2)") )
				( member ( signalRef "@baseboard_fab2_lib.baseboard_fab2(sch_1):m_e_cs_n(3)") )
				( member ( signalRef "@baseboard_fab2_lib.baseboard_fab2(sch_1):m_e_cs_n(4)") )
				( member ( signalRef "@baseboard_fab2_lib.baseboard_fab2(sch_1):m_e_cs_n(5)") )
				( member ( signalRef "@baseboard_fab2_lib.baseboard_fab2(sch_1):m_e_cs_n(6)") )
				( member ( signalRef "@baseboard_fab2_lib.baseboard_fab2(sch_1):m_e_cs_n(7)") )
				( objectStatus "M_E_CS_N" )
			)
			( bus "@baseboard_fab2_lib.baseboard_fab2(sch_1):m_e_dq"
				( memberType ( signal ) )
				( member ( signalRef "@baseboard_fab2_lib.baseboard_fab2(sch_1):m_e_dq(0)") )
				( member ( signalRef "@baseboard_fab2_lib.baseboard_fab2(sch_1):m_e_dq(1)") )
				( member ( signalRef "@baseboard_fab2_lib.baseboard_fab2(sch_1):m_e_dq(2)") )
				( member ( signalRef "@baseboard_fab2_lib.baseboard_fab2(sch_1):m_e_dq(3)") )
				( member ( signalRef "@baseboard_fab2_lib.baseboard_fab2(sch_1):m_e_dq(4)") )
				( member ( signalRef "@baseboard_fab2_lib.baseboard_fab2(sch_1):m_e_dq(5)") )
				( member ( signalRef "@baseboard_fab2_lib.baseboard_fab2(sch_1):m_e_dq(6)") )
				( member ( signalRef "@baseboard_fab2_lib.baseboard_fab2(sch_1):m_e_dq(7)") )
				( member ( signalRef "@baseboard_fab2_lib.baseboard_fab2(sch_1):m_e_dq(8)") )
				( member ( signalRef "@baseboard_fab2_lib.baseboard_fab2(sch_1):m_e_dq(9)") )
				( member ( signalRef "@baseboard_fab2_lib.baseboard_fab2(sch_1):m_e_dq(10)") )
				( member ( signalRef "@baseboard_fab2_lib.baseboard_fab2(sch_1):m_e_dq(11)") )
				( member ( signalRef "@baseboard_fab2_lib.baseboard_fab2(sch_1):m_e_dq(12)") )
				( member ( signalRef "@baseboard_fab2_lib.baseboard_fab2(sch_1):m_e_dq(13)") )
				( member ( signalRef "@baseboard_fab2_lib.baseboard_fab2(sch_1):m_e_dq(14)") )
				( member ( signalRef "@baseboard_fab2_lib.baseboard_fab2(sch_1):m_e_dq(15)") )
				( member ( signalRef "@baseboard_fab2_lib.baseboard_fab2(sch_1):m_e_dq(16)") )
				( member ( signalRef "@baseboard_fab2_lib.baseboard_fab2(sch_1):m_e_dq(17)") )
				( member ( signalRef "@baseboard_fab2_lib.baseboard_fab2(sch_1):m_e_dq(18)") )
				( member ( signalRef "@baseboard_fab2_lib.baseboard_fab2(sch_1):m_e_dq(19)") )
				( member ( signalRef "@baseboard_fab2_lib.baseboard_fab2(sch_1):m_e_dq(20)") )
				( member ( signalRef "@baseboard_fab2_lib.baseboard_fab2(sch_1):m_e_dq(21)") )
				( member ( signalRef "@baseboard_fab2_lib.baseboard_fab2(sch_1):m_e_dq(22)") )
				( member ( signalRef "@baseboard_fab2_lib.baseboard_fab2(sch_1):m_e_dq(23)") )
				( member ( signalRef "@baseboard_fab2_lib.baseboard_fab2(sch_1):m_e_dq(24)") )
				( member ( signalRef "@baseboard_fab2_lib.baseboard_fab2(sch_1):m_e_dq(25)") )
				( member ( signalRef "@baseboard_fab2_lib.baseboard_fab2(sch_1):m_e_dq(26)") )
				( member ( signalRef "@baseboard_fab2_lib.baseboard_fab2(sch_1):m_e_dq(27)") )
				( member ( signalRef "@baseboard_fab2_lib.baseboard_fab2(sch_1):m_e_dq(28)") )
				( member ( signalRef "@baseboard_fab2_lib.baseboard_fab2(sch_1):m_e_dq(29)") )
				( member ( signalRef "@baseboard_fab2_lib.baseboard_fab2(sch_1):m_e_dq(30)") )
				( member ( signalRef "@baseboard_fab2_lib.baseboard_fab2(sch_1):m_e_dq(31)") )
				( member ( signalRef "@baseboard_fab2_lib.baseboard_fab2(sch_1):m_e_dq(32)") )
				( member ( signalRef "@baseboard_fab2_lib.baseboard_fab2(sch_1):m_e_dq(33)") )
				( member ( signalRef "@baseboard_fab2_lib.baseboard_fab2(sch_1):m_e_dq(34)") )
				( member ( signalRef "@baseboard_fab2_lib.baseboard_fab2(sch_1):m_e_dq(35)") )
				( member ( signalRef "@baseboard_fab2_lib.baseboard_fab2(sch_1):m_e_dq(36)") )
				( member ( signalRef "@baseboard_fab2_lib.baseboard_fab2(sch_1):m_e_dq(37)") )
				( member ( signalRef "@baseboard_fab2_lib.baseboard_fab2(sch_1):m_e_dq(38)") )
				( member ( signalRef "@baseboard_fab2_lib.baseboard_fab2(sch_1):m_e_dq(39)") )
				( member ( signalRef "@baseboard_fab2_lib.baseboard_fab2(sch_1):m_e_dq(40)") )
				( member ( signalRef "@baseboard_fab2_lib.baseboard_fab2(sch_1):m_e_dq(41)") )
				( member ( signalRef "@baseboard_fab2_lib.baseboard_fab2(sch_1):m_e_dq(42)") )
				( member ( signalRef "@baseboard_fab2_lib.baseboard_fab2(sch_1):m_e_dq(43)") )
				( member ( signalRef "@baseboard_fab2_lib.baseboard_fab2(sch_1):m_e_dq(44)") )
				( member ( signalRef "@baseboard_fab2_lib.baseboard_fab2(sch_1):m_e_dq(45)") )
				( member ( signalRef "@baseboard_fab2_lib.baseboard_fab2(sch_1):m_e_dq(46)") )
				( member ( signalRef "@baseboard_fab2_lib.baseboard_fab2(sch_1):m_e_dq(47)") )
				( member ( signalRef "@baseboard_fab2_lib.baseboard_fab2(sch_1):m_e_dq(48)") )
				( member ( signalRef "@baseboard_fab2_lib.baseboard_fab2(sch_1):m_e_dq(49)") )
				( member ( signalRef "@baseboard_fab2_lib.baseboard_fab2(sch_1):m_e_dq(50)") )
				( member ( signalRef "@baseboard_fab2_lib.baseboard_fab2(sch_1):m_e_dq(51)") )
				( member ( signalRef "@baseboard_fab2_lib.baseboard_fab2(sch_1):m_e_dq(52)") )
				( member ( signalRef "@baseboard_fab2_lib.baseboard_fab2(sch_1):m_e_dq(53)") )
				( member ( signalRef "@baseboard_fab2_lib.baseboard_fab2(sch_1):m_e_dq(54)") )
				( member ( signalRef "@baseboard_fab2_lib.baseboard_fab2(sch_1):m_e_dq(55)") )
				( member ( signalRef "@baseboard_fab2_lib.baseboard_fab2(sch_1):m_e_dq(56)") )
				( member ( signalRef "@baseboard_fab2_lib.baseboard_fab2(sch_1):m_e_dq(57)") )
				( member ( signalRef "@baseboard_fab2_lib.baseboard_fab2(sch_1):m_e_dq(58)") )
				( member ( signalRef "@baseboard_fab2_lib.baseboard_fab2(sch_1):m_e_dq(59)") )
				( member ( signalRef "@baseboard_fab2_lib.baseboard_fab2(sch_1):m_e_dq(60)") )
				( member ( signalRef "@baseboard_fab2_lib.baseboard_fab2(sch_1):m_e_dq(61)") )
				( member ( signalRef "@baseboard_fab2_lib.baseboard_fab2(sch_1):m_e_dq(62)") )
				( member ( signalRef "@baseboard_fab2_lib.baseboard_fab2(sch_1):m_e_dq(63)") )
				( objectStatus "M_E_DQ" )
			)
			( bus "@baseboard_fab2_lib.baseboard_fab2(sch_1):m_e_dqs_dn"
				( memberType ( signal ) )
				( member ( signalRef "@baseboard_fab2_lib.baseboard_fab2(sch_1):m_e_dqs_dn(0)") )
				( member ( signalRef "@baseboard_fab2_lib.baseboard_fab2(sch_1):m_e_dqs_dn(1)") )
				( member ( signalRef "@baseboard_fab2_lib.baseboard_fab2(sch_1):m_e_dqs_dn(2)") )
				( member ( signalRef "@baseboard_fab2_lib.baseboard_fab2(sch_1):m_e_dqs_dn(3)") )
				( member ( signalRef "@baseboard_fab2_lib.baseboard_fab2(sch_1):m_e_dqs_dn(4)") )
				( member ( signalRef "@baseboard_fab2_lib.baseboard_fab2(sch_1):m_e_dqs_dn(5)") )
				( member ( signalRef "@baseboard_fab2_lib.baseboard_fab2(sch_1):m_e_dqs_dn(6)") )
				( member ( signalRef "@baseboard_fab2_lib.baseboard_fab2(sch_1):m_e_dqs_dn(7)") )
				( member ( signalRef "@baseboard_fab2_lib.baseboard_fab2(sch_1):m_e_dqs_dn(8)") )
				( member ( signalRef "@baseboard_fab2_lib.baseboard_fab2(sch_1):m_e_dqs_dn(9)") )
				( member ( signalRef "@baseboard_fab2_lib.baseboard_fab2(sch_1):m_e_dqs_dn(10)") )
				( member ( signalRef "@baseboard_fab2_lib.baseboard_fab2(sch_1):m_e_dqs_dn(11)") )
				( member ( signalRef "@baseboard_fab2_lib.baseboard_fab2(sch_1):m_e_dqs_dn(12)") )
				( member ( signalRef "@baseboard_fab2_lib.baseboard_fab2(sch_1):m_e_dqs_dn(13)") )
				( member ( signalRef "@baseboard_fab2_lib.baseboard_fab2(sch_1):m_e_dqs_dn(14)") )
				( member ( signalRef "@baseboard_fab2_lib.baseboard_fab2(sch_1):m_e_dqs_dn(15)") )
				( member ( signalRef "@baseboard_fab2_lib.baseboard_fab2(sch_1):m_e_dqs_dn(16)") )
				( member ( signalRef "@baseboard_fab2_lib.baseboard_fab2(sch_1):m_e_dqs_dn(17)") )
				( objectStatus "M_E_DQS_DN" )
			)
			( bus "@baseboard_fab2_lib.baseboard_fab2(sch_1):m_e_dqs_dp"
				( memberType ( signal ) )
				( member ( signalRef "@baseboard_fab2_lib.baseboard_fab2(sch_1):m_e_dqs_dp(0)") )
				( member ( signalRef "@baseboard_fab2_lib.baseboard_fab2(sch_1):m_e_dqs_dp(1)") )
				( member ( signalRef "@baseboard_fab2_lib.baseboard_fab2(sch_1):m_e_dqs_dp(2)") )
				( member ( signalRef "@baseboard_fab2_lib.baseboard_fab2(sch_1):m_e_dqs_dp(3)") )
				( member ( signalRef "@baseboard_fab2_lib.baseboard_fab2(sch_1):m_e_dqs_dp(4)") )
				( member ( signalRef "@baseboard_fab2_lib.baseboard_fab2(sch_1):m_e_dqs_dp(5)") )
				( member ( signalRef "@baseboard_fab2_lib.baseboard_fab2(sch_1):m_e_dqs_dp(6)") )
				( member ( signalRef "@baseboard_fab2_lib.baseboard_fab2(sch_1):m_e_dqs_dp(7)") )
				( member ( signalRef "@baseboard_fab2_lib.baseboard_fab2(sch_1):m_e_dqs_dp(8)") )
				( member ( signalRef "@baseboard_fab2_lib.baseboard_fab2(sch_1):m_e_dqs_dp(9)") )
				( member ( signalRef "@baseboard_fab2_lib.baseboard_fab2(sch_1):m_e_dqs_dp(10)") )
				( member ( signalRef "@baseboard_fab2_lib.baseboard_fab2(sch_1):m_e_dqs_dp(11)") )
				( member ( signalRef "@baseboard_fab2_lib.baseboard_fab2(sch_1):m_e_dqs_dp(12)") )
				( member ( signalRef "@baseboard_fab2_lib.baseboard_fab2(sch_1):m_e_dqs_dp(13)") )
				( member ( signalRef "@baseboard_fab2_lib.baseboard_fab2(sch_1):m_e_dqs_dp(14)") )
				( member ( signalRef "@baseboard_fab2_lib.baseboard_fab2(sch_1):m_e_dqs_dp(15)") )
				( member ( signalRef "@baseboard_fab2_lib.baseboard_fab2(sch_1):m_e_dqs_dp(16)") )
				( member ( signalRef "@baseboard_fab2_lib.baseboard_fab2(sch_1):m_e_dqs_dp(17)") )
				( objectStatus "M_E_DQS_DP" )
			)
			( bus "@baseboard_fab2_lib.baseboard_fab2(sch_1):m_e_ecc"
				( memberType ( signal ) )
				( member ( signalRef "@baseboard_fab2_lib.baseboard_fab2(sch_1):m_e_ecc(0)") )
				( member ( signalRef "@baseboard_fab2_lib.baseboard_fab2(sch_1):m_e_ecc(1)") )
				( member ( signalRef "@baseboard_fab2_lib.baseboard_fab2(sch_1):m_e_ecc(2)") )
				( member ( signalRef "@baseboard_fab2_lib.baseboard_fab2(sch_1):m_e_ecc(3)") )
				( member ( signalRef "@baseboard_fab2_lib.baseboard_fab2(sch_1):m_e_ecc(4)") )
				( member ( signalRef "@baseboard_fab2_lib.baseboard_fab2(sch_1):m_e_ecc(5)") )
				( member ( signalRef "@baseboard_fab2_lib.baseboard_fab2(sch_1):m_e_ecc(6)") )
				( member ( signalRef "@baseboard_fab2_lib.baseboard_fab2(sch_1):m_e_ecc(7)") )
				( objectStatus "M_E_ECC" )
			)
			( bus "@baseboard_fab2_lib.baseboard_fab2(sch_1):m_e_ma"
				( memberType ( signal ) )
				( member ( signalRef "@baseboard_fab2_lib.baseboard_fab2(sch_1):m_e_ma(0)") )
				( member ( signalRef "@baseboard_fab2_lib.baseboard_fab2(sch_1):m_e_ma(1)") )
				( member ( signalRef "@baseboard_fab2_lib.baseboard_fab2(sch_1):m_e_ma(2)") )
				( member ( signalRef "@baseboard_fab2_lib.baseboard_fab2(sch_1):m_e_ma(3)") )
				( member ( signalRef "@baseboard_fab2_lib.baseboard_fab2(sch_1):m_e_ma(4)") )
				( member ( signalRef "@baseboard_fab2_lib.baseboard_fab2(sch_1):m_e_ma(5)") )
				( member ( signalRef "@baseboard_fab2_lib.baseboard_fab2(sch_1):m_e_ma(6)") )
				( member ( signalRef "@baseboard_fab2_lib.baseboard_fab2(sch_1):m_e_ma(7)") )
				( member ( signalRef "@baseboard_fab2_lib.baseboard_fab2(sch_1):m_e_ma(8)") )
				( member ( signalRef "@baseboard_fab2_lib.baseboard_fab2(sch_1):m_e_ma(9)") )
				( member ( signalRef "@baseboard_fab2_lib.baseboard_fab2(sch_1):m_e_ma(10)") )
				( member ( signalRef "@baseboard_fab2_lib.baseboard_fab2(sch_1):m_e_ma(11)") )
				( member ( signalRef "@baseboard_fab2_lib.baseboard_fab2(sch_1):m_e_ma(12)") )
				( member ( signalRef "@baseboard_fab2_lib.baseboard_fab2(sch_1):m_e_ma(13)") )
				( member ( signalRef "@baseboard_fab2_lib.baseboard_fab2(sch_1):m_e_ma(14)") )
				( member ( signalRef "@baseboard_fab2_lib.baseboard_fab2(sch_1):m_e_ma(15)") )
				( member ( signalRef "@baseboard_fab2_lib.baseboard_fab2(sch_1):m_e_ma(16)") )
				( member ( signalRef "@baseboard_fab2_lib.baseboard_fab2(sch_1):m_e_ma(17)") )
				( objectStatus "M_E_MA" )
			)
			( bus "@baseboard_fab2_lib.baseboard_fab2(sch_1):m_e_odt"
				( memberType ( signal ) )
				( member ( signalRef "@baseboard_fab2_lib.baseboard_fab2(sch_1):m_e_odt(0)") )
				( member ( signalRef "@baseboard_fab2_lib.baseboard_fab2(sch_1):m_e_odt(1)") )
				( member ( signalRef "@baseboard_fab2_lib.baseboard_fab2(sch_1):m_e_odt(2)") )
				( member ( signalRef "@baseboard_fab2_lib.baseboard_fab2(sch_1):m_e_odt(3)") )
				( objectStatus "M_E_ODT" )
			)
			( bus "@baseboard_fab2_lib.baseboard_fab2(sch_1):m_f_ba"
				( memberType ( signal ) )
				( member ( signalRef "@baseboard_fab2_lib.baseboard_fab2(sch_1):m_f_ba(0)") )
				( member ( signalRef "@baseboard_fab2_lib.baseboard_fab2(sch_1):m_f_ba(1)") )
				( objectStatus "M_F_BA" )
			)
			( bus "@baseboard_fab2_lib.baseboard_fab2(sch_1):m_f_bg"
				( memberType ( signal ) )
				( member ( signalRef "@baseboard_fab2_lib.baseboard_fab2(sch_1):m_f_bg(0)") )
				( member ( signalRef "@baseboard_fab2_lib.baseboard_fab2(sch_1):m_f_bg(1)") )
				( objectStatus "M_F_BG" )
			)
			( bus "@baseboard_fab2_lib.baseboard_fab2(sch_1):m_f_c"
				( memberType ( signal ) )
				( member ( signalRef "@baseboard_fab2_lib.baseboard_fab2(sch_1):m_f_c(2)") )
				( objectStatus "M_F_C" )
			)
			( bus "@baseboard_fab2_lib.baseboard_fab2(sch_1):m_f_cke"
				( memberType ( signal ) )
				( member ( signalRef "@baseboard_fab2_lib.baseboard_fab2(sch_1):m_f_cke(0)") )
				( member ( signalRef "@baseboard_fab2_lib.baseboard_fab2(sch_1):m_f_cke(1)") )
				( member ( signalRef "@baseboard_fab2_lib.baseboard_fab2(sch_1):m_f_cke(2)") )
				( member ( signalRef "@baseboard_fab2_lib.baseboard_fab2(sch_1):m_f_cke(3)") )
				( objectStatus "M_F_CKE" )
			)
			( bus "@baseboard_fab2_lib.baseboard_fab2(sch_1):m_f_clk_dn"
				( memberType ( signal ) )
				( member ( signalRef "@baseboard_fab2_lib.baseboard_fab2(sch_1):m_f_clk_dn(0)") )
				( member ( signalRef "@baseboard_fab2_lib.baseboard_fab2(sch_1):m_f_clk_dn(1)") )
				( member ( signalRef "@baseboard_fab2_lib.baseboard_fab2(sch_1):m_f_clk_dn(2)") )
				( member ( signalRef "@baseboard_fab2_lib.baseboard_fab2(sch_1):m_f_clk_dn(3)") )
				( objectStatus "M_F_CLK_DN" )
			)
			( bus "@baseboard_fab2_lib.baseboard_fab2(sch_1):m_f_clk_dp"
				( memberType ( signal ) )
				( member ( signalRef "@baseboard_fab2_lib.baseboard_fab2(sch_1):m_f_clk_dp(0)") )
				( member ( signalRef "@baseboard_fab2_lib.baseboard_fab2(sch_1):m_f_clk_dp(1)") )
				( member ( signalRef "@baseboard_fab2_lib.baseboard_fab2(sch_1):m_f_clk_dp(2)") )
				( member ( signalRef "@baseboard_fab2_lib.baseboard_fab2(sch_1):m_f_clk_dp(3)") )
				( objectStatus "M_F_CLK_DP" )
			)
			( bus "@baseboard_fab2_lib.baseboard_fab2(sch_1):m_f_cs_n"
				( memberType ( signal ) )
				( member ( signalRef "@baseboard_fab2_lib.baseboard_fab2(sch_1):m_f_cs_n(0)") )
				( member ( signalRef "@baseboard_fab2_lib.baseboard_fab2(sch_1):m_f_cs_n(1)") )
				( member ( signalRef "@baseboard_fab2_lib.baseboard_fab2(sch_1):m_f_cs_n(2)") )
				( member ( signalRef "@baseboard_fab2_lib.baseboard_fab2(sch_1):m_f_cs_n(3)") )
				( member ( signalRef "@baseboard_fab2_lib.baseboard_fab2(sch_1):m_f_cs_n(4)") )
				( member ( signalRef "@baseboard_fab2_lib.baseboard_fab2(sch_1):m_f_cs_n(5)") )
				( member ( signalRef "@baseboard_fab2_lib.baseboard_fab2(sch_1):m_f_cs_n(6)") )
				( member ( signalRef "@baseboard_fab2_lib.baseboard_fab2(sch_1):m_f_cs_n(7)") )
				( objectStatus "M_F_CS_N" )
			)
			( bus "@baseboard_fab2_lib.baseboard_fab2(sch_1):m_f_dq"
				( memberType ( signal ) )
				( member ( signalRef "@baseboard_fab2_lib.baseboard_fab2(sch_1):m_f_dq(0)") )
				( member ( signalRef "@baseboard_fab2_lib.baseboard_fab2(sch_1):m_f_dq(1)") )
				( member ( signalRef "@baseboard_fab2_lib.baseboard_fab2(sch_1):m_f_dq(2)") )
				( member ( signalRef "@baseboard_fab2_lib.baseboard_fab2(sch_1):m_f_dq(3)") )
				( member ( signalRef "@baseboard_fab2_lib.baseboard_fab2(sch_1):m_f_dq(4)") )
				( member ( signalRef "@baseboard_fab2_lib.baseboard_fab2(sch_1):m_f_dq(5)") )
				( member ( signalRef "@baseboard_fab2_lib.baseboard_fab2(sch_1):m_f_dq(6)") )
				( member ( signalRef "@baseboard_fab2_lib.baseboard_fab2(sch_1):m_f_dq(7)") )
				( member ( signalRef "@baseboard_fab2_lib.baseboard_fab2(sch_1):m_f_dq(8)") )
				( member ( signalRef "@baseboard_fab2_lib.baseboard_fab2(sch_1):m_f_dq(9)") )
				( member ( signalRef "@baseboard_fab2_lib.baseboard_fab2(sch_1):m_f_dq(10)") )
				( member ( signalRef "@baseboard_fab2_lib.baseboard_fab2(sch_1):m_f_dq(11)") )
				( member ( signalRef "@baseboard_fab2_lib.baseboard_fab2(sch_1):m_f_dq(12)") )
				( member ( signalRef "@baseboard_fab2_lib.baseboard_fab2(sch_1):m_f_dq(13)") )
				( member ( signalRef "@baseboard_fab2_lib.baseboard_fab2(sch_1):m_f_dq(14)") )
				( member ( signalRef "@baseboard_fab2_lib.baseboard_fab2(sch_1):m_f_dq(15)") )
				( member ( signalRef "@baseboard_fab2_lib.baseboard_fab2(sch_1):m_f_dq(16)") )
				( member ( signalRef "@baseboard_fab2_lib.baseboard_fab2(sch_1):m_f_dq(17)") )
				( member ( signalRef "@baseboard_fab2_lib.baseboard_fab2(sch_1):m_f_dq(18)") )
				( member ( signalRef "@baseboard_fab2_lib.baseboard_fab2(sch_1):m_f_dq(19)") )
				( member ( signalRef "@baseboard_fab2_lib.baseboard_fab2(sch_1):m_f_dq(20)") )
				( member ( signalRef "@baseboard_fab2_lib.baseboard_fab2(sch_1):m_f_dq(21)") )
				( member ( signalRef "@baseboard_fab2_lib.baseboard_fab2(sch_1):m_f_dq(22)") )
				( member ( signalRef "@baseboard_fab2_lib.baseboard_fab2(sch_1):m_f_dq(23)") )
				( member ( signalRef "@baseboard_fab2_lib.baseboard_fab2(sch_1):m_f_dq(24)") )
				( member ( signalRef "@baseboard_fab2_lib.baseboard_fab2(sch_1):m_f_dq(25)") )
				( member ( signalRef "@baseboard_fab2_lib.baseboard_fab2(sch_1):m_f_dq(26)") )
				( member ( signalRef "@baseboard_fab2_lib.baseboard_fab2(sch_1):m_f_dq(27)") )
				( member ( signalRef "@baseboard_fab2_lib.baseboard_fab2(sch_1):m_f_dq(28)") )
				( member ( signalRef "@baseboard_fab2_lib.baseboard_fab2(sch_1):m_f_dq(29)") )
				( member ( signalRef "@baseboard_fab2_lib.baseboard_fab2(sch_1):m_f_dq(30)") )
				( member ( signalRef "@baseboard_fab2_lib.baseboard_fab2(sch_1):m_f_dq(31)") )
				( member ( signalRef "@baseboard_fab2_lib.baseboard_fab2(sch_1):m_f_dq(32)") )
				( member ( signalRef "@baseboard_fab2_lib.baseboard_fab2(sch_1):m_f_dq(33)") )
				( member ( signalRef "@baseboard_fab2_lib.baseboard_fab2(sch_1):m_f_dq(34)") )
				( member ( signalRef "@baseboard_fab2_lib.baseboard_fab2(sch_1):m_f_dq(35)") )
				( member ( signalRef "@baseboard_fab2_lib.baseboard_fab2(sch_1):m_f_dq(36)") )
				( member ( signalRef "@baseboard_fab2_lib.baseboard_fab2(sch_1):m_f_dq(37)") )
				( member ( signalRef "@baseboard_fab2_lib.baseboard_fab2(sch_1):m_f_dq(38)") )
				( member ( signalRef "@baseboard_fab2_lib.baseboard_fab2(sch_1):m_f_dq(39)") )
				( member ( signalRef "@baseboard_fab2_lib.baseboard_fab2(sch_1):m_f_dq(40)") )
				( member ( signalRef "@baseboard_fab2_lib.baseboard_fab2(sch_1):m_f_dq(41)") )
				( member ( signalRef "@baseboard_fab2_lib.baseboard_fab2(sch_1):m_f_dq(42)") )
				( member ( signalRef "@baseboard_fab2_lib.baseboard_fab2(sch_1):m_f_dq(43)") )
				( member ( signalRef "@baseboard_fab2_lib.baseboard_fab2(sch_1):m_f_dq(44)") )
				( member ( signalRef "@baseboard_fab2_lib.baseboard_fab2(sch_1):m_f_dq(45)") )
				( member ( signalRef "@baseboard_fab2_lib.baseboard_fab2(sch_1):m_f_dq(46)") )
				( member ( signalRef "@baseboard_fab2_lib.baseboard_fab2(sch_1):m_f_dq(47)") )
				( member ( signalRef "@baseboard_fab2_lib.baseboard_fab2(sch_1):m_f_dq(48)") )
				( member ( signalRef "@baseboard_fab2_lib.baseboard_fab2(sch_1):m_f_dq(49)") )
				( member ( signalRef "@baseboard_fab2_lib.baseboard_fab2(sch_1):m_f_dq(50)") )
				( member ( signalRef "@baseboard_fab2_lib.baseboard_fab2(sch_1):m_f_dq(51)") )
				( member ( signalRef "@baseboard_fab2_lib.baseboard_fab2(sch_1):m_f_dq(52)") )
				( member ( signalRef "@baseboard_fab2_lib.baseboard_fab2(sch_1):m_f_dq(53)") )
				( member ( signalRef "@baseboard_fab2_lib.baseboard_fab2(sch_1):m_f_dq(54)") )
				( member ( signalRef "@baseboard_fab2_lib.baseboard_fab2(sch_1):m_f_dq(55)") )
				( member ( signalRef "@baseboard_fab2_lib.baseboard_fab2(sch_1):m_f_dq(56)") )
				( member ( signalRef "@baseboard_fab2_lib.baseboard_fab2(sch_1):m_f_dq(57)") )
				( member ( signalRef "@baseboard_fab2_lib.baseboard_fab2(sch_1):m_f_dq(58)") )
				( member ( signalRef "@baseboard_fab2_lib.baseboard_fab2(sch_1):m_f_dq(59)") )
				( member ( signalRef "@baseboard_fab2_lib.baseboard_fab2(sch_1):m_f_dq(60)") )
				( member ( signalRef "@baseboard_fab2_lib.baseboard_fab2(sch_1):m_f_dq(61)") )
				( member ( signalRef "@baseboard_fab2_lib.baseboard_fab2(sch_1):m_f_dq(62)") )
				( member ( signalRef "@baseboard_fab2_lib.baseboard_fab2(sch_1):m_f_dq(63)") )
				( objectStatus "M_F_DQ" )
			)
			( bus "@baseboard_fab2_lib.baseboard_fab2(sch_1):m_f_dqs_dn"
				( memberType ( signal ) )
				( member ( signalRef "@baseboard_fab2_lib.baseboard_fab2(sch_1):m_f_dqs_dn(0)") )
				( member ( signalRef "@baseboard_fab2_lib.baseboard_fab2(sch_1):m_f_dqs_dn(1)") )
				( member ( signalRef "@baseboard_fab2_lib.baseboard_fab2(sch_1):m_f_dqs_dn(2)") )
				( member ( signalRef "@baseboard_fab2_lib.baseboard_fab2(sch_1):m_f_dqs_dn(3)") )
				( member ( signalRef "@baseboard_fab2_lib.baseboard_fab2(sch_1):m_f_dqs_dn(4)") )
				( member ( signalRef "@baseboard_fab2_lib.baseboard_fab2(sch_1):m_f_dqs_dn(5)") )
				( member ( signalRef "@baseboard_fab2_lib.baseboard_fab2(sch_1):m_f_dqs_dn(6)") )
				( member ( signalRef "@baseboard_fab2_lib.baseboard_fab2(sch_1):m_f_dqs_dn(7)") )
				( member ( signalRef "@baseboard_fab2_lib.baseboard_fab2(sch_1):m_f_dqs_dn(8)") )
				( member ( signalRef "@baseboard_fab2_lib.baseboard_fab2(sch_1):m_f_dqs_dn(9)") )
				( member ( signalRef "@baseboard_fab2_lib.baseboard_fab2(sch_1):m_f_dqs_dn(10)") )
				( member ( signalRef "@baseboard_fab2_lib.baseboard_fab2(sch_1):m_f_dqs_dn(11)") )
				( member ( signalRef "@baseboard_fab2_lib.baseboard_fab2(sch_1):m_f_dqs_dn(12)") )
				( member ( signalRef "@baseboard_fab2_lib.baseboard_fab2(sch_1):m_f_dqs_dn(13)") )
				( member ( signalRef "@baseboard_fab2_lib.baseboard_fab2(sch_1):m_f_dqs_dn(14)") )
				( member ( signalRef "@baseboard_fab2_lib.baseboard_fab2(sch_1):m_f_dqs_dn(15)") )
				( member ( signalRef "@baseboard_fab2_lib.baseboard_fab2(sch_1):m_f_dqs_dn(16)") )
				( member ( signalRef "@baseboard_fab2_lib.baseboard_fab2(sch_1):m_f_dqs_dn(17)") )
				( objectStatus "M_F_DQS_DN" )
			)
			( bus "@baseboard_fab2_lib.baseboard_fab2(sch_1):m_f_dqs_dp"
				( memberType ( signal ) )
				( member ( signalRef "@baseboard_fab2_lib.baseboard_fab2(sch_1):m_f_dqs_dp(0)") )
				( member ( signalRef "@baseboard_fab2_lib.baseboard_fab2(sch_1):m_f_dqs_dp(1)") )
				( member ( signalRef "@baseboard_fab2_lib.baseboard_fab2(sch_1):m_f_dqs_dp(2)") )
				( member ( signalRef "@baseboard_fab2_lib.baseboard_fab2(sch_1):m_f_dqs_dp(3)") )
				( member ( signalRef "@baseboard_fab2_lib.baseboard_fab2(sch_1):m_f_dqs_dp(4)") )
				( member ( signalRef "@baseboard_fab2_lib.baseboard_fab2(sch_1):m_f_dqs_dp(5)") )
				( member ( signalRef "@baseboard_fab2_lib.baseboard_fab2(sch_1):m_f_dqs_dp(6)") )
				( member ( signalRef "@baseboard_fab2_lib.baseboard_fab2(sch_1):m_f_dqs_dp(7)") )
				( member ( signalRef "@baseboard_fab2_lib.baseboard_fab2(sch_1):m_f_dqs_dp(8)") )
				( member ( signalRef "@baseboard_fab2_lib.baseboard_fab2(sch_1):m_f_dqs_dp(9)") )
				( member ( signalRef "@baseboard_fab2_lib.baseboard_fab2(sch_1):m_f_dqs_dp(10)") )
				( member ( signalRef "@baseboard_fab2_lib.baseboard_fab2(sch_1):m_f_dqs_dp(11)") )
				( member ( signalRef "@baseboard_fab2_lib.baseboard_fab2(sch_1):m_f_dqs_dp(12)") )
				( member ( signalRef "@baseboard_fab2_lib.baseboard_fab2(sch_1):m_f_dqs_dp(13)") )
				( member ( signalRef "@baseboard_fab2_lib.baseboard_fab2(sch_1):m_f_dqs_dp(14)") )
				( member ( signalRef "@baseboard_fab2_lib.baseboard_fab2(sch_1):m_f_dqs_dp(15)") )
				( member ( signalRef "@baseboard_fab2_lib.baseboard_fab2(sch_1):m_f_dqs_dp(16)") )
				( member ( signalRef "@baseboard_fab2_lib.baseboard_fab2(sch_1):m_f_dqs_dp(17)") )
				( objectStatus "M_F_DQS_DP" )
			)
			( bus "@baseboard_fab2_lib.baseboard_fab2(sch_1):m_f_ecc"
				( memberType ( signal ) )
				( member ( signalRef "@baseboard_fab2_lib.baseboard_fab2(sch_1):m_f_ecc(0)") )
				( member ( signalRef "@baseboard_fab2_lib.baseboard_fab2(sch_1):m_f_ecc(1)") )
				( member ( signalRef "@baseboard_fab2_lib.baseboard_fab2(sch_1):m_f_ecc(2)") )
				( member ( signalRef "@baseboard_fab2_lib.baseboard_fab2(sch_1):m_f_ecc(3)") )
				( member ( signalRef "@baseboard_fab2_lib.baseboard_fab2(sch_1):m_f_ecc(4)") )
				( member ( signalRef "@baseboard_fab2_lib.baseboard_fab2(sch_1):m_f_ecc(5)") )
				( member ( signalRef "@baseboard_fab2_lib.baseboard_fab2(sch_1):m_f_ecc(6)") )
				( member ( signalRef "@baseboard_fab2_lib.baseboard_fab2(sch_1):m_f_ecc(7)") )
				( objectStatus "M_F_ECC" )
			)
			( bus "@baseboard_fab2_lib.baseboard_fab2(sch_1):m_f_ma"
				( memberType ( signal ) )
				( member ( signalRef "@baseboard_fab2_lib.baseboard_fab2(sch_1):m_f_ma(0)") )
				( member ( signalRef "@baseboard_fab2_lib.baseboard_fab2(sch_1):m_f_ma(1)") )
				( member ( signalRef "@baseboard_fab2_lib.baseboard_fab2(sch_1):m_f_ma(2)") )
				( member ( signalRef "@baseboard_fab2_lib.baseboard_fab2(sch_1):m_f_ma(3)") )
				( member ( signalRef "@baseboard_fab2_lib.baseboard_fab2(sch_1):m_f_ma(4)") )
				( member ( signalRef "@baseboard_fab2_lib.baseboard_fab2(sch_1):m_f_ma(5)") )
				( member ( signalRef "@baseboard_fab2_lib.baseboard_fab2(sch_1):m_f_ma(6)") )
				( member ( signalRef "@baseboard_fab2_lib.baseboard_fab2(sch_1):m_f_ma(7)") )
				( member ( signalRef "@baseboard_fab2_lib.baseboard_fab2(sch_1):m_f_ma(8)") )
				( member ( signalRef "@baseboard_fab2_lib.baseboard_fab2(sch_1):m_f_ma(9)") )
				( member ( signalRef "@baseboard_fab2_lib.baseboard_fab2(sch_1):m_f_ma(10)") )
				( member ( signalRef "@baseboard_fab2_lib.baseboard_fab2(sch_1):m_f_ma(11)") )
				( member ( signalRef "@baseboard_fab2_lib.baseboard_fab2(sch_1):m_f_ma(12)") )
				( member ( signalRef "@baseboard_fab2_lib.baseboard_fab2(sch_1):m_f_ma(13)") )
				( member ( signalRef "@baseboard_fab2_lib.baseboard_fab2(sch_1):m_f_ma(14)") )
				( member ( signalRef "@baseboard_fab2_lib.baseboard_fab2(sch_1):m_f_ma(15)") )
				( member ( signalRef "@baseboard_fab2_lib.baseboard_fab2(sch_1):m_f_ma(16)") )
				( member ( signalRef "@baseboard_fab2_lib.baseboard_fab2(sch_1):m_f_ma(17)") )
				( objectStatus "M_F_MA" )
			)
			( bus "@baseboard_fab2_lib.baseboard_fab2(sch_1):m_f_odt"
				( memberType ( signal ) )
				( member ( signalRef "@baseboard_fab2_lib.baseboard_fab2(sch_1):m_f_odt(0)") )
				( member ( signalRef "@baseboard_fab2_lib.baseboard_fab2(sch_1):m_f_odt(1)") )
				( member ( signalRef "@baseboard_fab2_lib.baseboard_fab2(sch_1):m_f_odt(2)") )
				( member ( signalRef "@baseboard_fab2_lib.baseboard_fab2(sch_1):m_f_odt(3)") )
				( objectStatus "M_F_ODT" )
			)
			( bus "@baseboard_fab2_lib.baseboard_fab2(sch_1):dmi_cpu0_pch_rx_c_dn"
				( memberType ( signal ) )
				( member ( signalRef "@baseboard_fab2_lib.baseboard_fab2(sch_1):dmi_cpu0_pch_rx_c_dn(0)") )
				( member ( signalRef "@baseboard_fab2_lib.baseboard_fab2(sch_1):dmi_cpu0_pch_rx_c_dn(1)") )
				( member ( signalRef "@baseboard_fab2_lib.baseboard_fab2(sch_1):dmi_cpu0_pch_rx_c_dn(2)") )
				( member ( signalRef "@baseboard_fab2_lib.baseboard_fab2(sch_1):dmi_cpu0_pch_rx_c_dn(3)") )
				( objectStatus "DMI_CPU0_PCH_RX_C_DN" )
			)
			( bus "@baseboard_fab2_lib.baseboard_fab2(sch_1):dmi_cpu0_pch_rx_c_dp"
				( memberType ( signal ) )
				( member ( signalRef "@baseboard_fab2_lib.baseboard_fab2(sch_1):dmi_cpu0_pch_rx_c_dp(0)") )
				( member ( signalRef "@baseboard_fab2_lib.baseboard_fab2(sch_1):dmi_cpu0_pch_rx_c_dp(1)") )
				( member ( signalRef "@baseboard_fab2_lib.baseboard_fab2(sch_1):dmi_cpu0_pch_rx_c_dp(2)") )
				( member ( signalRef "@baseboard_fab2_lib.baseboard_fab2(sch_1):dmi_cpu0_pch_rx_c_dp(3)") )
				( objectStatus "DMI_CPU0_PCH_RX_C_DP" )
			)
			( bus "@baseboard_fab2_lib.baseboard_fab2(sch_1):dmi_cpu0_pch_tx_dn"
				( memberType ( signal ) )
				( member ( signalRef "@baseboard_fab2_lib.baseboard_fab2(sch_1):dmi_cpu0_pch_tx_dn(0)") )
				( member ( signalRef "@baseboard_fab2_lib.baseboard_fab2(sch_1):dmi_cpu0_pch_tx_dn(1)") )
				( member ( signalRef "@baseboard_fab2_lib.baseboard_fab2(sch_1):dmi_cpu0_pch_tx_dn(2)") )
				( member ( signalRef "@baseboard_fab2_lib.baseboard_fab2(sch_1):dmi_cpu0_pch_tx_dn(3)") )
				( objectStatus "DMI_CPU0_PCH_TX_DN" )
			)
			( bus "@baseboard_fab2_lib.baseboard_fab2(sch_1):dmi_cpu0_pch_tx_dp"
				( memberType ( signal ) )
				( member ( signalRef "@baseboard_fab2_lib.baseboard_fab2(sch_1):dmi_cpu0_pch_tx_dp(0)") )
				( member ( signalRef "@baseboard_fab2_lib.baseboard_fab2(sch_1):dmi_cpu0_pch_tx_dp(1)") )
				( member ( signalRef "@baseboard_fab2_lib.baseboard_fab2(sch_1):dmi_cpu0_pch_tx_dp(2)") )
				( member ( signalRef "@baseboard_fab2_lib.baseboard_fab2(sch_1):dmi_cpu0_pch_tx_dp(3)") )
				( objectStatus "DMI_CPU0_PCH_TX_DP" )
			)
			( bus "@baseboard_fab2_lib.baseboard_fab2(sch_1):p3e_cpu0_pe1_pch_rxn"
				( memberType ( signal ) )
				( member ( signalRef "@baseboard_fab2_lib.baseboard_fab2(sch_1):p3e_cpu0_pe1_pch_rxn(8)") )
				( member ( signalRef "@baseboard_fab2_lib.baseboard_fab2(sch_1):p3e_cpu0_pe1_pch_rxn(9)") )
				( member ( signalRef "@baseboard_fab2_lib.baseboard_fab2(sch_1):p3e_cpu0_pe1_pch_rxn(10)") )
				( member ( signalRef "@baseboard_fab2_lib.baseboard_fab2(sch_1):p3e_cpu0_pe1_pch_rxn(11)") )
				( member ( signalRef "@baseboard_fab2_lib.baseboard_fab2(sch_1):p3e_cpu0_pe1_pch_rxn(12)") )
				( member ( signalRef "@baseboard_fab2_lib.baseboard_fab2(sch_1):p3e_cpu0_pe1_pch_rxn(13)") )
				( member ( signalRef "@baseboard_fab2_lib.baseboard_fab2(sch_1):p3e_cpu0_pe1_pch_rxn(14)") )
				( member ( signalRef "@baseboard_fab2_lib.baseboard_fab2(sch_1):p3e_cpu0_pe1_pch_rxn(15)") )
				( member ( signalRef "@baseboard_fab2_lib.baseboard_fab2(sch_1):p3e_cpu0_pe1_pch_rxn(0)") )
				( member ( signalRef "@baseboard_fab2_lib.baseboard_fab2(sch_1):p3e_cpu0_pe1_pch_rxn(1)") )
				( member ( signalRef "@baseboard_fab2_lib.baseboard_fab2(sch_1):p3e_cpu0_pe1_pch_rxn(2)") )
				( member ( signalRef "@baseboard_fab2_lib.baseboard_fab2(sch_1):p3e_cpu0_pe1_pch_rxn(3)") )
				( member ( signalRef "@baseboard_fab2_lib.baseboard_fab2(sch_1):p3e_cpu0_pe1_pch_rxn(4)") )
				( member ( signalRef "@baseboard_fab2_lib.baseboard_fab2(sch_1):p3e_cpu0_pe1_pch_rxn(5)") )
				( member ( signalRef "@baseboard_fab2_lib.baseboard_fab2(sch_1):p3e_cpu0_pe1_pch_rxn(6)") )
				( member ( signalRef "@baseboard_fab2_lib.baseboard_fab2(sch_1):p3e_cpu0_pe1_pch_rxn(7)") )
				( objectStatus "P3E_CPU0_PE1_PCH_RXN" )
			)
			( bus "@baseboard_fab2_lib.baseboard_fab2(sch_1):p3e_cpu0_pe1_pch_rxp"
				( memberType ( signal ) )
				( member ( signalRef "@baseboard_fab2_lib.baseboard_fab2(sch_1):p3e_cpu0_pe1_pch_rxp(8)") )
				( member ( signalRef "@baseboard_fab2_lib.baseboard_fab2(sch_1):p3e_cpu0_pe1_pch_rxp(9)") )
				( member ( signalRef "@baseboard_fab2_lib.baseboard_fab2(sch_1):p3e_cpu0_pe1_pch_rxp(10)") )
				( member ( signalRef "@baseboard_fab2_lib.baseboard_fab2(sch_1):p3e_cpu0_pe1_pch_rxp(11)") )
				( member ( signalRef "@baseboard_fab2_lib.baseboard_fab2(sch_1):p3e_cpu0_pe1_pch_rxp(12)") )
				( member ( signalRef "@baseboard_fab2_lib.baseboard_fab2(sch_1):p3e_cpu0_pe1_pch_rxp(13)") )
				( member ( signalRef "@baseboard_fab2_lib.baseboard_fab2(sch_1):p3e_cpu0_pe1_pch_rxp(14)") )
				( member ( signalRef "@baseboard_fab2_lib.baseboard_fab2(sch_1):p3e_cpu0_pe1_pch_rxp(15)") )
				( member ( signalRef "@baseboard_fab2_lib.baseboard_fab2(sch_1):p3e_cpu0_pe1_pch_rxp(0)") )
				( member ( signalRef "@baseboard_fab2_lib.baseboard_fab2(sch_1):p3e_cpu0_pe1_pch_rxp(1)") )
				( member ( signalRef "@baseboard_fab2_lib.baseboard_fab2(sch_1):p3e_cpu0_pe1_pch_rxp(2)") )
				( member ( signalRef "@baseboard_fab2_lib.baseboard_fab2(sch_1):p3e_cpu0_pe1_pch_rxp(3)") )
				( member ( signalRef "@baseboard_fab2_lib.baseboard_fab2(sch_1):p3e_cpu0_pe1_pch_rxp(4)") )
				( member ( signalRef "@baseboard_fab2_lib.baseboard_fab2(sch_1):p3e_cpu0_pe1_pch_rxp(5)") )
				( member ( signalRef "@baseboard_fab2_lib.baseboard_fab2(sch_1):p3e_cpu0_pe1_pch_rxp(6)") )
				( member ( signalRef "@baseboard_fab2_lib.baseboard_fab2(sch_1):p3e_cpu0_pe1_pch_rxp(7)") )
				( objectStatus "P3E_CPU0_PE1_PCH_RXP" )
			)
			( bus "@baseboard_fab2_lib.baseboard_fab2(sch_1):p3e_cpu0_pe1_pch_txn"
				( memberType ( signal ) )
				( member ( signalRef "@baseboard_fab2_lib.baseboard_fab2(sch_1):p3e_cpu0_pe1_pch_txn(8)") )
				( member ( signalRef "@baseboard_fab2_lib.baseboard_fab2(sch_1):p3e_cpu0_pe1_pch_txn(9)") )
				( member ( signalRef "@baseboard_fab2_lib.baseboard_fab2(sch_1):p3e_cpu0_pe1_pch_txn(10)") )
				( member ( signalRef "@baseboard_fab2_lib.baseboard_fab2(sch_1):p3e_cpu0_pe1_pch_txn(11)") )
				( member ( signalRef "@baseboard_fab2_lib.baseboard_fab2(sch_1):p3e_cpu0_pe1_pch_txn(12)") )
				( member ( signalRef "@baseboard_fab2_lib.baseboard_fab2(sch_1):p3e_cpu0_pe1_pch_txn(13)") )
				( member ( signalRef "@baseboard_fab2_lib.baseboard_fab2(sch_1):p3e_cpu0_pe1_pch_txn(14)") )
				( member ( signalRef "@baseboard_fab2_lib.baseboard_fab2(sch_1):p3e_cpu0_pe1_pch_txn(15)") )
				( member ( signalRef "@baseboard_fab2_lib.baseboard_fab2(sch_1):p3e_cpu0_pe1_pch_txn(0)") )
				( member ( signalRef "@baseboard_fab2_lib.baseboard_fab2(sch_1):p3e_cpu0_pe1_pch_txn(1)") )
				( member ( signalRef "@baseboard_fab2_lib.baseboard_fab2(sch_1):p3e_cpu0_pe1_pch_txn(2)") )
				( member ( signalRef "@baseboard_fab2_lib.baseboard_fab2(sch_1):p3e_cpu0_pe1_pch_txn(3)") )
				( member ( signalRef "@baseboard_fab2_lib.baseboard_fab2(sch_1):p3e_cpu0_pe1_pch_txn(4)") )
				( member ( signalRef "@baseboard_fab2_lib.baseboard_fab2(sch_1):p3e_cpu0_pe1_pch_txn(5)") )
				( member ( signalRef "@baseboard_fab2_lib.baseboard_fab2(sch_1):p3e_cpu0_pe1_pch_txn(6)") )
				( member ( signalRef "@baseboard_fab2_lib.baseboard_fab2(sch_1):p3e_cpu0_pe1_pch_txn(7)") )
				( objectStatus "P3E_CPU0_PE1_PCH_TXN" )
			)
			( bus "@baseboard_fab2_lib.baseboard_fab2(sch_1):p3e_cpu0_pe1_pch_txp"
				( memberType ( signal ) )
				( member ( signalRef "@baseboard_fab2_lib.baseboard_fab2(sch_1):p3e_cpu0_pe1_pch_txp(8)") )
				( member ( signalRef "@baseboard_fab2_lib.baseboard_fab2(sch_1):p3e_cpu0_pe1_pch_txp(9)") )
				( member ( signalRef "@baseboard_fab2_lib.baseboard_fab2(sch_1):p3e_cpu0_pe1_pch_txp(10)") )
				( member ( signalRef "@baseboard_fab2_lib.baseboard_fab2(sch_1):p3e_cpu0_pe1_pch_txp(11)") )
				( member ( signalRef "@baseboard_fab2_lib.baseboard_fab2(sch_1):p3e_cpu0_pe1_pch_txp(12)") )
				( member ( signalRef "@baseboard_fab2_lib.baseboard_fab2(sch_1):p3e_cpu0_pe1_pch_txp(13)") )
				( member ( signalRef "@baseboard_fab2_lib.baseboard_fab2(sch_1):p3e_cpu0_pe1_pch_txp(14)") )
				( member ( signalRef "@baseboard_fab2_lib.baseboard_fab2(sch_1):p3e_cpu0_pe1_pch_txp(15)") )
				( member ( signalRef "@baseboard_fab2_lib.baseboard_fab2(sch_1):p3e_cpu0_pe1_pch_txp(0)") )
				( member ( signalRef "@baseboard_fab2_lib.baseboard_fab2(sch_1):p3e_cpu0_pe1_pch_txp(1)") )
				( member ( signalRef "@baseboard_fab2_lib.baseboard_fab2(sch_1):p3e_cpu0_pe1_pch_txp(2)") )
				( member ( signalRef "@baseboard_fab2_lib.baseboard_fab2(sch_1):p3e_cpu0_pe1_pch_txp(3)") )
				( member ( signalRef "@baseboard_fab2_lib.baseboard_fab2(sch_1):p3e_cpu0_pe1_pch_txp(4)") )
				( member ( signalRef "@baseboard_fab2_lib.baseboard_fab2(sch_1):p3e_cpu0_pe1_pch_txp(5)") )
				( member ( signalRef "@baseboard_fab2_lib.baseboard_fab2(sch_1):p3e_cpu0_pe1_pch_txp(6)") )
				( member ( signalRef "@baseboard_fab2_lib.baseboard_fab2(sch_1):p3e_cpu0_pe1_pch_txp(7)") )
				( objectStatus "P3E_CPU0_PE1_PCH_TXP" )
			)
			( bus "@baseboard_fab2_lib.baseboard_fab2(sch_1):p3e_cpu0_pe1_ss_rxn"
				( memberType ( signal ) )
				( member ( signalRef "@baseboard_fab2_lib.baseboard_fab2(sch_1):p3e_cpu0_pe1_ss_rxn(0)") )
				( member ( signalRef "@baseboard_fab2_lib.baseboard_fab2(sch_1):p3e_cpu0_pe1_ss_rxn(1)") )
				( member ( signalRef "@baseboard_fab2_lib.baseboard_fab2(sch_1):p3e_cpu0_pe1_ss_rxn(2)") )
				( member ( signalRef "@baseboard_fab2_lib.baseboard_fab2(sch_1):p3e_cpu0_pe1_ss_rxn(3)") )
				( member ( signalRef "@baseboard_fab2_lib.baseboard_fab2(sch_1):p3e_cpu0_pe1_ss_rxn(4)") )
				( member ( signalRef "@baseboard_fab2_lib.baseboard_fab2(sch_1):p3e_cpu0_pe1_ss_rxn(5)") )
				( member ( signalRef "@baseboard_fab2_lib.baseboard_fab2(sch_1):p3e_cpu0_pe1_ss_rxn(6)") )
				( member ( signalRef "@baseboard_fab2_lib.baseboard_fab2(sch_1):p3e_cpu0_pe1_ss_rxn(7)") )
				( objectStatus "P3E_CPU0_PE1_SS_RXN" )
			)
			( bus "@baseboard_fab2_lib.baseboard_fab2(sch_1):p3e_cpu0_pe1_ss_rxp"
				( memberType ( signal ) )
				( member ( signalRef "@baseboard_fab2_lib.baseboard_fab2(sch_1):p3e_cpu0_pe1_ss_rxp(0)") )
				( member ( signalRef "@baseboard_fab2_lib.baseboard_fab2(sch_1):p3e_cpu0_pe1_ss_rxp(1)") )
				( member ( signalRef "@baseboard_fab2_lib.baseboard_fab2(sch_1):p3e_cpu0_pe1_ss_rxp(2)") )
				( member ( signalRef "@baseboard_fab2_lib.baseboard_fab2(sch_1):p3e_cpu0_pe1_ss_rxp(3)") )
				( member ( signalRef "@baseboard_fab2_lib.baseboard_fab2(sch_1):p3e_cpu0_pe1_ss_rxp(4)") )
				( member ( signalRef "@baseboard_fab2_lib.baseboard_fab2(sch_1):p3e_cpu0_pe1_ss_rxp(5)") )
				( member ( signalRef "@baseboard_fab2_lib.baseboard_fab2(sch_1):p3e_cpu0_pe1_ss_rxp(6)") )
				( member ( signalRef "@baseboard_fab2_lib.baseboard_fab2(sch_1):p3e_cpu0_pe1_ss_rxp(7)") )
				( objectStatus "P3E_CPU0_PE1_SS_RXP" )
			)
			( bus "@baseboard_fab2_lib.baseboard_fab2(sch_1):p3e_cpu0_pe1_ss_txn"
				( memberType ( signal ) )
				( member ( signalRef "@baseboard_fab2_lib.baseboard_fab2(sch_1):p3e_cpu0_pe1_ss_txn(0)") )
				( member ( signalRef "@baseboard_fab2_lib.baseboard_fab2(sch_1):p3e_cpu0_pe1_ss_txn(1)") )
				( member ( signalRef "@baseboard_fab2_lib.baseboard_fab2(sch_1):p3e_cpu0_pe1_ss_txn(2)") )
				( member ( signalRef "@baseboard_fab2_lib.baseboard_fab2(sch_1):p3e_cpu0_pe1_ss_txn(3)") )
				( member ( signalRef "@baseboard_fab2_lib.baseboard_fab2(sch_1):p3e_cpu0_pe1_ss_txn(4)") )
				( member ( signalRef "@baseboard_fab2_lib.baseboard_fab2(sch_1):p3e_cpu0_pe1_ss_txn(5)") )
				( member ( signalRef "@baseboard_fab2_lib.baseboard_fab2(sch_1):p3e_cpu0_pe1_ss_txn(6)") )
				( member ( signalRef "@baseboard_fab2_lib.baseboard_fab2(sch_1):p3e_cpu0_pe1_ss_txn(7)") )
				( objectStatus "P3E_CPU0_PE1_SS_TXN" )
			)
			( bus "@baseboard_fab2_lib.baseboard_fab2(sch_1):p3e_cpu0_pe1_ss_txp"
				( memberType ( signal ) )
				( member ( signalRef "@baseboard_fab2_lib.baseboard_fab2(sch_1):p3e_cpu0_pe1_ss_txp(0)") )
				( member ( signalRef "@baseboard_fab2_lib.baseboard_fab2(sch_1):p3e_cpu0_pe1_ss_txp(1)") )
				( member ( signalRef "@baseboard_fab2_lib.baseboard_fab2(sch_1):p3e_cpu0_pe1_ss_txp(2)") )
				( member ( signalRef "@baseboard_fab2_lib.baseboard_fab2(sch_1):p3e_cpu0_pe1_ss_txp(3)") )
				( member ( signalRef "@baseboard_fab2_lib.baseboard_fab2(sch_1):p3e_cpu0_pe1_ss_txp(4)") )
				( member ( signalRef "@baseboard_fab2_lib.baseboard_fab2(sch_1):p3e_cpu0_pe1_ss_txp(5)") )
				( member ( signalRef "@baseboard_fab2_lib.baseboard_fab2(sch_1):p3e_cpu0_pe1_ss_txp(6)") )
				( member ( signalRef "@baseboard_fab2_lib.baseboard_fab2(sch_1):p3e_cpu0_pe1_ss_txp(7)") )
				( objectStatus "P3E_CPU0_PE1_SS_TXP" )
			)
			( bus "@baseboard_fab2_lib.baseboard_fab2(sch_1):p3e_cpu0_pe2_ss_rxn"
				( memberType ( signal ) )
				( member ( signalRef "@baseboard_fab2_lib.baseboard_fab2(sch_1):p3e_cpu0_pe2_ss_rxn(0)") )
				( member ( signalRef "@baseboard_fab2_lib.baseboard_fab2(sch_1):p3e_cpu0_pe2_ss_rxn(1)") )
				( member ( signalRef "@baseboard_fab2_lib.baseboard_fab2(sch_1):p3e_cpu0_pe2_ss_rxn(2)") )
				( member ( signalRef "@baseboard_fab2_lib.baseboard_fab2(sch_1):p3e_cpu0_pe2_ss_rxn(3)") )
				( member ( signalRef "@baseboard_fab2_lib.baseboard_fab2(sch_1):p3e_cpu0_pe2_ss_rxn(4)") )
				( member ( signalRef "@baseboard_fab2_lib.baseboard_fab2(sch_1):p3e_cpu0_pe2_ss_rxn(5)") )
				( member ( signalRef "@baseboard_fab2_lib.baseboard_fab2(sch_1):p3e_cpu0_pe2_ss_rxn(6)") )
				( member ( signalRef "@baseboard_fab2_lib.baseboard_fab2(sch_1):p3e_cpu0_pe2_ss_rxn(7)") )
				( member ( signalRef "@baseboard_fab2_lib.baseboard_fab2(sch_1):p3e_cpu0_pe2_ss_rxn(8)") )
				( member ( signalRef "@baseboard_fab2_lib.baseboard_fab2(sch_1):p3e_cpu0_pe2_ss_rxn(9)") )
				( member ( signalRef "@baseboard_fab2_lib.baseboard_fab2(sch_1):p3e_cpu0_pe2_ss_rxn(10)") )
				( member ( signalRef "@baseboard_fab2_lib.baseboard_fab2(sch_1):p3e_cpu0_pe2_ss_rxn(11)") )
				( member ( signalRef "@baseboard_fab2_lib.baseboard_fab2(sch_1):p3e_cpu0_pe2_ss_rxn(12)") )
				( member ( signalRef "@baseboard_fab2_lib.baseboard_fab2(sch_1):p3e_cpu0_pe2_ss_rxn(13)") )
				( member ( signalRef "@baseboard_fab2_lib.baseboard_fab2(sch_1):p3e_cpu0_pe2_ss_rxn(14)") )
				( member ( signalRef "@baseboard_fab2_lib.baseboard_fab2(sch_1):p3e_cpu0_pe2_ss_rxn(15)") )
				( objectStatus "P3E_CPU0_PE2_SS_RXN" )
			)
			( bus "@baseboard_fab2_lib.baseboard_fab2(sch_1):p3e_cpu0_pe2_ss_rxp"
				( memberType ( signal ) )
				( member ( signalRef "@baseboard_fab2_lib.baseboard_fab2(sch_1):p3e_cpu0_pe2_ss_rxp(0)") )
				( member ( signalRef "@baseboard_fab2_lib.baseboard_fab2(sch_1):p3e_cpu0_pe2_ss_rxp(1)") )
				( member ( signalRef "@baseboard_fab2_lib.baseboard_fab2(sch_1):p3e_cpu0_pe2_ss_rxp(2)") )
				( member ( signalRef "@baseboard_fab2_lib.baseboard_fab2(sch_1):p3e_cpu0_pe2_ss_rxp(3)") )
				( member ( signalRef "@baseboard_fab2_lib.baseboard_fab2(sch_1):p3e_cpu0_pe2_ss_rxp(4)") )
				( member ( signalRef "@baseboard_fab2_lib.baseboard_fab2(sch_1):p3e_cpu0_pe2_ss_rxp(5)") )
				( member ( signalRef "@baseboard_fab2_lib.baseboard_fab2(sch_1):p3e_cpu0_pe2_ss_rxp(6)") )
				( member ( signalRef "@baseboard_fab2_lib.baseboard_fab2(sch_1):p3e_cpu0_pe2_ss_rxp(7)") )
				( member ( signalRef "@baseboard_fab2_lib.baseboard_fab2(sch_1):p3e_cpu0_pe2_ss_rxp(8)") )
				( member ( signalRef "@baseboard_fab2_lib.baseboard_fab2(sch_1):p3e_cpu0_pe2_ss_rxp(9)") )
				( member ( signalRef "@baseboard_fab2_lib.baseboard_fab2(sch_1):p3e_cpu0_pe2_ss_rxp(10)") )
				( member ( signalRef "@baseboard_fab2_lib.baseboard_fab2(sch_1):p3e_cpu0_pe2_ss_rxp(11)") )
				( member ( signalRef "@baseboard_fab2_lib.baseboard_fab2(sch_1):p3e_cpu0_pe2_ss_rxp(12)") )
				( member ( signalRef "@baseboard_fab2_lib.baseboard_fab2(sch_1):p3e_cpu0_pe2_ss_rxp(13)") )
				( member ( signalRef "@baseboard_fab2_lib.baseboard_fab2(sch_1):p3e_cpu0_pe2_ss_rxp(14)") )
				( member ( signalRef "@baseboard_fab2_lib.baseboard_fab2(sch_1):p3e_cpu0_pe2_ss_rxp(15)") )
				( objectStatus "P3E_CPU0_PE2_SS_RXP" )
			)
			( bus "@baseboard_fab2_lib.baseboard_fab2(sch_1):p3e_cpu0_pe2_ss_txn"
				( memberType ( signal ) )
				( member ( signalRef "@baseboard_fab2_lib.baseboard_fab2(sch_1):p3e_cpu0_pe2_ss_txn(0)") )
				( member ( signalRef "@baseboard_fab2_lib.baseboard_fab2(sch_1):p3e_cpu0_pe2_ss_txn(1)") )
				( member ( signalRef "@baseboard_fab2_lib.baseboard_fab2(sch_1):p3e_cpu0_pe2_ss_txn(2)") )
				( member ( signalRef "@baseboard_fab2_lib.baseboard_fab2(sch_1):p3e_cpu0_pe2_ss_txn(3)") )
				( member ( signalRef "@baseboard_fab2_lib.baseboard_fab2(sch_1):p3e_cpu0_pe2_ss_txn(4)") )
				( member ( signalRef "@baseboard_fab2_lib.baseboard_fab2(sch_1):p3e_cpu0_pe2_ss_txn(5)") )
				( member ( signalRef "@baseboard_fab2_lib.baseboard_fab2(sch_1):p3e_cpu0_pe2_ss_txn(6)") )
				( member ( signalRef "@baseboard_fab2_lib.baseboard_fab2(sch_1):p3e_cpu0_pe2_ss_txn(7)") )
				( member ( signalRef "@baseboard_fab2_lib.baseboard_fab2(sch_1):p3e_cpu0_pe2_ss_txn(8)") )
				( member ( signalRef "@baseboard_fab2_lib.baseboard_fab2(sch_1):p3e_cpu0_pe2_ss_txn(9)") )
				( member ( signalRef "@baseboard_fab2_lib.baseboard_fab2(sch_1):p3e_cpu0_pe2_ss_txn(10)") )
				( member ( signalRef "@baseboard_fab2_lib.baseboard_fab2(sch_1):p3e_cpu0_pe2_ss_txn(11)") )
				( member ( signalRef "@baseboard_fab2_lib.baseboard_fab2(sch_1):p3e_cpu0_pe2_ss_txn(12)") )
				( member ( signalRef "@baseboard_fab2_lib.baseboard_fab2(sch_1):p3e_cpu0_pe2_ss_txn(13)") )
				( member ( signalRef "@baseboard_fab2_lib.baseboard_fab2(sch_1):p3e_cpu0_pe2_ss_txn(14)") )
				( member ( signalRef "@baseboard_fab2_lib.baseboard_fab2(sch_1):p3e_cpu0_pe2_ss_txn(15)") )
				( objectStatus "P3E_CPU0_PE2_SS_TXN" )
			)
			( bus "@baseboard_fab2_lib.baseboard_fab2(sch_1):p3e_cpu0_pe2_ss_txp"
				( memberType ( signal ) )
				( member ( signalRef "@baseboard_fab2_lib.baseboard_fab2(sch_1):p3e_cpu0_pe2_ss_txp(0)") )
				( member ( signalRef "@baseboard_fab2_lib.baseboard_fab2(sch_1):p3e_cpu0_pe2_ss_txp(1)") )
				( member ( signalRef "@baseboard_fab2_lib.baseboard_fab2(sch_1):p3e_cpu0_pe2_ss_txp(2)") )
				( member ( signalRef "@baseboard_fab2_lib.baseboard_fab2(sch_1):p3e_cpu0_pe2_ss_txp(3)") )
				( member ( signalRef "@baseboard_fab2_lib.baseboard_fab2(sch_1):p3e_cpu0_pe2_ss_txp(4)") )
				( member ( signalRef "@baseboard_fab2_lib.baseboard_fab2(sch_1):p3e_cpu0_pe2_ss_txp(5)") )
				( member ( signalRef "@baseboard_fab2_lib.baseboard_fab2(sch_1):p3e_cpu0_pe2_ss_txp(6)") )
				( member ( signalRef "@baseboard_fab2_lib.baseboard_fab2(sch_1):p3e_cpu0_pe2_ss_txp(7)") )
				( member ( signalRef "@baseboard_fab2_lib.baseboard_fab2(sch_1):p3e_cpu0_pe2_ss_txp(8)") )
				( member ( signalRef "@baseboard_fab2_lib.baseboard_fab2(sch_1):p3e_cpu0_pe2_ss_txp(9)") )
				( member ( signalRef "@baseboard_fab2_lib.baseboard_fab2(sch_1):p3e_cpu0_pe2_ss_txp(10)") )
				( member ( signalRef "@baseboard_fab2_lib.baseboard_fab2(sch_1):p3e_cpu0_pe2_ss_txp(11)") )
				( member ( signalRef "@baseboard_fab2_lib.baseboard_fab2(sch_1):p3e_cpu0_pe2_ss_txp(12)") )
				( member ( signalRef "@baseboard_fab2_lib.baseboard_fab2(sch_1):p3e_cpu0_pe2_ss_txp(13)") )
				( member ( signalRef "@baseboard_fab2_lib.baseboard_fab2(sch_1):p3e_cpu0_pe2_ss_txp(14)") )
				( member ( signalRef "@baseboard_fab2_lib.baseboard_fab2(sch_1):p3e_cpu0_pe2_ss_txp(15)") )
				( objectStatus "P3E_CPU0_PE2_SS_TXP" )
			)
			( bus "@baseboard_fab2_lib.baseboard_fab2(sch_1):p3e_cpu0_pe3_ocp_rxn"
				( memberType ( signal ) )
				( member ( signalRef "@baseboard_fab2_lib.baseboard_fab2(sch_1):p3e_cpu0_pe3_ocp_rxn(0)") )
				( member ( signalRef "@baseboard_fab2_lib.baseboard_fab2(sch_1):p3e_cpu0_pe3_ocp_rxn(1)") )
				( member ( signalRef "@baseboard_fab2_lib.baseboard_fab2(sch_1):p3e_cpu0_pe3_ocp_rxn(2)") )
				( member ( signalRef "@baseboard_fab2_lib.baseboard_fab2(sch_1):p3e_cpu0_pe3_ocp_rxn(3)") )
				( member ( signalRef "@baseboard_fab2_lib.baseboard_fab2(sch_1):p3e_cpu0_pe3_ocp_rxn(4)") )
				( member ( signalRef "@baseboard_fab2_lib.baseboard_fab2(sch_1):p3e_cpu0_pe3_ocp_rxn(5)") )
				( member ( signalRef "@baseboard_fab2_lib.baseboard_fab2(sch_1):p3e_cpu0_pe3_ocp_rxn(6)") )
				( member ( signalRef "@baseboard_fab2_lib.baseboard_fab2(sch_1):p3e_cpu0_pe3_ocp_rxn(7)") )
				( member ( signalRef "@baseboard_fab2_lib.baseboard_fab2(sch_1):p3e_cpu0_pe3_ocp_rxn(8)") )
				( member ( signalRef "@baseboard_fab2_lib.baseboard_fab2(sch_1):p3e_cpu0_pe3_ocp_rxn(9)") )
				( member ( signalRef "@baseboard_fab2_lib.baseboard_fab2(sch_1):p3e_cpu0_pe3_ocp_rxn(10)") )
				( member ( signalRef "@baseboard_fab2_lib.baseboard_fab2(sch_1):p3e_cpu0_pe3_ocp_rxn(11)") )
				( member ( signalRef "@baseboard_fab2_lib.baseboard_fab2(sch_1):p3e_cpu0_pe3_ocp_rxn(12)") )
				( member ( signalRef "@baseboard_fab2_lib.baseboard_fab2(sch_1):p3e_cpu0_pe3_ocp_rxn(13)") )
				( member ( signalRef "@baseboard_fab2_lib.baseboard_fab2(sch_1):p3e_cpu0_pe3_ocp_rxn(14)") )
				( member ( signalRef "@baseboard_fab2_lib.baseboard_fab2(sch_1):p3e_cpu0_pe3_ocp_rxn(15)") )
				( objectStatus "P3E_CPU0_PE3_OCP_RXN" )
			)
			( bus "@baseboard_fab2_lib.baseboard_fab2(sch_1):p3e_cpu0_pe3_ocp_rxp"
				( memberType ( signal ) )
				( member ( signalRef "@baseboard_fab2_lib.baseboard_fab2(sch_1):p3e_cpu0_pe3_ocp_rxp(0)") )
				( member ( signalRef "@baseboard_fab2_lib.baseboard_fab2(sch_1):p3e_cpu0_pe3_ocp_rxp(1)") )
				( member ( signalRef "@baseboard_fab2_lib.baseboard_fab2(sch_1):p3e_cpu0_pe3_ocp_rxp(2)") )
				( member ( signalRef "@baseboard_fab2_lib.baseboard_fab2(sch_1):p3e_cpu0_pe3_ocp_rxp(3)") )
				( member ( signalRef "@baseboard_fab2_lib.baseboard_fab2(sch_1):p3e_cpu0_pe3_ocp_rxp(4)") )
				( member ( signalRef "@baseboard_fab2_lib.baseboard_fab2(sch_1):p3e_cpu0_pe3_ocp_rxp(5)") )
				( member ( signalRef "@baseboard_fab2_lib.baseboard_fab2(sch_1):p3e_cpu0_pe3_ocp_rxp(6)") )
				( member ( signalRef "@baseboard_fab2_lib.baseboard_fab2(sch_1):p3e_cpu0_pe3_ocp_rxp(7)") )
				( member ( signalRef "@baseboard_fab2_lib.baseboard_fab2(sch_1):p3e_cpu0_pe3_ocp_rxp(8)") )
				( member ( signalRef "@baseboard_fab2_lib.baseboard_fab2(sch_1):p3e_cpu0_pe3_ocp_rxp(9)") )
				( member ( signalRef "@baseboard_fab2_lib.baseboard_fab2(sch_1):p3e_cpu0_pe3_ocp_rxp(10)") )
				( member ( signalRef "@baseboard_fab2_lib.baseboard_fab2(sch_1):p3e_cpu0_pe3_ocp_rxp(11)") )
				( member ( signalRef "@baseboard_fab2_lib.baseboard_fab2(sch_1):p3e_cpu0_pe3_ocp_rxp(12)") )
				( member ( signalRef "@baseboard_fab2_lib.baseboard_fab2(sch_1):p3e_cpu0_pe3_ocp_rxp(13)") )
				( member ( signalRef "@baseboard_fab2_lib.baseboard_fab2(sch_1):p3e_cpu0_pe3_ocp_rxp(14)") )
				( member ( signalRef "@baseboard_fab2_lib.baseboard_fab2(sch_1):p3e_cpu0_pe3_ocp_rxp(15)") )
				( objectStatus "P3E_CPU0_PE3_OCP_RXP" )
			)
			( bus "@baseboard_fab2_lib.baseboard_fab2(sch_1):p3e_cpu0_pe3_ocp_txn"
				( memberType ( signal ) )
				( member ( signalRef "@baseboard_fab2_lib.baseboard_fab2(sch_1):p3e_cpu0_pe3_ocp_txn(0)") )
				( member ( signalRef "@baseboard_fab2_lib.baseboard_fab2(sch_1):p3e_cpu0_pe3_ocp_txn(1)") )
				( member ( signalRef "@baseboard_fab2_lib.baseboard_fab2(sch_1):p3e_cpu0_pe3_ocp_txn(2)") )
				( member ( signalRef "@baseboard_fab2_lib.baseboard_fab2(sch_1):p3e_cpu0_pe3_ocp_txn(3)") )
				( member ( signalRef "@baseboard_fab2_lib.baseboard_fab2(sch_1):p3e_cpu0_pe3_ocp_txn(4)") )
				( member ( signalRef "@baseboard_fab2_lib.baseboard_fab2(sch_1):p3e_cpu0_pe3_ocp_txn(5)") )
				( member ( signalRef "@baseboard_fab2_lib.baseboard_fab2(sch_1):p3e_cpu0_pe3_ocp_txn(6)") )
				( member ( signalRef "@baseboard_fab2_lib.baseboard_fab2(sch_1):p3e_cpu0_pe3_ocp_txn(7)") )
				( member ( signalRef "@baseboard_fab2_lib.baseboard_fab2(sch_1):p3e_cpu0_pe3_ocp_txn(8)") )
				( member ( signalRef "@baseboard_fab2_lib.baseboard_fab2(sch_1):p3e_cpu0_pe3_ocp_txn(9)") )
				( member ( signalRef "@baseboard_fab2_lib.baseboard_fab2(sch_1):p3e_cpu0_pe3_ocp_txn(10)") )
				( member ( signalRef "@baseboard_fab2_lib.baseboard_fab2(sch_1):p3e_cpu0_pe3_ocp_txn(11)") )
				( member ( signalRef "@baseboard_fab2_lib.baseboard_fab2(sch_1):p3e_cpu0_pe3_ocp_txn(12)") )
				( member ( signalRef "@baseboard_fab2_lib.baseboard_fab2(sch_1):p3e_cpu0_pe3_ocp_txn(13)") )
				( member ( signalRef "@baseboard_fab2_lib.baseboard_fab2(sch_1):p3e_cpu0_pe3_ocp_txn(14)") )
				( member ( signalRef "@baseboard_fab2_lib.baseboard_fab2(sch_1):p3e_cpu0_pe3_ocp_txn(15)") )
				( objectStatus "P3E_CPU0_PE3_OCP_TXN" )
			)
			( bus "@baseboard_fab2_lib.baseboard_fab2(sch_1):p3e_cpu0_pe3_ocp_txp"
				( memberType ( signal ) )
				( member ( signalRef "@baseboard_fab2_lib.baseboard_fab2(sch_1):p3e_cpu0_pe3_ocp_txp(0)") )
				( member ( signalRef "@baseboard_fab2_lib.baseboard_fab2(sch_1):p3e_cpu0_pe3_ocp_txp(1)") )
				( member ( signalRef "@baseboard_fab2_lib.baseboard_fab2(sch_1):p3e_cpu0_pe3_ocp_txp(2)") )
				( member ( signalRef "@baseboard_fab2_lib.baseboard_fab2(sch_1):p3e_cpu0_pe3_ocp_txp(3)") )
				( member ( signalRef "@baseboard_fab2_lib.baseboard_fab2(sch_1):p3e_cpu0_pe3_ocp_txp(4)") )
				( member ( signalRef "@baseboard_fab2_lib.baseboard_fab2(sch_1):p3e_cpu0_pe3_ocp_txp(5)") )
				( member ( signalRef "@baseboard_fab2_lib.baseboard_fab2(sch_1):p3e_cpu0_pe3_ocp_txp(6)") )
				( member ( signalRef "@baseboard_fab2_lib.baseboard_fab2(sch_1):p3e_cpu0_pe3_ocp_txp(7)") )
				( member ( signalRef "@baseboard_fab2_lib.baseboard_fab2(sch_1):p3e_cpu0_pe3_ocp_txp(8)") )
				( member ( signalRef "@baseboard_fab2_lib.baseboard_fab2(sch_1):p3e_cpu0_pe3_ocp_txp(9)") )
				( member ( signalRef "@baseboard_fab2_lib.baseboard_fab2(sch_1):p3e_cpu0_pe3_ocp_txp(10)") )
				( member ( signalRef "@baseboard_fab2_lib.baseboard_fab2(sch_1):p3e_cpu0_pe3_ocp_txp(11)") )
				( member ( signalRef "@baseboard_fab2_lib.baseboard_fab2(sch_1):p3e_cpu0_pe3_ocp_txp(12)") )
				( member ( signalRef "@baseboard_fab2_lib.baseboard_fab2(sch_1):p3e_cpu0_pe3_ocp_txp(13)") )
				( member ( signalRef "@baseboard_fab2_lib.baseboard_fab2(sch_1):p3e_cpu0_pe3_ocp_txp(14)") )
				( member ( signalRef "@baseboard_fab2_lib.baseboard_fab2(sch_1):p3e_cpu0_pe3_ocp_txp(15)") )
				( objectStatus "P3E_CPU0_PE3_OCP_TXP" )
			)
			( bus "@baseboard_fab2_lib.baseboard_fab2(sch_1):upi_cpu0_cpu1_p0p0_dn"
				( memberType ( signal ) )
				( member ( signalRef "@baseboard_fab2_lib.baseboard_fab2(sch_1):upi_cpu0_cpu1_p0p0_dn(0)") )
				( member ( signalRef "@baseboard_fab2_lib.baseboard_fab2(sch_1):upi_cpu0_cpu1_p0p0_dn(1)") )
				( member ( signalRef "@baseboard_fab2_lib.baseboard_fab2(sch_1):upi_cpu0_cpu1_p0p0_dn(2)") )
				( member ( signalRef "@baseboard_fab2_lib.baseboard_fab2(sch_1):upi_cpu0_cpu1_p0p0_dn(3)") )
				( member ( signalRef "@baseboard_fab2_lib.baseboard_fab2(sch_1):upi_cpu0_cpu1_p0p0_dn(4)") )
				( member ( signalRef "@baseboard_fab2_lib.baseboard_fab2(sch_1):upi_cpu0_cpu1_p0p0_dn(5)") )
				( member ( signalRef "@baseboard_fab2_lib.baseboard_fab2(sch_1):upi_cpu0_cpu1_p0p0_dn(6)") )
				( member ( signalRef "@baseboard_fab2_lib.baseboard_fab2(sch_1):upi_cpu0_cpu1_p0p0_dn(7)") )
				( member ( signalRef "@baseboard_fab2_lib.baseboard_fab2(sch_1):upi_cpu0_cpu1_p0p0_dn(8)") )
				( member ( signalRef "@baseboard_fab2_lib.baseboard_fab2(sch_1):upi_cpu0_cpu1_p0p0_dn(9)") )
				( member ( signalRef "@baseboard_fab2_lib.baseboard_fab2(sch_1):upi_cpu0_cpu1_p0p0_dn(10)") )
				( member ( signalRef "@baseboard_fab2_lib.baseboard_fab2(sch_1):upi_cpu0_cpu1_p0p0_dn(11)") )
				( member ( signalRef "@baseboard_fab2_lib.baseboard_fab2(sch_1):upi_cpu0_cpu1_p0p0_dn(12)") )
				( member ( signalRef "@baseboard_fab2_lib.baseboard_fab2(sch_1):upi_cpu0_cpu1_p0p0_dn(13)") )
				( member ( signalRef "@baseboard_fab2_lib.baseboard_fab2(sch_1):upi_cpu0_cpu1_p0p0_dn(14)") )
				( member ( signalRef "@baseboard_fab2_lib.baseboard_fab2(sch_1):upi_cpu0_cpu1_p0p0_dn(15)") )
				( member ( signalRef "@baseboard_fab2_lib.baseboard_fab2(sch_1):upi_cpu0_cpu1_p0p0_dn(16)") )
				( member ( signalRef "@baseboard_fab2_lib.baseboard_fab2(sch_1):upi_cpu0_cpu1_p0p0_dn(17)") )
				( member ( signalRef "@baseboard_fab2_lib.baseboard_fab2(sch_1):upi_cpu0_cpu1_p0p0_dn(18)") )
				( member ( signalRef "@baseboard_fab2_lib.baseboard_fab2(sch_1):upi_cpu0_cpu1_p0p0_dn(19)") )
				( objectStatus "UPI_CPU0_CPU1_P0P0_DN" )
			)
			( bus "@baseboard_fab2_lib.baseboard_fab2(sch_1):upi_cpu0_cpu1_p0p0_dp"
				( memberType ( signal ) )
				( member ( signalRef "@baseboard_fab2_lib.baseboard_fab2(sch_1):upi_cpu0_cpu1_p0p0_dp(0)") )
				( member ( signalRef "@baseboard_fab2_lib.baseboard_fab2(sch_1):upi_cpu0_cpu1_p0p0_dp(1)") )
				( member ( signalRef "@baseboard_fab2_lib.baseboard_fab2(sch_1):upi_cpu0_cpu1_p0p0_dp(2)") )
				( member ( signalRef "@baseboard_fab2_lib.baseboard_fab2(sch_1):upi_cpu0_cpu1_p0p0_dp(3)") )
				( member ( signalRef "@baseboard_fab2_lib.baseboard_fab2(sch_1):upi_cpu0_cpu1_p0p0_dp(4)") )
				( member ( signalRef "@baseboard_fab2_lib.baseboard_fab2(sch_1):upi_cpu0_cpu1_p0p0_dp(5)") )
				( member ( signalRef "@baseboard_fab2_lib.baseboard_fab2(sch_1):upi_cpu0_cpu1_p0p0_dp(6)") )
				( member ( signalRef "@baseboard_fab2_lib.baseboard_fab2(sch_1):upi_cpu0_cpu1_p0p0_dp(7)") )
				( member ( signalRef "@baseboard_fab2_lib.baseboard_fab2(sch_1):upi_cpu0_cpu1_p0p0_dp(8)") )
				( member ( signalRef "@baseboard_fab2_lib.baseboard_fab2(sch_1):upi_cpu0_cpu1_p0p0_dp(9)") )
				( member ( signalRef "@baseboard_fab2_lib.baseboard_fab2(sch_1):upi_cpu0_cpu1_p0p0_dp(10)") )
				( member ( signalRef "@baseboard_fab2_lib.baseboard_fab2(sch_1):upi_cpu0_cpu1_p0p0_dp(11)") )
				( member ( signalRef "@baseboard_fab2_lib.baseboard_fab2(sch_1):upi_cpu0_cpu1_p0p0_dp(12)") )
				( member ( signalRef "@baseboard_fab2_lib.baseboard_fab2(sch_1):upi_cpu0_cpu1_p0p0_dp(13)") )
				( member ( signalRef "@baseboard_fab2_lib.baseboard_fab2(sch_1):upi_cpu0_cpu1_p0p0_dp(14)") )
				( member ( signalRef "@baseboard_fab2_lib.baseboard_fab2(sch_1):upi_cpu0_cpu1_p0p0_dp(15)") )
				( member ( signalRef "@baseboard_fab2_lib.baseboard_fab2(sch_1):upi_cpu0_cpu1_p0p0_dp(16)") )
				( member ( signalRef "@baseboard_fab2_lib.baseboard_fab2(sch_1):upi_cpu0_cpu1_p0p0_dp(17)") )
				( member ( signalRef "@baseboard_fab2_lib.baseboard_fab2(sch_1):upi_cpu0_cpu1_p0p0_dp(18)") )
				( member ( signalRef "@baseboard_fab2_lib.baseboard_fab2(sch_1):upi_cpu0_cpu1_p0p0_dp(19)") )
				( objectStatus "UPI_CPU0_CPU1_P0P0_DP" )
			)
			( bus "@baseboard_fab2_lib.baseboard_fab2(sch_1):upi_cpu1_cpu0_p0p0_dn"
				( memberType ( signal ) )
				( member ( signalRef "@baseboard_fab2_lib.baseboard_fab2(sch_1):upi_cpu1_cpu0_p0p0_dn(0)") )
				( member ( signalRef "@baseboard_fab2_lib.baseboard_fab2(sch_1):upi_cpu1_cpu0_p0p0_dn(1)") )
				( member ( signalRef "@baseboard_fab2_lib.baseboard_fab2(sch_1):upi_cpu1_cpu0_p0p0_dn(2)") )
				( member ( signalRef "@baseboard_fab2_lib.baseboard_fab2(sch_1):upi_cpu1_cpu0_p0p0_dn(3)") )
				( member ( signalRef "@baseboard_fab2_lib.baseboard_fab2(sch_1):upi_cpu1_cpu0_p0p0_dn(4)") )
				( member ( signalRef "@baseboard_fab2_lib.baseboard_fab2(sch_1):upi_cpu1_cpu0_p0p0_dn(5)") )
				( member ( signalRef "@baseboard_fab2_lib.baseboard_fab2(sch_1):upi_cpu1_cpu0_p0p0_dn(6)") )
				( member ( signalRef "@baseboard_fab2_lib.baseboard_fab2(sch_1):upi_cpu1_cpu0_p0p0_dn(7)") )
				( member ( signalRef "@baseboard_fab2_lib.baseboard_fab2(sch_1):upi_cpu1_cpu0_p0p0_dn(8)") )
				( member ( signalRef "@baseboard_fab2_lib.baseboard_fab2(sch_1):upi_cpu1_cpu0_p0p0_dn(9)") )
				( member ( signalRef "@baseboard_fab2_lib.baseboard_fab2(sch_1):upi_cpu1_cpu0_p0p0_dn(10)") )
				( member ( signalRef "@baseboard_fab2_lib.baseboard_fab2(sch_1):upi_cpu1_cpu0_p0p0_dn(11)") )
				( member ( signalRef "@baseboard_fab2_lib.baseboard_fab2(sch_1):upi_cpu1_cpu0_p0p0_dn(12)") )
				( member ( signalRef "@baseboard_fab2_lib.baseboard_fab2(sch_1):upi_cpu1_cpu0_p0p0_dn(13)") )
				( member ( signalRef "@baseboard_fab2_lib.baseboard_fab2(sch_1):upi_cpu1_cpu0_p0p0_dn(14)") )
				( member ( signalRef "@baseboard_fab2_lib.baseboard_fab2(sch_1):upi_cpu1_cpu0_p0p0_dn(15)") )
				( member ( signalRef "@baseboard_fab2_lib.baseboard_fab2(sch_1):upi_cpu1_cpu0_p0p0_dn(16)") )
				( member ( signalRef "@baseboard_fab2_lib.baseboard_fab2(sch_1):upi_cpu1_cpu0_p0p0_dn(17)") )
				( member ( signalRef "@baseboard_fab2_lib.baseboard_fab2(sch_1):upi_cpu1_cpu0_p0p0_dn(18)") )
				( member ( signalRef "@baseboard_fab2_lib.baseboard_fab2(sch_1):upi_cpu1_cpu0_p0p0_dn(19)") )
				( objectStatus "UPI_CPU1_CPU0_P0P0_DN" )
			)
			( bus "@baseboard_fab2_lib.baseboard_fab2(sch_1):upi_cpu1_cpu0_p0p0_dp"
				( memberType ( signal ) )
				( member ( signalRef "@baseboard_fab2_lib.baseboard_fab2(sch_1):upi_cpu1_cpu0_p0p0_dp(0)") )
				( member ( signalRef "@baseboard_fab2_lib.baseboard_fab2(sch_1):upi_cpu1_cpu0_p0p0_dp(1)") )
				( member ( signalRef "@baseboard_fab2_lib.baseboard_fab2(sch_1):upi_cpu1_cpu0_p0p0_dp(2)") )
				( member ( signalRef "@baseboard_fab2_lib.baseboard_fab2(sch_1):upi_cpu1_cpu0_p0p0_dp(3)") )
				( member ( signalRef "@baseboard_fab2_lib.baseboard_fab2(sch_1):upi_cpu1_cpu0_p0p0_dp(4)") )
				( member ( signalRef "@baseboard_fab2_lib.baseboard_fab2(sch_1):upi_cpu1_cpu0_p0p0_dp(5)") )
				( member ( signalRef "@baseboard_fab2_lib.baseboard_fab2(sch_1):upi_cpu1_cpu0_p0p0_dp(6)") )
				( member ( signalRef "@baseboard_fab2_lib.baseboard_fab2(sch_1):upi_cpu1_cpu0_p0p0_dp(7)") )
				( member ( signalRef "@baseboard_fab2_lib.baseboard_fab2(sch_1):upi_cpu1_cpu0_p0p0_dp(8)") )
				( member ( signalRef "@baseboard_fab2_lib.baseboard_fab2(sch_1):upi_cpu1_cpu0_p0p0_dp(9)") )
				( member ( signalRef "@baseboard_fab2_lib.baseboard_fab2(sch_1):upi_cpu1_cpu0_p0p0_dp(10)") )
				( member ( signalRef "@baseboard_fab2_lib.baseboard_fab2(sch_1):upi_cpu1_cpu0_p0p0_dp(11)") )
				( member ( signalRef "@baseboard_fab2_lib.baseboard_fab2(sch_1):upi_cpu1_cpu0_p0p0_dp(12)") )
				( member ( signalRef "@baseboard_fab2_lib.baseboard_fab2(sch_1):upi_cpu1_cpu0_p0p0_dp(13)") )
				( member ( signalRef "@baseboard_fab2_lib.baseboard_fab2(sch_1):upi_cpu1_cpu0_p0p0_dp(14)") )
				( member ( signalRef "@baseboard_fab2_lib.baseboard_fab2(sch_1):upi_cpu1_cpu0_p0p0_dp(15)") )
				( member ( signalRef "@baseboard_fab2_lib.baseboard_fab2(sch_1):upi_cpu1_cpu0_p0p0_dp(16)") )
				( member ( signalRef "@baseboard_fab2_lib.baseboard_fab2(sch_1):upi_cpu1_cpu0_p0p0_dp(17)") )
				( member ( signalRef "@baseboard_fab2_lib.baseboard_fab2(sch_1):upi_cpu1_cpu0_p0p0_dp(18)") )
				( member ( signalRef "@baseboard_fab2_lib.baseboard_fab2(sch_1):upi_cpu1_cpu0_p0p0_dp(19)") )
				( objectStatus "UPI_CPU1_CPU0_P0P0_DP" )
			)
			( bus "@baseboard_fab2_lib.baseboard_fab2(sch_1):upi_cpu0_cpu1_p1p1_dn"
				( memberType ( signal ) )
				( member ( signalRef "@baseboard_fab2_lib.baseboard_fab2(sch_1):upi_cpu0_cpu1_p1p1_dn(0)") )
				( member ( signalRef "@baseboard_fab2_lib.baseboard_fab2(sch_1):upi_cpu0_cpu1_p1p1_dn(1)") )
				( member ( signalRef "@baseboard_fab2_lib.baseboard_fab2(sch_1):upi_cpu0_cpu1_p1p1_dn(2)") )
				( member ( signalRef "@baseboard_fab2_lib.baseboard_fab2(sch_1):upi_cpu0_cpu1_p1p1_dn(3)") )
				( member ( signalRef "@baseboard_fab2_lib.baseboard_fab2(sch_1):upi_cpu0_cpu1_p1p1_dn(4)") )
				( member ( signalRef "@baseboard_fab2_lib.baseboard_fab2(sch_1):upi_cpu0_cpu1_p1p1_dn(5)") )
				( member ( signalRef "@baseboard_fab2_lib.baseboard_fab2(sch_1):upi_cpu0_cpu1_p1p1_dn(6)") )
				( member ( signalRef "@baseboard_fab2_lib.baseboard_fab2(sch_1):upi_cpu0_cpu1_p1p1_dn(7)") )
				( member ( signalRef "@baseboard_fab2_lib.baseboard_fab2(sch_1):upi_cpu0_cpu1_p1p1_dn(8)") )
				( member ( signalRef "@baseboard_fab2_lib.baseboard_fab2(sch_1):upi_cpu0_cpu1_p1p1_dn(9)") )
				( member ( signalRef "@baseboard_fab2_lib.baseboard_fab2(sch_1):upi_cpu0_cpu1_p1p1_dn(10)") )
				( member ( signalRef "@baseboard_fab2_lib.baseboard_fab2(sch_1):upi_cpu0_cpu1_p1p1_dn(11)") )
				( member ( signalRef "@baseboard_fab2_lib.baseboard_fab2(sch_1):upi_cpu0_cpu1_p1p1_dn(12)") )
				( member ( signalRef "@baseboard_fab2_lib.baseboard_fab2(sch_1):upi_cpu0_cpu1_p1p1_dn(13)") )
				( member ( signalRef "@baseboard_fab2_lib.baseboard_fab2(sch_1):upi_cpu0_cpu1_p1p1_dn(14)") )
				( member ( signalRef "@baseboard_fab2_lib.baseboard_fab2(sch_1):upi_cpu0_cpu1_p1p1_dn(15)") )
				( member ( signalRef "@baseboard_fab2_lib.baseboard_fab2(sch_1):upi_cpu0_cpu1_p1p1_dn(16)") )
				( member ( signalRef "@baseboard_fab2_lib.baseboard_fab2(sch_1):upi_cpu0_cpu1_p1p1_dn(17)") )
				( member ( signalRef "@baseboard_fab2_lib.baseboard_fab2(sch_1):upi_cpu0_cpu1_p1p1_dn(18)") )
				( member ( signalRef "@baseboard_fab2_lib.baseboard_fab2(sch_1):upi_cpu0_cpu1_p1p1_dn(19)") )
				( objectStatus "UPI_CPU0_CPU1_P1P1_DN" )
			)
			( bus "@baseboard_fab2_lib.baseboard_fab2(sch_1):upi_cpu0_cpu1_p1p1_dp"
				( memberType ( signal ) )
				( member ( signalRef "@baseboard_fab2_lib.baseboard_fab2(sch_1):upi_cpu0_cpu1_p1p1_dp(0)") )
				( member ( signalRef "@baseboard_fab2_lib.baseboard_fab2(sch_1):upi_cpu0_cpu1_p1p1_dp(1)") )
				( member ( signalRef "@baseboard_fab2_lib.baseboard_fab2(sch_1):upi_cpu0_cpu1_p1p1_dp(2)") )
				( member ( signalRef "@baseboard_fab2_lib.baseboard_fab2(sch_1):upi_cpu0_cpu1_p1p1_dp(3)") )
				( member ( signalRef "@baseboard_fab2_lib.baseboard_fab2(sch_1):upi_cpu0_cpu1_p1p1_dp(4)") )
				( member ( signalRef "@baseboard_fab2_lib.baseboard_fab2(sch_1):upi_cpu0_cpu1_p1p1_dp(5)") )
				( member ( signalRef "@baseboard_fab2_lib.baseboard_fab2(sch_1):upi_cpu0_cpu1_p1p1_dp(6)") )
				( member ( signalRef "@baseboard_fab2_lib.baseboard_fab2(sch_1):upi_cpu0_cpu1_p1p1_dp(7)") )
				( member ( signalRef "@baseboard_fab2_lib.baseboard_fab2(sch_1):upi_cpu0_cpu1_p1p1_dp(8)") )
				( member ( signalRef "@baseboard_fab2_lib.baseboard_fab2(sch_1):upi_cpu0_cpu1_p1p1_dp(9)") )
				( member ( signalRef "@baseboard_fab2_lib.baseboard_fab2(sch_1):upi_cpu0_cpu1_p1p1_dp(10)") )
				( member ( signalRef "@baseboard_fab2_lib.baseboard_fab2(sch_1):upi_cpu0_cpu1_p1p1_dp(11)") )
				( member ( signalRef "@baseboard_fab2_lib.baseboard_fab2(sch_1):upi_cpu0_cpu1_p1p1_dp(12)") )
				( member ( signalRef "@baseboard_fab2_lib.baseboard_fab2(sch_1):upi_cpu0_cpu1_p1p1_dp(13)") )
				( member ( signalRef "@baseboard_fab2_lib.baseboard_fab2(sch_1):upi_cpu0_cpu1_p1p1_dp(14)") )
				( member ( signalRef "@baseboard_fab2_lib.baseboard_fab2(sch_1):upi_cpu0_cpu1_p1p1_dp(15)") )
				( member ( signalRef "@baseboard_fab2_lib.baseboard_fab2(sch_1):upi_cpu0_cpu1_p1p1_dp(16)") )
				( member ( signalRef "@baseboard_fab2_lib.baseboard_fab2(sch_1):upi_cpu0_cpu1_p1p1_dp(17)") )
				( member ( signalRef "@baseboard_fab2_lib.baseboard_fab2(sch_1):upi_cpu0_cpu1_p1p1_dp(18)") )
				( member ( signalRef "@baseboard_fab2_lib.baseboard_fab2(sch_1):upi_cpu0_cpu1_p1p1_dp(19)") )
				( objectStatus "UPI_CPU0_CPU1_P1P1_DP" )
			)
			( bus "@baseboard_fab2_lib.baseboard_fab2(sch_1):upi_cpu1_cpu0_p1p1_dn"
				( memberType ( signal ) )
				( member ( signalRef "@baseboard_fab2_lib.baseboard_fab2(sch_1):upi_cpu1_cpu0_p1p1_dn(0)") )
				( member ( signalRef "@baseboard_fab2_lib.baseboard_fab2(sch_1):upi_cpu1_cpu0_p1p1_dn(1)") )
				( member ( signalRef "@baseboard_fab2_lib.baseboard_fab2(sch_1):upi_cpu1_cpu0_p1p1_dn(2)") )
				( member ( signalRef "@baseboard_fab2_lib.baseboard_fab2(sch_1):upi_cpu1_cpu0_p1p1_dn(3)") )
				( member ( signalRef "@baseboard_fab2_lib.baseboard_fab2(sch_1):upi_cpu1_cpu0_p1p1_dn(4)") )
				( member ( signalRef "@baseboard_fab2_lib.baseboard_fab2(sch_1):upi_cpu1_cpu0_p1p1_dn(5)") )
				( member ( signalRef "@baseboard_fab2_lib.baseboard_fab2(sch_1):upi_cpu1_cpu0_p1p1_dn(6)") )
				( member ( signalRef "@baseboard_fab2_lib.baseboard_fab2(sch_1):upi_cpu1_cpu0_p1p1_dn(7)") )
				( member ( signalRef "@baseboard_fab2_lib.baseboard_fab2(sch_1):upi_cpu1_cpu0_p1p1_dn(8)") )
				( member ( signalRef "@baseboard_fab2_lib.baseboard_fab2(sch_1):upi_cpu1_cpu0_p1p1_dn(9)") )
				( member ( signalRef "@baseboard_fab2_lib.baseboard_fab2(sch_1):upi_cpu1_cpu0_p1p1_dn(10)") )
				( member ( signalRef "@baseboard_fab2_lib.baseboard_fab2(sch_1):upi_cpu1_cpu0_p1p1_dn(11)") )
				( member ( signalRef "@baseboard_fab2_lib.baseboard_fab2(sch_1):upi_cpu1_cpu0_p1p1_dn(12)") )
				( member ( signalRef "@baseboard_fab2_lib.baseboard_fab2(sch_1):upi_cpu1_cpu0_p1p1_dn(13)") )
				( member ( signalRef "@baseboard_fab2_lib.baseboard_fab2(sch_1):upi_cpu1_cpu0_p1p1_dn(14)") )
				( member ( signalRef "@baseboard_fab2_lib.baseboard_fab2(sch_1):upi_cpu1_cpu0_p1p1_dn(15)") )
				( member ( signalRef "@baseboard_fab2_lib.baseboard_fab2(sch_1):upi_cpu1_cpu0_p1p1_dn(16)") )
				( member ( signalRef "@baseboard_fab2_lib.baseboard_fab2(sch_1):upi_cpu1_cpu0_p1p1_dn(17)") )
				( member ( signalRef "@baseboard_fab2_lib.baseboard_fab2(sch_1):upi_cpu1_cpu0_p1p1_dn(18)") )
				( member ( signalRef "@baseboard_fab2_lib.baseboard_fab2(sch_1):upi_cpu1_cpu0_p1p1_dn(19)") )
				( objectStatus "UPI_CPU1_CPU0_P1P1_DN" )
			)
			( bus "@baseboard_fab2_lib.baseboard_fab2(sch_1):upi_cpu1_cpu0_p1p1_dp"
				( memberType ( signal ) )
				( member ( signalRef "@baseboard_fab2_lib.baseboard_fab2(sch_1):upi_cpu1_cpu0_p1p1_dp(0)") )
				( member ( signalRef "@baseboard_fab2_lib.baseboard_fab2(sch_1):upi_cpu1_cpu0_p1p1_dp(1)") )
				( member ( signalRef "@baseboard_fab2_lib.baseboard_fab2(sch_1):upi_cpu1_cpu0_p1p1_dp(2)") )
				( member ( signalRef "@baseboard_fab2_lib.baseboard_fab2(sch_1):upi_cpu1_cpu0_p1p1_dp(3)") )
				( member ( signalRef "@baseboard_fab2_lib.baseboard_fab2(sch_1):upi_cpu1_cpu0_p1p1_dp(4)") )
				( member ( signalRef "@baseboard_fab2_lib.baseboard_fab2(sch_1):upi_cpu1_cpu0_p1p1_dp(5)") )
				( member ( signalRef "@baseboard_fab2_lib.baseboard_fab2(sch_1):upi_cpu1_cpu0_p1p1_dp(6)") )
				( member ( signalRef "@baseboard_fab2_lib.baseboard_fab2(sch_1):upi_cpu1_cpu0_p1p1_dp(7)") )
				( member ( signalRef "@baseboard_fab2_lib.baseboard_fab2(sch_1):upi_cpu1_cpu0_p1p1_dp(8)") )
				( member ( signalRef "@baseboard_fab2_lib.baseboard_fab2(sch_1):upi_cpu1_cpu0_p1p1_dp(9)") )
				( member ( signalRef "@baseboard_fab2_lib.baseboard_fab2(sch_1):upi_cpu1_cpu0_p1p1_dp(10)") )
				( member ( signalRef "@baseboard_fab2_lib.baseboard_fab2(sch_1):upi_cpu1_cpu0_p1p1_dp(11)") )
				( member ( signalRef "@baseboard_fab2_lib.baseboard_fab2(sch_1):upi_cpu1_cpu0_p1p1_dp(12)") )
				( member ( signalRef "@baseboard_fab2_lib.baseboard_fab2(sch_1):upi_cpu1_cpu0_p1p1_dp(13)") )
				( member ( signalRef "@baseboard_fab2_lib.baseboard_fab2(sch_1):upi_cpu1_cpu0_p1p1_dp(14)") )
				( member ( signalRef "@baseboard_fab2_lib.baseboard_fab2(sch_1):upi_cpu1_cpu0_p1p1_dp(15)") )
				( member ( signalRef "@baseboard_fab2_lib.baseboard_fab2(sch_1):upi_cpu1_cpu0_p1p1_dp(16)") )
				( member ( signalRef "@baseboard_fab2_lib.baseboard_fab2(sch_1):upi_cpu1_cpu0_p1p1_dp(17)") )
				( member ( signalRef "@baseboard_fab2_lib.baseboard_fab2(sch_1):upi_cpu1_cpu0_p1p1_dp(18)") )
				( member ( signalRef "@baseboard_fab2_lib.baseboard_fab2(sch_1):upi_cpu1_cpu0_p1p1_dp(19)") )
				( objectStatus "UPI_CPU1_CPU0_P1P1_DP" )
			)
			( bus "@baseboard_fab2_lib.baseboard_fab2(sch_1):m_g_ba"
				( memberType ( signal ) )
				( member ( signalRef "@baseboard_fab2_lib.baseboard_fab2(sch_1):m_g_ba(0)") )
				( member ( signalRef "@baseboard_fab2_lib.baseboard_fab2(sch_1):m_g_ba(1)") )
				( objectStatus "M_G_BA" )
			)
			( bus "@baseboard_fab2_lib.baseboard_fab2(sch_1):m_g_bg"
				( memberType ( signal ) )
				( member ( signalRef "@baseboard_fab2_lib.baseboard_fab2(sch_1):m_g_bg(0)") )
				( member ( signalRef "@baseboard_fab2_lib.baseboard_fab2(sch_1):m_g_bg(1)") )
				( objectStatus "M_G_BG" )
			)
			( bus "@baseboard_fab2_lib.baseboard_fab2(sch_1):m_g_c"
				( memberType ( signal ) )
				( member ( signalRef "@baseboard_fab2_lib.baseboard_fab2(sch_1):m_g_c(2)") )
				( objectStatus "M_G_C" )
			)
			( bus "@baseboard_fab2_lib.baseboard_fab2(sch_1):m_g_cke"
				( memberType ( signal ) )
				( member ( signalRef "@baseboard_fab2_lib.baseboard_fab2(sch_1):m_g_cke(0)") )
				( member ( signalRef "@baseboard_fab2_lib.baseboard_fab2(sch_1):m_g_cke(1)") )
				( member ( signalRef "@baseboard_fab2_lib.baseboard_fab2(sch_1):m_g_cke(2)") )
				( member ( signalRef "@baseboard_fab2_lib.baseboard_fab2(sch_1):m_g_cke(3)") )
				( objectStatus "M_G_CKE" )
			)
			( bus "@baseboard_fab2_lib.baseboard_fab2(sch_1):m_g_clk_dn"
				( memberType ( signal ) )
				( member ( signalRef "@baseboard_fab2_lib.baseboard_fab2(sch_1):m_g_clk_dn(0)") )
				( member ( signalRef "@baseboard_fab2_lib.baseboard_fab2(sch_1):m_g_clk_dn(1)") )
				( member ( signalRef "@baseboard_fab2_lib.baseboard_fab2(sch_1):m_g_clk_dn(2)") )
				( member ( signalRef "@baseboard_fab2_lib.baseboard_fab2(sch_1):m_g_clk_dn(3)") )
				( objectStatus "M_G_CLK_DN" )
			)
			( bus "@baseboard_fab2_lib.baseboard_fab2(sch_1):m_g_clk_dp"
				( memberType ( signal ) )
				( member ( signalRef "@baseboard_fab2_lib.baseboard_fab2(sch_1):m_g_clk_dp(0)") )
				( member ( signalRef "@baseboard_fab2_lib.baseboard_fab2(sch_1):m_g_clk_dp(1)") )
				( member ( signalRef "@baseboard_fab2_lib.baseboard_fab2(sch_1):m_g_clk_dp(2)") )
				( member ( signalRef "@baseboard_fab2_lib.baseboard_fab2(sch_1):m_g_clk_dp(3)") )
				( objectStatus "M_G_CLK_DP" )
			)
			( bus "@baseboard_fab2_lib.baseboard_fab2(sch_1):m_g_cs_n"
				( memberType ( signal ) )
				( member ( signalRef "@baseboard_fab2_lib.baseboard_fab2(sch_1):m_g_cs_n(0)") )
				( member ( signalRef "@baseboard_fab2_lib.baseboard_fab2(sch_1):m_g_cs_n(1)") )
				( member ( signalRef "@baseboard_fab2_lib.baseboard_fab2(sch_1):m_g_cs_n(2)") )
				( member ( signalRef "@baseboard_fab2_lib.baseboard_fab2(sch_1):m_g_cs_n(3)") )
				( member ( signalRef "@baseboard_fab2_lib.baseboard_fab2(sch_1):m_g_cs_n(4)") )
				( member ( signalRef "@baseboard_fab2_lib.baseboard_fab2(sch_1):m_g_cs_n(5)") )
				( member ( signalRef "@baseboard_fab2_lib.baseboard_fab2(sch_1):m_g_cs_n(6)") )
				( member ( signalRef "@baseboard_fab2_lib.baseboard_fab2(sch_1):m_g_cs_n(7)") )
				( objectStatus "M_G_CS_N" )
			)
			( bus "@baseboard_fab2_lib.baseboard_fab2(sch_1):m_g_dq"
				( memberType ( signal ) )
				( member ( signalRef "@baseboard_fab2_lib.baseboard_fab2(sch_1):m_g_dq(0)") )
				( member ( signalRef "@baseboard_fab2_lib.baseboard_fab2(sch_1):m_g_dq(1)") )
				( member ( signalRef "@baseboard_fab2_lib.baseboard_fab2(sch_1):m_g_dq(2)") )
				( member ( signalRef "@baseboard_fab2_lib.baseboard_fab2(sch_1):m_g_dq(3)") )
				( member ( signalRef "@baseboard_fab2_lib.baseboard_fab2(sch_1):m_g_dq(4)") )
				( member ( signalRef "@baseboard_fab2_lib.baseboard_fab2(sch_1):m_g_dq(5)") )
				( member ( signalRef "@baseboard_fab2_lib.baseboard_fab2(sch_1):m_g_dq(6)") )
				( member ( signalRef "@baseboard_fab2_lib.baseboard_fab2(sch_1):m_g_dq(7)") )
				( member ( signalRef "@baseboard_fab2_lib.baseboard_fab2(sch_1):m_g_dq(8)") )
				( member ( signalRef "@baseboard_fab2_lib.baseboard_fab2(sch_1):m_g_dq(9)") )
				( member ( signalRef "@baseboard_fab2_lib.baseboard_fab2(sch_1):m_g_dq(10)") )
				( member ( signalRef "@baseboard_fab2_lib.baseboard_fab2(sch_1):m_g_dq(11)") )
				( member ( signalRef "@baseboard_fab2_lib.baseboard_fab2(sch_1):m_g_dq(12)") )
				( member ( signalRef "@baseboard_fab2_lib.baseboard_fab2(sch_1):m_g_dq(13)") )
				( member ( signalRef "@baseboard_fab2_lib.baseboard_fab2(sch_1):m_g_dq(14)") )
				( member ( signalRef "@baseboard_fab2_lib.baseboard_fab2(sch_1):m_g_dq(15)") )
				( member ( signalRef "@baseboard_fab2_lib.baseboard_fab2(sch_1):m_g_dq(16)") )
				( member ( signalRef "@baseboard_fab2_lib.baseboard_fab2(sch_1):m_g_dq(17)") )
				( member ( signalRef "@baseboard_fab2_lib.baseboard_fab2(sch_1):m_g_dq(18)") )
				( member ( signalRef "@baseboard_fab2_lib.baseboard_fab2(sch_1):m_g_dq(19)") )
				( member ( signalRef "@baseboard_fab2_lib.baseboard_fab2(sch_1):m_g_dq(20)") )
				( member ( signalRef "@baseboard_fab2_lib.baseboard_fab2(sch_1):m_g_dq(21)") )
				( member ( signalRef "@baseboard_fab2_lib.baseboard_fab2(sch_1):m_g_dq(22)") )
				( member ( signalRef "@baseboard_fab2_lib.baseboard_fab2(sch_1):m_g_dq(23)") )
				( member ( signalRef "@baseboard_fab2_lib.baseboard_fab2(sch_1):m_g_dq(24)") )
				( member ( signalRef "@baseboard_fab2_lib.baseboard_fab2(sch_1):m_g_dq(25)") )
				( member ( signalRef "@baseboard_fab2_lib.baseboard_fab2(sch_1):m_g_dq(26)") )
				( member ( signalRef "@baseboard_fab2_lib.baseboard_fab2(sch_1):m_g_dq(27)") )
				( member ( signalRef "@baseboard_fab2_lib.baseboard_fab2(sch_1):m_g_dq(28)") )
				( member ( signalRef "@baseboard_fab2_lib.baseboard_fab2(sch_1):m_g_dq(29)") )
				( member ( signalRef "@baseboard_fab2_lib.baseboard_fab2(sch_1):m_g_dq(30)") )
				( member ( signalRef "@baseboard_fab2_lib.baseboard_fab2(sch_1):m_g_dq(31)") )
				( member ( signalRef "@baseboard_fab2_lib.baseboard_fab2(sch_1):m_g_dq(32)") )
				( member ( signalRef "@baseboard_fab2_lib.baseboard_fab2(sch_1):m_g_dq(33)") )
				( member ( signalRef "@baseboard_fab2_lib.baseboard_fab2(sch_1):m_g_dq(34)") )
				( member ( signalRef "@baseboard_fab2_lib.baseboard_fab2(sch_1):m_g_dq(35)") )
				( member ( signalRef "@baseboard_fab2_lib.baseboard_fab2(sch_1):m_g_dq(36)") )
				( member ( signalRef "@baseboard_fab2_lib.baseboard_fab2(sch_1):m_g_dq(37)") )
				( member ( signalRef "@baseboard_fab2_lib.baseboard_fab2(sch_1):m_g_dq(38)") )
				( member ( signalRef "@baseboard_fab2_lib.baseboard_fab2(sch_1):m_g_dq(39)") )
				( member ( signalRef "@baseboard_fab2_lib.baseboard_fab2(sch_1):m_g_dq(40)") )
				( member ( signalRef "@baseboard_fab2_lib.baseboard_fab2(sch_1):m_g_dq(41)") )
				( member ( signalRef "@baseboard_fab2_lib.baseboard_fab2(sch_1):m_g_dq(42)") )
				( member ( signalRef "@baseboard_fab2_lib.baseboard_fab2(sch_1):m_g_dq(43)") )
				( member ( signalRef "@baseboard_fab2_lib.baseboard_fab2(sch_1):m_g_dq(44)") )
				( member ( signalRef "@baseboard_fab2_lib.baseboard_fab2(sch_1):m_g_dq(45)") )
				( member ( signalRef "@baseboard_fab2_lib.baseboard_fab2(sch_1):m_g_dq(46)") )
				( member ( signalRef "@baseboard_fab2_lib.baseboard_fab2(sch_1):m_g_dq(47)") )
				( member ( signalRef "@baseboard_fab2_lib.baseboard_fab2(sch_1):m_g_dq(48)") )
				( member ( signalRef "@baseboard_fab2_lib.baseboard_fab2(sch_1):m_g_dq(49)") )
				( member ( signalRef "@baseboard_fab2_lib.baseboard_fab2(sch_1):m_g_dq(50)") )
				( member ( signalRef "@baseboard_fab2_lib.baseboard_fab2(sch_1):m_g_dq(51)") )
				( member ( signalRef "@baseboard_fab2_lib.baseboard_fab2(sch_1):m_g_dq(52)") )
				( member ( signalRef "@baseboard_fab2_lib.baseboard_fab2(sch_1):m_g_dq(53)") )
				( member ( signalRef "@baseboard_fab2_lib.baseboard_fab2(sch_1):m_g_dq(54)") )
				( member ( signalRef "@baseboard_fab2_lib.baseboard_fab2(sch_1):m_g_dq(55)") )
				( member ( signalRef "@baseboard_fab2_lib.baseboard_fab2(sch_1):m_g_dq(56)") )
				( member ( signalRef "@baseboard_fab2_lib.baseboard_fab2(sch_1):m_g_dq(57)") )
				( member ( signalRef "@baseboard_fab2_lib.baseboard_fab2(sch_1):m_g_dq(58)") )
				( member ( signalRef "@baseboard_fab2_lib.baseboard_fab2(sch_1):m_g_dq(59)") )
				( member ( signalRef "@baseboard_fab2_lib.baseboard_fab2(sch_1):m_g_dq(60)") )
				( member ( signalRef "@baseboard_fab2_lib.baseboard_fab2(sch_1):m_g_dq(61)") )
				( member ( signalRef "@baseboard_fab2_lib.baseboard_fab2(sch_1):m_g_dq(62)") )
				( member ( signalRef "@baseboard_fab2_lib.baseboard_fab2(sch_1):m_g_dq(63)") )
				( objectStatus "M_G_DQ" )
			)
			( bus "@baseboard_fab2_lib.baseboard_fab2(sch_1):m_g_dqs_dn"
				( memberType ( signal ) )
				( member ( signalRef "@baseboard_fab2_lib.baseboard_fab2(sch_1):m_g_dqs_dn(0)") )
				( member ( signalRef "@baseboard_fab2_lib.baseboard_fab2(sch_1):m_g_dqs_dn(1)") )
				( member ( signalRef "@baseboard_fab2_lib.baseboard_fab2(sch_1):m_g_dqs_dn(2)") )
				( member ( signalRef "@baseboard_fab2_lib.baseboard_fab2(sch_1):m_g_dqs_dn(3)") )
				( member ( signalRef "@baseboard_fab2_lib.baseboard_fab2(sch_1):m_g_dqs_dn(4)") )
				( member ( signalRef "@baseboard_fab2_lib.baseboard_fab2(sch_1):m_g_dqs_dn(5)") )
				( member ( signalRef "@baseboard_fab2_lib.baseboard_fab2(sch_1):m_g_dqs_dn(6)") )
				( member ( signalRef "@baseboard_fab2_lib.baseboard_fab2(sch_1):m_g_dqs_dn(7)") )
				( member ( signalRef "@baseboard_fab2_lib.baseboard_fab2(sch_1):m_g_dqs_dn(8)") )
				( member ( signalRef "@baseboard_fab2_lib.baseboard_fab2(sch_1):m_g_dqs_dn(9)") )
				( member ( signalRef "@baseboard_fab2_lib.baseboard_fab2(sch_1):m_g_dqs_dn(10)") )
				( member ( signalRef "@baseboard_fab2_lib.baseboard_fab2(sch_1):m_g_dqs_dn(11)") )
				( member ( signalRef "@baseboard_fab2_lib.baseboard_fab2(sch_1):m_g_dqs_dn(12)") )
				( member ( signalRef "@baseboard_fab2_lib.baseboard_fab2(sch_1):m_g_dqs_dn(13)") )
				( member ( signalRef "@baseboard_fab2_lib.baseboard_fab2(sch_1):m_g_dqs_dn(14)") )
				( member ( signalRef "@baseboard_fab2_lib.baseboard_fab2(sch_1):m_g_dqs_dn(15)") )
				( member ( signalRef "@baseboard_fab2_lib.baseboard_fab2(sch_1):m_g_dqs_dn(16)") )
				( member ( signalRef "@baseboard_fab2_lib.baseboard_fab2(sch_1):m_g_dqs_dn(17)") )
				( objectStatus "M_G_DQS_DN" )
			)
			( bus "@baseboard_fab2_lib.baseboard_fab2(sch_1):m_g_dqs_dp"
				( memberType ( signal ) )
				( member ( signalRef "@baseboard_fab2_lib.baseboard_fab2(sch_1):m_g_dqs_dp(0)") )
				( member ( signalRef "@baseboard_fab2_lib.baseboard_fab2(sch_1):m_g_dqs_dp(1)") )
				( member ( signalRef "@baseboard_fab2_lib.baseboard_fab2(sch_1):m_g_dqs_dp(2)") )
				( member ( signalRef "@baseboard_fab2_lib.baseboard_fab2(sch_1):m_g_dqs_dp(3)") )
				( member ( signalRef "@baseboard_fab2_lib.baseboard_fab2(sch_1):m_g_dqs_dp(4)") )
				( member ( signalRef "@baseboard_fab2_lib.baseboard_fab2(sch_1):m_g_dqs_dp(5)") )
				( member ( signalRef "@baseboard_fab2_lib.baseboard_fab2(sch_1):m_g_dqs_dp(6)") )
				( member ( signalRef "@baseboard_fab2_lib.baseboard_fab2(sch_1):m_g_dqs_dp(7)") )
				( member ( signalRef "@baseboard_fab2_lib.baseboard_fab2(sch_1):m_g_dqs_dp(8)") )
				( member ( signalRef "@baseboard_fab2_lib.baseboard_fab2(sch_1):m_g_dqs_dp(9)") )
				( member ( signalRef "@baseboard_fab2_lib.baseboard_fab2(sch_1):m_g_dqs_dp(10)") )
				( member ( signalRef "@baseboard_fab2_lib.baseboard_fab2(sch_1):m_g_dqs_dp(11)") )
				( member ( signalRef "@baseboard_fab2_lib.baseboard_fab2(sch_1):m_g_dqs_dp(12)") )
				( member ( signalRef "@baseboard_fab2_lib.baseboard_fab2(sch_1):m_g_dqs_dp(13)") )
				( member ( signalRef "@baseboard_fab2_lib.baseboard_fab2(sch_1):m_g_dqs_dp(14)") )
				( member ( signalRef "@baseboard_fab2_lib.baseboard_fab2(sch_1):m_g_dqs_dp(15)") )
				( member ( signalRef "@baseboard_fab2_lib.baseboard_fab2(sch_1):m_g_dqs_dp(16)") )
				( member ( signalRef "@baseboard_fab2_lib.baseboard_fab2(sch_1):m_g_dqs_dp(17)") )
				( objectStatus "M_G_DQS_DP" )
			)
			( bus "@baseboard_fab2_lib.baseboard_fab2(sch_1):m_g_ecc"
				( memberType ( signal ) )
				( member ( signalRef "@baseboard_fab2_lib.baseboard_fab2(sch_1):m_g_ecc(0)") )
				( member ( signalRef "@baseboard_fab2_lib.baseboard_fab2(sch_1):m_g_ecc(1)") )
				( member ( signalRef "@baseboard_fab2_lib.baseboard_fab2(sch_1):m_g_ecc(2)") )
				( member ( signalRef "@baseboard_fab2_lib.baseboard_fab2(sch_1):m_g_ecc(3)") )
				( member ( signalRef "@baseboard_fab2_lib.baseboard_fab2(sch_1):m_g_ecc(4)") )
				( member ( signalRef "@baseboard_fab2_lib.baseboard_fab2(sch_1):m_g_ecc(5)") )
				( member ( signalRef "@baseboard_fab2_lib.baseboard_fab2(sch_1):m_g_ecc(6)") )
				( member ( signalRef "@baseboard_fab2_lib.baseboard_fab2(sch_1):m_g_ecc(7)") )
				( objectStatus "M_G_ECC" )
			)
			( bus "@baseboard_fab2_lib.baseboard_fab2(sch_1):m_g_ma"
				( memberType ( signal ) )
				( member ( signalRef "@baseboard_fab2_lib.baseboard_fab2(sch_1):m_g_ma(0)") )
				( member ( signalRef "@baseboard_fab2_lib.baseboard_fab2(sch_1):m_g_ma(1)") )
				( member ( signalRef "@baseboard_fab2_lib.baseboard_fab2(sch_1):m_g_ma(2)") )
				( member ( signalRef "@baseboard_fab2_lib.baseboard_fab2(sch_1):m_g_ma(3)") )
				( member ( signalRef "@baseboard_fab2_lib.baseboard_fab2(sch_1):m_g_ma(4)") )
				( member ( signalRef "@baseboard_fab2_lib.baseboard_fab2(sch_1):m_g_ma(5)") )
				( member ( signalRef "@baseboard_fab2_lib.baseboard_fab2(sch_1):m_g_ma(6)") )
				( member ( signalRef "@baseboard_fab2_lib.baseboard_fab2(sch_1):m_g_ma(7)") )
				( member ( signalRef "@baseboard_fab2_lib.baseboard_fab2(sch_1):m_g_ma(8)") )
				( member ( signalRef "@baseboard_fab2_lib.baseboard_fab2(sch_1):m_g_ma(9)") )
				( member ( signalRef "@baseboard_fab2_lib.baseboard_fab2(sch_1):m_g_ma(10)") )
				( member ( signalRef "@baseboard_fab2_lib.baseboard_fab2(sch_1):m_g_ma(11)") )
				( member ( signalRef "@baseboard_fab2_lib.baseboard_fab2(sch_1):m_g_ma(12)") )
				( member ( signalRef "@baseboard_fab2_lib.baseboard_fab2(sch_1):m_g_ma(13)") )
				( member ( signalRef "@baseboard_fab2_lib.baseboard_fab2(sch_1):m_g_ma(14)") )
				( member ( signalRef "@baseboard_fab2_lib.baseboard_fab2(sch_1):m_g_ma(15)") )
				( member ( signalRef "@baseboard_fab2_lib.baseboard_fab2(sch_1):m_g_ma(16)") )
				( member ( signalRef "@baseboard_fab2_lib.baseboard_fab2(sch_1):m_g_ma(17)") )
				( objectStatus "M_G_MA" )
			)
			( bus "@baseboard_fab2_lib.baseboard_fab2(sch_1):m_g_odt"
				( memberType ( signal ) )
				( member ( signalRef "@baseboard_fab2_lib.baseboard_fab2(sch_1):m_g_odt(0)") )
				( member ( signalRef "@baseboard_fab2_lib.baseboard_fab2(sch_1):m_g_odt(1)") )
				( member ( signalRef "@baseboard_fab2_lib.baseboard_fab2(sch_1):m_g_odt(2)") )
				( member ( signalRef "@baseboard_fab2_lib.baseboard_fab2(sch_1):m_g_odt(3)") )
				( objectStatus "M_G_ODT" )
			)
			( bus "@baseboard_fab2_lib.baseboard_fab2(sch_1):m_h_ba"
				( memberType ( signal ) )
				( member ( signalRef "@baseboard_fab2_lib.baseboard_fab2(sch_1):m_h_ba(0)") )
				( member ( signalRef "@baseboard_fab2_lib.baseboard_fab2(sch_1):m_h_ba(1)") )
				( objectStatus "M_H_BA" )
			)
			( bus "@baseboard_fab2_lib.baseboard_fab2(sch_1):m_h_bg"
				( memberType ( signal ) )
				( member ( signalRef "@baseboard_fab2_lib.baseboard_fab2(sch_1):m_h_bg(0)") )
				( member ( signalRef "@baseboard_fab2_lib.baseboard_fab2(sch_1):m_h_bg(1)") )
				( objectStatus "M_H_BG" )
			)
			( bus "@baseboard_fab2_lib.baseboard_fab2(sch_1):m_h_c"
				( memberType ( signal ) )
				( member ( signalRef "@baseboard_fab2_lib.baseboard_fab2(sch_1):m_h_c(2)") )
				( objectStatus "M_H_C" )
			)
			( bus "@baseboard_fab2_lib.baseboard_fab2(sch_1):m_h_cke"
				( memberType ( signal ) )
				( member ( signalRef "@baseboard_fab2_lib.baseboard_fab2(sch_1):m_h_cke(0)") )
				( member ( signalRef "@baseboard_fab2_lib.baseboard_fab2(sch_1):m_h_cke(1)") )
				( member ( signalRef "@baseboard_fab2_lib.baseboard_fab2(sch_1):m_h_cke(2)") )
				( member ( signalRef "@baseboard_fab2_lib.baseboard_fab2(sch_1):m_h_cke(3)") )
				( objectStatus "M_H_CKE" )
			)
			( bus "@baseboard_fab2_lib.baseboard_fab2(sch_1):m_h_clk_dn"
				( memberType ( signal ) )
				( member ( signalRef "@baseboard_fab2_lib.baseboard_fab2(sch_1):m_h_clk_dn(0)") )
				( member ( signalRef "@baseboard_fab2_lib.baseboard_fab2(sch_1):m_h_clk_dn(1)") )
				( member ( signalRef "@baseboard_fab2_lib.baseboard_fab2(sch_1):m_h_clk_dn(2)") )
				( member ( signalRef "@baseboard_fab2_lib.baseboard_fab2(sch_1):m_h_clk_dn(3)") )
				( objectStatus "M_H_CLK_DN" )
			)
			( bus "@baseboard_fab2_lib.baseboard_fab2(sch_1):m_h_clk_dp"
				( memberType ( signal ) )
				( member ( signalRef "@baseboard_fab2_lib.baseboard_fab2(sch_1):m_h_clk_dp(0)") )
				( member ( signalRef "@baseboard_fab2_lib.baseboard_fab2(sch_1):m_h_clk_dp(1)") )
				( member ( signalRef "@baseboard_fab2_lib.baseboard_fab2(sch_1):m_h_clk_dp(2)") )
				( member ( signalRef "@baseboard_fab2_lib.baseboard_fab2(sch_1):m_h_clk_dp(3)") )
				( objectStatus "M_H_CLK_DP" )
			)
			( bus "@baseboard_fab2_lib.baseboard_fab2(sch_1):m_h_cs_n"
				( memberType ( signal ) )
				( member ( signalRef "@baseboard_fab2_lib.baseboard_fab2(sch_1):m_h_cs_n(0)") )
				( member ( signalRef "@baseboard_fab2_lib.baseboard_fab2(sch_1):m_h_cs_n(1)") )
				( member ( signalRef "@baseboard_fab2_lib.baseboard_fab2(sch_1):m_h_cs_n(2)") )
				( member ( signalRef "@baseboard_fab2_lib.baseboard_fab2(sch_1):m_h_cs_n(3)") )
				( member ( signalRef "@baseboard_fab2_lib.baseboard_fab2(sch_1):m_h_cs_n(4)") )
				( member ( signalRef "@baseboard_fab2_lib.baseboard_fab2(sch_1):m_h_cs_n(5)") )
				( member ( signalRef "@baseboard_fab2_lib.baseboard_fab2(sch_1):m_h_cs_n(6)") )
				( member ( signalRef "@baseboard_fab2_lib.baseboard_fab2(sch_1):m_h_cs_n(7)") )
				( objectStatus "M_H_CS_N" )
			)
			( bus "@baseboard_fab2_lib.baseboard_fab2(sch_1):m_h_dq"
				( memberType ( signal ) )
				( member ( signalRef "@baseboard_fab2_lib.baseboard_fab2(sch_1):m_h_dq(0)") )
				( member ( signalRef "@baseboard_fab2_lib.baseboard_fab2(sch_1):m_h_dq(1)") )
				( member ( signalRef "@baseboard_fab2_lib.baseboard_fab2(sch_1):m_h_dq(2)") )
				( member ( signalRef "@baseboard_fab2_lib.baseboard_fab2(sch_1):m_h_dq(3)") )
				( member ( signalRef "@baseboard_fab2_lib.baseboard_fab2(sch_1):m_h_dq(4)") )
				( member ( signalRef "@baseboard_fab2_lib.baseboard_fab2(sch_1):m_h_dq(5)") )
				( member ( signalRef "@baseboard_fab2_lib.baseboard_fab2(sch_1):m_h_dq(6)") )
				( member ( signalRef "@baseboard_fab2_lib.baseboard_fab2(sch_1):m_h_dq(7)") )
				( member ( signalRef "@baseboard_fab2_lib.baseboard_fab2(sch_1):m_h_dq(8)") )
				( member ( signalRef "@baseboard_fab2_lib.baseboard_fab2(sch_1):m_h_dq(9)") )
				( member ( signalRef "@baseboard_fab2_lib.baseboard_fab2(sch_1):m_h_dq(10)") )
				( member ( signalRef "@baseboard_fab2_lib.baseboard_fab2(sch_1):m_h_dq(11)") )
				( member ( signalRef "@baseboard_fab2_lib.baseboard_fab2(sch_1):m_h_dq(12)") )
				( member ( signalRef "@baseboard_fab2_lib.baseboard_fab2(sch_1):m_h_dq(13)") )
				( member ( signalRef "@baseboard_fab2_lib.baseboard_fab2(sch_1):m_h_dq(14)") )
				( member ( signalRef "@baseboard_fab2_lib.baseboard_fab2(sch_1):m_h_dq(15)") )
				( member ( signalRef "@baseboard_fab2_lib.baseboard_fab2(sch_1):m_h_dq(16)") )
				( member ( signalRef "@baseboard_fab2_lib.baseboard_fab2(sch_1):m_h_dq(17)") )
				( member ( signalRef "@baseboard_fab2_lib.baseboard_fab2(sch_1):m_h_dq(18)") )
				( member ( signalRef "@baseboard_fab2_lib.baseboard_fab2(sch_1):m_h_dq(19)") )
				( member ( signalRef "@baseboard_fab2_lib.baseboard_fab2(sch_1):m_h_dq(20)") )
				( member ( signalRef "@baseboard_fab2_lib.baseboard_fab2(sch_1):m_h_dq(21)") )
				( member ( signalRef "@baseboard_fab2_lib.baseboard_fab2(sch_1):m_h_dq(22)") )
				( member ( signalRef "@baseboard_fab2_lib.baseboard_fab2(sch_1):m_h_dq(23)") )
				( member ( signalRef "@baseboard_fab2_lib.baseboard_fab2(sch_1):m_h_dq(24)") )
				( member ( signalRef "@baseboard_fab2_lib.baseboard_fab2(sch_1):m_h_dq(25)") )
				( member ( signalRef "@baseboard_fab2_lib.baseboard_fab2(sch_1):m_h_dq(26)") )
				( member ( signalRef "@baseboard_fab2_lib.baseboard_fab2(sch_1):m_h_dq(27)") )
				( member ( signalRef "@baseboard_fab2_lib.baseboard_fab2(sch_1):m_h_dq(28)") )
				( member ( signalRef "@baseboard_fab2_lib.baseboard_fab2(sch_1):m_h_dq(29)") )
				( member ( signalRef "@baseboard_fab2_lib.baseboard_fab2(sch_1):m_h_dq(30)") )
				( member ( signalRef "@baseboard_fab2_lib.baseboard_fab2(sch_1):m_h_dq(31)") )
				( member ( signalRef "@baseboard_fab2_lib.baseboard_fab2(sch_1):m_h_dq(32)") )
				( member ( signalRef "@baseboard_fab2_lib.baseboard_fab2(sch_1):m_h_dq(33)") )
				( member ( signalRef "@baseboard_fab2_lib.baseboard_fab2(sch_1):m_h_dq(34)") )
				( member ( signalRef "@baseboard_fab2_lib.baseboard_fab2(sch_1):m_h_dq(35)") )
				( member ( signalRef "@baseboard_fab2_lib.baseboard_fab2(sch_1):m_h_dq(36)") )
				( member ( signalRef "@baseboard_fab2_lib.baseboard_fab2(sch_1):m_h_dq(37)") )
				( member ( signalRef "@baseboard_fab2_lib.baseboard_fab2(sch_1):m_h_dq(38)") )
				( member ( signalRef "@baseboard_fab2_lib.baseboard_fab2(sch_1):m_h_dq(39)") )
				( member ( signalRef "@baseboard_fab2_lib.baseboard_fab2(sch_1):m_h_dq(40)") )
				( member ( signalRef "@baseboard_fab2_lib.baseboard_fab2(sch_1):m_h_dq(41)") )
				( member ( signalRef "@baseboard_fab2_lib.baseboard_fab2(sch_1):m_h_dq(42)") )
				( member ( signalRef "@baseboard_fab2_lib.baseboard_fab2(sch_1):m_h_dq(43)") )
				( member ( signalRef "@baseboard_fab2_lib.baseboard_fab2(sch_1):m_h_dq(44)") )
				( member ( signalRef "@baseboard_fab2_lib.baseboard_fab2(sch_1):m_h_dq(45)") )
				( member ( signalRef "@baseboard_fab2_lib.baseboard_fab2(sch_1):m_h_dq(46)") )
				( member ( signalRef "@baseboard_fab2_lib.baseboard_fab2(sch_1):m_h_dq(47)") )
				( member ( signalRef "@baseboard_fab2_lib.baseboard_fab2(sch_1):m_h_dq(48)") )
				( member ( signalRef "@baseboard_fab2_lib.baseboard_fab2(sch_1):m_h_dq(49)") )
				( member ( signalRef "@baseboard_fab2_lib.baseboard_fab2(sch_1):m_h_dq(50)") )
				( member ( signalRef "@baseboard_fab2_lib.baseboard_fab2(sch_1):m_h_dq(51)") )
				( member ( signalRef "@baseboard_fab2_lib.baseboard_fab2(sch_1):m_h_dq(52)") )
				( member ( signalRef "@baseboard_fab2_lib.baseboard_fab2(sch_1):m_h_dq(53)") )
				( member ( signalRef "@baseboard_fab2_lib.baseboard_fab2(sch_1):m_h_dq(54)") )
				( member ( signalRef "@baseboard_fab2_lib.baseboard_fab2(sch_1):m_h_dq(55)") )
				( member ( signalRef "@baseboard_fab2_lib.baseboard_fab2(sch_1):m_h_dq(56)") )
				( member ( signalRef "@baseboard_fab2_lib.baseboard_fab2(sch_1):m_h_dq(57)") )
				( member ( signalRef "@baseboard_fab2_lib.baseboard_fab2(sch_1):m_h_dq(58)") )
				( member ( signalRef "@baseboard_fab2_lib.baseboard_fab2(sch_1):m_h_dq(59)") )
				( member ( signalRef "@baseboard_fab2_lib.baseboard_fab2(sch_1):m_h_dq(60)") )
				( member ( signalRef "@baseboard_fab2_lib.baseboard_fab2(sch_1):m_h_dq(61)") )
				( member ( signalRef "@baseboard_fab2_lib.baseboard_fab2(sch_1):m_h_dq(62)") )
				( member ( signalRef "@baseboard_fab2_lib.baseboard_fab2(sch_1):m_h_dq(63)") )
				( objectStatus "M_H_DQ" )
			)
			( bus "@baseboard_fab2_lib.baseboard_fab2(sch_1):m_h_dqs_dn"
				( memberType ( signal ) )
				( member ( signalRef "@baseboard_fab2_lib.baseboard_fab2(sch_1):m_h_dqs_dn(0)") )
				( member ( signalRef "@baseboard_fab2_lib.baseboard_fab2(sch_1):m_h_dqs_dn(1)") )
				( member ( signalRef "@baseboard_fab2_lib.baseboard_fab2(sch_1):m_h_dqs_dn(2)") )
				( member ( signalRef "@baseboard_fab2_lib.baseboard_fab2(sch_1):m_h_dqs_dn(3)") )
				( member ( signalRef "@baseboard_fab2_lib.baseboard_fab2(sch_1):m_h_dqs_dn(4)") )
				( member ( signalRef "@baseboard_fab2_lib.baseboard_fab2(sch_1):m_h_dqs_dn(5)") )
				( member ( signalRef "@baseboard_fab2_lib.baseboard_fab2(sch_1):m_h_dqs_dn(6)") )
				( member ( signalRef "@baseboard_fab2_lib.baseboard_fab2(sch_1):m_h_dqs_dn(7)") )
				( member ( signalRef "@baseboard_fab2_lib.baseboard_fab2(sch_1):m_h_dqs_dn(8)") )
				( member ( signalRef "@baseboard_fab2_lib.baseboard_fab2(sch_1):m_h_dqs_dn(9)") )
				( member ( signalRef "@baseboard_fab2_lib.baseboard_fab2(sch_1):m_h_dqs_dn(10)") )
				( member ( signalRef "@baseboard_fab2_lib.baseboard_fab2(sch_1):m_h_dqs_dn(11)") )
				( member ( signalRef "@baseboard_fab2_lib.baseboard_fab2(sch_1):m_h_dqs_dn(12)") )
				( member ( signalRef "@baseboard_fab2_lib.baseboard_fab2(sch_1):m_h_dqs_dn(13)") )
				( member ( signalRef "@baseboard_fab2_lib.baseboard_fab2(sch_1):m_h_dqs_dn(14)") )
				( member ( signalRef "@baseboard_fab2_lib.baseboard_fab2(sch_1):m_h_dqs_dn(15)") )
				( member ( signalRef "@baseboard_fab2_lib.baseboard_fab2(sch_1):m_h_dqs_dn(16)") )
				( member ( signalRef "@baseboard_fab2_lib.baseboard_fab2(sch_1):m_h_dqs_dn(17)") )
				( objectStatus "M_H_DQS_DN" )
			)
			( bus "@baseboard_fab2_lib.baseboard_fab2(sch_1):m_h_dqs_dp"
				( memberType ( signal ) )
				( member ( signalRef "@baseboard_fab2_lib.baseboard_fab2(sch_1):m_h_dqs_dp(0)") )
				( member ( signalRef "@baseboard_fab2_lib.baseboard_fab2(sch_1):m_h_dqs_dp(1)") )
				( member ( signalRef "@baseboard_fab2_lib.baseboard_fab2(sch_1):m_h_dqs_dp(2)") )
				( member ( signalRef "@baseboard_fab2_lib.baseboard_fab2(sch_1):m_h_dqs_dp(3)") )
				( member ( signalRef "@baseboard_fab2_lib.baseboard_fab2(sch_1):m_h_dqs_dp(4)") )
				( member ( signalRef "@baseboard_fab2_lib.baseboard_fab2(sch_1):m_h_dqs_dp(5)") )
				( member ( signalRef "@baseboard_fab2_lib.baseboard_fab2(sch_1):m_h_dqs_dp(6)") )
				( member ( signalRef "@baseboard_fab2_lib.baseboard_fab2(sch_1):m_h_dqs_dp(7)") )
				( member ( signalRef "@baseboard_fab2_lib.baseboard_fab2(sch_1):m_h_dqs_dp(8)") )
				( member ( signalRef "@baseboard_fab2_lib.baseboard_fab2(sch_1):m_h_dqs_dp(9)") )
				( member ( signalRef "@baseboard_fab2_lib.baseboard_fab2(sch_1):m_h_dqs_dp(10)") )
				( member ( signalRef "@baseboard_fab2_lib.baseboard_fab2(sch_1):m_h_dqs_dp(11)") )
				( member ( signalRef "@baseboard_fab2_lib.baseboard_fab2(sch_1):m_h_dqs_dp(12)") )
				( member ( signalRef "@baseboard_fab2_lib.baseboard_fab2(sch_1):m_h_dqs_dp(13)") )
				( member ( signalRef "@baseboard_fab2_lib.baseboard_fab2(sch_1):m_h_dqs_dp(14)") )
				( member ( signalRef "@baseboard_fab2_lib.baseboard_fab2(sch_1):m_h_dqs_dp(15)") )
				( member ( signalRef "@baseboard_fab2_lib.baseboard_fab2(sch_1):m_h_dqs_dp(16)") )
				( member ( signalRef "@baseboard_fab2_lib.baseboard_fab2(sch_1):m_h_dqs_dp(17)") )
				( objectStatus "M_H_DQS_DP" )
			)
			( bus "@baseboard_fab2_lib.baseboard_fab2(sch_1):m_h_ecc"
				( memberType ( signal ) )
				( member ( signalRef "@baseboard_fab2_lib.baseboard_fab2(sch_1):m_h_ecc(0)") )
				( member ( signalRef "@baseboard_fab2_lib.baseboard_fab2(sch_1):m_h_ecc(1)") )
				( member ( signalRef "@baseboard_fab2_lib.baseboard_fab2(sch_1):m_h_ecc(2)") )
				( member ( signalRef "@baseboard_fab2_lib.baseboard_fab2(sch_1):m_h_ecc(3)") )
				( member ( signalRef "@baseboard_fab2_lib.baseboard_fab2(sch_1):m_h_ecc(4)") )
				( member ( signalRef "@baseboard_fab2_lib.baseboard_fab2(sch_1):m_h_ecc(5)") )
				( member ( signalRef "@baseboard_fab2_lib.baseboard_fab2(sch_1):m_h_ecc(6)") )
				( member ( signalRef "@baseboard_fab2_lib.baseboard_fab2(sch_1):m_h_ecc(7)") )
				( objectStatus "M_H_ECC" )
			)
			( bus "@baseboard_fab2_lib.baseboard_fab2(sch_1):m_h_ma"
				( memberType ( signal ) )
				( member ( signalRef "@baseboard_fab2_lib.baseboard_fab2(sch_1):m_h_ma(0)") )
				( member ( signalRef "@baseboard_fab2_lib.baseboard_fab2(sch_1):m_h_ma(1)") )
				( member ( signalRef "@baseboard_fab2_lib.baseboard_fab2(sch_1):m_h_ma(2)") )
				( member ( signalRef "@baseboard_fab2_lib.baseboard_fab2(sch_1):m_h_ma(3)") )
				( member ( signalRef "@baseboard_fab2_lib.baseboard_fab2(sch_1):m_h_ma(4)") )
				( member ( signalRef "@baseboard_fab2_lib.baseboard_fab2(sch_1):m_h_ma(5)") )
				( member ( signalRef "@baseboard_fab2_lib.baseboard_fab2(sch_1):m_h_ma(6)") )
				( member ( signalRef "@baseboard_fab2_lib.baseboard_fab2(sch_1):m_h_ma(7)") )
				( member ( signalRef "@baseboard_fab2_lib.baseboard_fab2(sch_1):m_h_ma(8)") )
				( member ( signalRef "@baseboard_fab2_lib.baseboard_fab2(sch_1):m_h_ma(9)") )
				( member ( signalRef "@baseboard_fab2_lib.baseboard_fab2(sch_1):m_h_ma(10)") )
				( member ( signalRef "@baseboard_fab2_lib.baseboard_fab2(sch_1):m_h_ma(11)") )
				( member ( signalRef "@baseboard_fab2_lib.baseboard_fab2(sch_1):m_h_ma(12)") )
				( member ( signalRef "@baseboard_fab2_lib.baseboard_fab2(sch_1):m_h_ma(13)") )
				( member ( signalRef "@baseboard_fab2_lib.baseboard_fab2(sch_1):m_h_ma(14)") )
				( member ( signalRef "@baseboard_fab2_lib.baseboard_fab2(sch_1):m_h_ma(15)") )
				( member ( signalRef "@baseboard_fab2_lib.baseboard_fab2(sch_1):m_h_ma(16)") )
				( member ( signalRef "@baseboard_fab2_lib.baseboard_fab2(sch_1):m_h_ma(17)") )
				( objectStatus "M_H_MA" )
			)
			( bus "@baseboard_fab2_lib.baseboard_fab2(sch_1):m_h_odt"
				( memberType ( signal ) )
				( member ( signalRef "@baseboard_fab2_lib.baseboard_fab2(sch_1):m_h_odt(0)") )
				( member ( signalRef "@baseboard_fab2_lib.baseboard_fab2(sch_1):m_h_odt(1)") )
				( member ( signalRef "@baseboard_fab2_lib.baseboard_fab2(sch_1):m_h_odt(2)") )
				( member ( signalRef "@baseboard_fab2_lib.baseboard_fab2(sch_1):m_h_odt(3)") )
				( objectStatus "M_H_ODT" )
			)
			( bus "@baseboard_fab2_lib.baseboard_fab2(sch_1):m_j_ba"
				( memberType ( signal ) )
				( member ( signalRef "@baseboard_fab2_lib.baseboard_fab2(sch_1):m_j_ba(0)") )
				( member ( signalRef "@baseboard_fab2_lib.baseboard_fab2(sch_1):m_j_ba(1)") )
				( objectStatus "M_J_BA" )
			)
			( bus "@baseboard_fab2_lib.baseboard_fab2(sch_1):m_j_bg"
				( memberType ( signal ) )
				( member ( signalRef "@baseboard_fab2_lib.baseboard_fab2(sch_1):m_j_bg(0)") )
				( member ( signalRef "@baseboard_fab2_lib.baseboard_fab2(sch_1):m_j_bg(1)") )
				( objectStatus "M_J_BG" )
			)
			( bus "@baseboard_fab2_lib.baseboard_fab2(sch_1):m_j_c"
				( memberType ( signal ) )
				( member ( signalRef "@baseboard_fab2_lib.baseboard_fab2(sch_1):m_j_c(2)") )
				( objectStatus "M_J_C" )
			)
			( bus "@baseboard_fab2_lib.baseboard_fab2(sch_1):m_j_cke"
				( memberType ( signal ) )
				( member ( signalRef "@baseboard_fab2_lib.baseboard_fab2(sch_1):m_j_cke(0)") )
				( member ( signalRef "@baseboard_fab2_lib.baseboard_fab2(sch_1):m_j_cke(1)") )
				( member ( signalRef "@baseboard_fab2_lib.baseboard_fab2(sch_1):m_j_cke(2)") )
				( member ( signalRef "@baseboard_fab2_lib.baseboard_fab2(sch_1):m_j_cke(3)") )
				( objectStatus "M_J_CKE" )
			)
			( bus "@baseboard_fab2_lib.baseboard_fab2(sch_1):m_j_clk_dn"
				( memberType ( signal ) )
				( member ( signalRef "@baseboard_fab2_lib.baseboard_fab2(sch_1):m_j_clk_dn(0)") )
				( member ( signalRef "@baseboard_fab2_lib.baseboard_fab2(sch_1):m_j_clk_dn(1)") )
				( member ( signalRef "@baseboard_fab2_lib.baseboard_fab2(sch_1):m_j_clk_dn(2)") )
				( member ( signalRef "@baseboard_fab2_lib.baseboard_fab2(sch_1):m_j_clk_dn(3)") )
				( objectStatus "M_J_CLK_DN" )
			)
			( bus "@baseboard_fab2_lib.baseboard_fab2(sch_1):m_j_clk_dp"
				( memberType ( signal ) )
				( member ( signalRef "@baseboard_fab2_lib.baseboard_fab2(sch_1):m_j_clk_dp(0)") )
				( member ( signalRef "@baseboard_fab2_lib.baseboard_fab2(sch_1):m_j_clk_dp(1)") )
				( member ( signalRef "@baseboard_fab2_lib.baseboard_fab2(sch_1):m_j_clk_dp(2)") )
				( member ( signalRef "@baseboard_fab2_lib.baseboard_fab2(sch_1):m_j_clk_dp(3)") )
				( objectStatus "M_J_CLK_DP" )
			)
			( bus "@baseboard_fab2_lib.baseboard_fab2(sch_1):m_j_cs_n"
				( memberType ( signal ) )
				( member ( signalRef "@baseboard_fab2_lib.baseboard_fab2(sch_1):m_j_cs_n(0)") )
				( member ( signalRef "@baseboard_fab2_lib.baseboard_fab2(sch_1):m_j_cs_n(1)") )
				( member ( signalRef "@baseboard_fab2_lib.baseboard_fab2(sch_1):m_j_cs_n(2)") )
				( member ( signalRef "@baseboard_fab2_lib.baseboard_fab2(sch_1):m_j_cs_n(3)") )
				( member ( signalRef "@baseboard_fab2_lib.baseboard_fab2(sch_1):m_j_cs_n(4)") )
				( member ( signalRef "@baseboard_fab2_lib.baseboard_fab2(sch_1):m_j_cs_n(5)") )
				( member ( signalRef "@baseboard_fab2_lib.baseboard_fab2(sch_1):m_j_cs_n(6)") )
				( member ( signalRef "@baseboard_fab2_lib.baseboard_fab2(sch_1):m_j_cs_n(7)") )
				( objectStatus "M_J_CS_N" )
			)
			( bus "@baseboard_fab2_lib.baseboard_fab2(sch_1):m_j_dq"
				( memberType ( signal ) )
				( member ( signalRef "@baseboard_fab2_lib.baseboard_fab2(sch_1):m_j_dq(0)") )
				( member ( signalRef "@baseboard_fab2_lib.baseboard_fab2(sch_1):m_j_dq(1)") )
				( member ( signalRef "@baseboard_fab2_lib.baseboard_fab2(sch_1):m_j_dq(2)") )
				( member ( signalRef "@baseboard_fab2_lib.baseboard_fab2(sch_1):m_j_dq(3)") )
				( member ( signalRef "@baseboard_fab2_lib.baseboard_fab2(sch_1):m_j_dq(4)") )
				( member ( signalRef "@baseboard_fab2_lib.baseboard_fab2(sch_1):m_j_dq(5)") )
				( member ( signalRef "@baseboard_fab2_lib.baseboard_fab2(sch_1):m_j_dq(6)") )
				( member ( signalRef "@baseboard_fab2_lib.baseboard_fab2(sch_1):m_j_dq(7)") )
				( member ( signalRef "@baseboard_fab2_lib.baseboard_fab2(sch_1):m_j_dq(8)") )
				( member ( signalRef "@baseboard_fab2_lib.baseboard_fab2(sch_1):m_j_dq(9)") )
				( member ( signalRef "@baseboard_fab2_lib.baseboard_fab2(sch_1):m_j_dq(10)") )
				( member ( signalRef "@baseboard_fab2_lib.baseboard_fab2(sch_1):m_j_dq(11)") )
				( member ( signalRef "@baseboard_fab2_lib.baseboard_fab2(sch_1):m_j_dq(12)") )
				( member ( signalRef "@baseboard_fab2_lib.baseboard_fab2(sch_1):m_j_dq(13)") )
				( member ( signalRef "@baseboard_fab2_lib.baseboard_fab2(sch_1):m_j_dq(14)") )
				( member ( signalRef "@baseboard_fab2_lib.baseboard_fab2(sch_1):m_j_dq(15)") )
				( member ( signalRef "@baseboard_fab2_lib.baseboard_fab2(sch_1):m_j_dq(16)") )
				( member ( signalRef "@baseboard_fab2_lib.baseboard_fab2(sch_1):m_j_dq(17)") )
				( member ( signalRef "@baseboard_fab2_lib.baseboard_fab2(sch_1):m_j_dq(18)") )
				( member ( signalRef "@baseboard_fab2_lib.baseboard_fab2(sch_1):m_j_dq(19)") )
				( member ( signalRef "@baseboard_fab2_lib.baseboard_fab2(sch_1):m_j_dq(20)") )
				( member ( signalRef "@baseboard_fab2_lib.baseboard_fab2(sch_1):m_j_dq(21)") )
				( member ( signalRef "@baseboard_fab2_lib.baseboard_fab2(sch_1):m_j_dq(22)") )
				( member ( signalRef "@baseboard_fab2_lib.baseboard_fab2(sch_1):m_j_dq(23)") )
				( member ( signalRef "@baseboard_fab2_lib.baseboard_fab2(sch_1):m_j_dq(24)") )
				( member ( signalRef "@baseboard_fab2_lib.baseboard_fab2(sch_1):m_j_dq(25)") )
				( member ( signalRef "@baseboard_fab2_lib.baseboard_fab2(sch_1):m_j_dq(26)") )
				( member ( signalRef "@baseboard_fab2_lib.baseboard_fab2(sch_1):m_j_dq(27)") )
				( member ( signalRef "@baseboard_fab2_lib.baseboard_fab2(sch_1):m_j_dq(28)") )
				( member ( signalRef "@baseboard_fab2_lib.baseboard_fab2(sch_1):m_j_dq(29)") )
				( member ( signalRef "@baseboard_fab2_lib.baseboard_fab2(sch_1):m_j_dq(30)") )
				( member ( signalRef "@baseboard_fab2_lib.baseboard_fab2(sch_1):m_j_dq(31)") )
				( member ( signalRef "@baseboard_fab2_lib.baseboard_fab2(sch_1):m_j_dq(32)") )
				( member ( signalRef "@baseboard_fab2_lib.baseboard_fab2(sch_1):m_j_dq(33)") )
				( member ( signalRef "@baseboard_fab2_lib.baseboard_fab2(sch_1):m_j_dq(34)") )
				( member ( signalRef "@baseboard_fab2_lib.baseboard_fab2(sch_1):m_j_dq(35)") )
				( member ( signalRef "@baseboard_fab2_lib.baseboard_fab2(sch_1):m_j_dq(36)") )
				( member ( signalRef "@baseboard_fab2_lib.baseboard_fab2(sch_1):m_j_dq(37)") )
				( member ( signalRef "@baseboard_fab2_lib.baseboard_fab2(sch_1):m_j_dq(38)") )
				( member ( signalRef "@baseboard_fab2_lib.baseboard_fab2(sch_1):m_j_dq(39)") )
				( member ( signalRef "@baseboard_fab2_lib.baseboard_fab2(sch_1):m_j_dq(40)") )
				( member ( signalRef "@baseboard_fab2_lib.baseboard_fab2(sch_1):m_j_dq(41)") )
				( member ( signalRef "@baseboard_fab2_lib.baseboard_fab2(sch_1):m_j_dq(42)") )
				( member ( signalRef "@baseboard_fab2_lib.baseboard_fab2(sch_1):m_j_dq(43)") )
				( member ( signalRef "@baseboard_fab2_lib.baseboard_fab2(sch_1):m_j_dq(44)") )
				( member ( signalRef "@baseboard_fab2_lib.baseboard_fab2(sch_1):m_j_dq(45)") )
				( member ( signalRef "@baseboard_fab2_lib.baseboard_fab2(sch_1):m_j_dq(46)") )
				( member ( signalRef "@baseboard_fab2_lib.baseboard_fab2(sch_1):m_j_dq(47)") )
				( member ( signalRef "@baseboard_fab2_lib.baseboard_fab2(sch_1):m_j_dq(48)") )
				( member ( signalRef "@baseboard_fab2_lib.baseboard_fab2(sch_1):m_j_dq(49)") )
				( member ( signalRef "@baseboard_fab2_lib.baseboard_fab2(sch_1):m_j_dq(50)") )
				( member ( signalRef "@baseboard_fab2_lib.baseboard_fab2(sch_1):m_j_dq(51)") )
				( member ( signalRef "@baseboard_fab2_lib.baseboard_fab2(sch_1):m_j_dq(52)") )
				( member ( signalRef "@baseboard_fab2_lib.baseboard_fab2(sch_1):m_j_dq(53)") )
				( member ( signalRef "@baseboard_fab2_lib.baseboard_fab2(sch_1):m_j_dq(54)") )
				( member ( signalRef "@baseboard_fab2_lib.baseboard_fab2(sch_1):m_j_dq(55)") )
				( member ( signalRef "@baseboard_fab2_lib.baseboard_fab2(sch_1):m_j_dq(56)") )
				( member ( signalRef "@baseboard_fab2_lib.baseboard_fab2(sch_1):m_j_dq(57)") )
				( member ( signalRef "@baseboard_fab2_lib.baseboard_fab2(sch_1):m_j_dq(58)") )
				( member ( signalRef "@baseboard_fab2_lib.baseboard_fab2(sch_1):m_j_dq(59)") )
				( member ( signalRef "@baseboard_fab2_lib.baseboard_fab2(sch_1):m_j_dq(60)") )
				( member ( signalRef "@baseboard_fab2_lib.baseboard_fab2(sch_1):m_j_dq(61)") )
				( member ( signalRef "@baseboard_fab2_lib.baseboard_fab2(sch_1):m_j_dq(62)") )
				( member ( signalRef "@baseboard_fab2_lib.baseboard_fab2(sch_1):m_j_dq(63)") )
				( objectStatus "M_J_DQ" )
			)
			( bus "@baseboard_fab2_lib.baseboard_fab2(sch_1):m_j_dqs_dn"
				( memberType ( signal ) )
				( member ( signalRef "@baseboard_fab2_lib.baseboard_fab2(sch_1):m_j_dqs_dn(0)") )
				( member ( signalRef "@baseboard_fab2_lib.baseboard_fab2(sch_1):m_j_dqs_dn(1)") )
				( member ( signalRef "@baseboard_fab2_lib.baseboard_fab2(sch_1):m_j_dqs_dn(2)") )
				( member ( signalRef "@baseboard_fab2_lib.baseboard_fab2(sch_1):m_j_dqs_dn(3)") )
				( member ( signalRef "@baseboard_fab2_lib.baseboard_fab2(sch_1):m_j_dqs_dn(4)") )
				( member ( signalRef "@baseboard_fab2_lib.baseboard_fab2(sch_1):m_j_dqs_dn(5)") )
				( member ( signalRef "@baseboard_fab2_lib.baseboard_fab2(sch_1):m_j_dqs_dn(6)") )
				( member ( signalRef "@baseboard_fab2_lib.baseboard_fab2(sch_1):m_j_dqs_dn(7)") )
				( member ( signalRef "@baseboard_fab2_lib.baseboard_fab2(sch_1):m_j_dqs_dn(8)") )
				( member ( signalRef "@baseboard_fab2_lib.baseboard_fab2(sch_1):m_j_dqs_dn(9)") )
				( member ( signalRef "@baseboard_fab2_lib.baseboard_fab2(sch_1):m_j_dqs_dn(10)") )
				( member ( signalRef "@baseboard_fab2_lib.baseboard_fab2(sch_1):m_j_dqs_dn(11)") )
				( member ( signalRef "@baseboard_fab2_lib.baseboard_fab2(sch_1):m_j_dqs_dn(12)") )
				( member ( signalRef "@baseboard_fab2_lib.baseboard_fab2(sch_1):m_j_dqs_dn(13)") )
				( member ( signalRef "@baseboard_fab2_lib.baseboard_fab2(sch_1):m_j_dqs_dn(14)") )
				( member ( signalRef "@baseboard_fab2_lib.baseboard_fab2(sch_1):m_j_dqs_dn(15)") )
				( member ( signalRef "@baseboard_fab2_lib.baseboard_fab2(sch_1):m_j_dqs_dn(16)") )
				( member ( signalRef "@baseboard_fab2_lib.baseboard_fab2(sch_1):m_j_dqs_dn(17)") )
				( objectStatus "M_J_DQS_DN" )
			)
			( bus "@baseboard_fab2_lib.baseboard_fab2(sch_1):m_j_dqs_dp"
				( memberType ( signal ) )
				( member ( signalRef "@baseboard_fab2_lib.baseboard_fab2(sch_1):m_j_dqs_dp(0)") )
				( member ( signalRef "@baseboard_fab2_lib.baseboard_fab2(sch_1):m_j_dqs_dp(1)") )
				( member ( signalRef "@baseboard_fab2_lib.baseboard_fab2(sch_1):m_j_dqs_dp(2)") )
				( member ( signalRef "@baseboard_fab2_lib.baseboard_fab2(sch_1):m_j_dqs_dp(3)") )
				( member ( signalRef "@baseboard_fab2_lib.baseboard_fab2(sch_1):m_j_dqs_dp(4)") )
				( member ( signalRef "@baseboard_fab2_lib.baseboard_fab2(sch_1):m_j_dqs_dp(5)") )
				( member ( signalRef "@baseboard_fab2_lib.baseboard_fab2(sch_1):m_j_dqs_dp(6)") )
				( member ( signalRef "@baseboard_fab2_lib.baseboard_fab2(sch_1):m_j_dqs_dp(7)") )
				( member ( signalRef "@baseboard_fab2_lib.baseboard_fab2(sch_1):m_j_dqs_dp(8)") )
				( member ( signalRef "@baseboard_fab2_lib.baseboard_fab2(sch_1):m_j_dqs_dp(9)") )
				( member ( signalRef "@baseboard_fab2_lib.baseboard_fab2(sch_1):m_j_dqs_dp(10)") )
				( member ( signalRef "@baseboard_fab2_lib.baseboard_fab2(sch_1):m_j_dqs_dp(11)") )
				( member ( signalRef "@baseboard_fab2_lib.baseboard_fab2(sch_1):m_j_dqs_dp(12)") )
				( member ( signalRef "@baseboard_fab2_lib.baseboard_fab2(sch_1):m_j_dqs_dp(13)") )
				( member ( signalRef "@baseboard_fab2_lib.baseboard_fab2(sch_1):m_j_dqs_dp(14)") )
				( member ( signalRef "@baseboard_fab2_lib.baseboard_fab2(sch_1):m_j_dqs_dp(15)") )
				( member ( signalRef "@baseboard_fab2_lib.baseboard_fab2(sch_1):m_j_dqs_dp(16)") )
				( member ( signalRef "@baseboard_fab2_lib.baseboard_fab2(sch_1):m_j_dqs_dp(17)") )
				( objectStatus "M_J_DQS_DP" )
			)
			( bus "@baseboard_fab2_lib.baseboard_fab2(sch_1):m_j_ecc"
				( memberType ( signal ) )
				( member ( signalRef "@baseboard_fab2_lib.baseboard_fab2(sch_1):m_j_ecc(0)") )
				( member ( signalRef "@baseboard_fab2_lib.baseboard_fab2(sch_1):m_j_ecc(1)") )
				( member ( signalRef "@baseboard_fab2_lib.baseboard_fab2(sch_1):m_j_ecc(2)") )
				( member ( signalRef "@baseboard_fab2_lib.baseboard_fab2(sch_1):m_j_ecc(3)") )
				( member ( signalRef "@baseboard_fab2_lib.baseboard_fab2(sch_1):m_j_ecc(4)") )
				( member ( signalRef "@baseboard_fab2_lib.baseboard_fab2(sch_1):m_j_ecc(5)") )
				( member ( signalRef "@baseboard_fab2_lib.baseboard_fab2(sch_1):m_j_ecc(6)") )
				( member ( signalRef "@baseboard_fab2_lib.baseboard_fab2(sch_1):m_j_ecc(7)") )
				( objectStatus "M_J_ECC" )
			)
			( bus "@baseboard_fab2_lib.baseboard_fab2(sch_1):m_j_ma"
				( memberType ( signal ) )
				( member ( signalRef "@baseboard_fab2_lib.baseboard_fab2(sch_1):m_j_ma(0)") )
				( member ( signalRef "@baseboard_fab2_lib.baseboard_fab2(sch_1):m_j_ma(1)") )
				( member ( signalRef "@baseboard_fab2_lib.baseboard_fab2(sch_1):m_j_ma(2)") )
				( member ( signalRef "@baseboard_fab2_lib.baseboard_fab2(sch_1):m_j_ma(3)") )
				( member ( signalRef "@baseboard_fab2_lib.baseboard_fab2(sch_1):m_j_ma(4)") )
				( member ( signalRef "@baseboard_fab2_lib.baseboard_fab2(sch_1):m_j_ma(5)") )
				( member ( signalRef "@baseboard_fab2_lib.baseboard_fab2(sch_1):m_j_ma(6)") )
				( member ( signalRef "@baseboard_fab2_lib.baseboard_fab2(sch_1):m_j_ma(7)") )
				( member ( signalRef "@baseboard_fab2_lib.baseboard_fab2(sch_1):m_j_ma(8)") )
				( member ( signalRef "@baseboard_fab2_lib.baseboard_fab2(sch_1):m_j_ma(9)") )
				( member ( signalRef "@baseboard_fab2_lib.baseboard_fab2(sch_1):m_j_ma(10)") )
				( member ( signalRef "@baseboard_fab2_lib.baseboard_fab2(sch_1):m_j_ma(11)") )
				( member ( signalRef "@baseboard_fab2_lib.baseboard_fab2(sch_1):m_j_ma(12)") )
				( member ( signalRef "@baseboard_fab2_lib.baseboard_fab2(sch_1):m_j_ma(13)") )
				( member ( signalRef "@baseboard_fab2_lib.baseboard_fab2(sch_1):m_j_ma(14)") )
				( member ( signalRef "@baseboard_fab2_lib.baseboard_fab2(sch_1):m_j_ma(15)") )
				( member ( signalRef "@baseboard_fab2_lib.baseboard_fab2(sch_1):m_j_ma(16)") )
				( member ( signalRef "@baseboard_fab2_lib.baseboard_fab2(sch_1):m_j_ma(17)") )
				( objectStatus "M_J_MA" )
			)
			( bus "@baseboard_fab2_lib.baseboard_fab2(sch_1):m_j_odt"
				( memberType ( signal ) )
				( member ( signalRef "@baseboard_fab2_lib.baseboard_fab2(sch_1):m_j_odt(0)") )
				( member ( signalRef "@baseboard_fab2_lib.baseboard_fab2(sch_1):m_j_odt(1)") )
				( member ( signalRef "@baseboard_fab2_lib.baseboard_fab2(sch_1):m_j_odt(2)") )
				( member ( signalRef "@baseboard_fab2_lib.baseboard_fab2(sch_1):m_j_odt(3)") )
				( objectStatus "M_J_ODT" )
			)
			( bus "@baseboard_fab2_lib.baseboard_fab2(sch_1):m_k_ba"
				( memberType ( signal ) )
				( member ( signalRef "@baseboard_fab2_lib.baseboard_fab2(sch_1):m_k_ba(0)") )
				( member ( signalRef "@baseboard_fab2_lib.baseboard_fab2(sch_1):m_k_ba(1)") )
				( objectStatus "M_K_BA" )
			)
			( bus "@baseboard_fab2_lib.baseboard_fab2(sch_1):m_k_bg"
				( memberType ( signal ) )
				( member ( signalRef "@baseboard_fab2_lib.baseboard_fab2(sch_1):m_k_bg(0)") )
				( member ( signalRef "@baseboard_fab2_lib.baseboard_fab2(sch_1):m_k_bg(1)") )
				( objectStatus "M_K_BG" )
			)
			( bus "@baseboard_fab2_lib.baseboard_fab2(sch_1):m_k_c"
				( memberType ( signal ) )
				( member ( signalRef "@baseboard_fab2_lib.baseboard_fab2(sch_1):m_k_c(2)") )
				( objectStatus "M_K_C" )
			)
			( bus "@baseboard_fab2_lib.baseboard_fab2(sch_1):m_k_cke"
				( memberType ( signal ) )
				( member ( signalRef "@baseboard_fab2_lib.baseboard_fab2(sch_1):m_k_cke(0)") )
				( member ( signalRef "@baseboard_fab2_lib.baseboard_fab2(sch_1):m_k_cke(1)") )
				( member ( signalRef "@baseboard_fab2_lib.baseboard_fab2(sch_1):m_k_cke(2)") )
				( member ( signalRef "@baseboard_fab2_lib.baseboard_fab2(sch_1):m_k_cke(3)") )
				( objectStatus "M_K_CKE" )
			)
			( bus "@baseboard_fab2_lib.baseboard_fab2(sch_1):m_k_clk_dn"
				( memberType ( signal ) )
				( member ( signalRef "@baseboard_fab2_lib.baseboard_fab2(sch_1):m_k_clk_dn(0)") )
				( member ( signalRef "@baseboard_fab2_lib.baseboard_fab2(sch_1):m_k_clk_dn(1)") )
				( member ( signalRef "@baseboard_fab2_lib.baseboard_fab2(sch_1):m_k_clk_dn(2)") )
				( member ( signalRef "@baseboard_fab2_lib.baseboard_fab2(sch_1):m_k_clk_dn(3)") )
				( objectStatus "M_K_CLK_DN" )
			)
			( bus "@baseboard_fab2_lib.baseboard_fab2(sch_1):m_k_clk_dp"
				( memberType ( signal ) )
				( member ( signalRef "@baseboard_fab2_lib.baseboard_fab2(sch_1):m_k_clk_dp(0)") )
				( member ( signalRef "@baseboard_fab2_lib.baseboard_fab2(sch_1):m_k_clk_dp(1)") )
				( member ( signalRef "@baseboard_fab2_lib.baseboard_fab2(sch_1):m_k_clk_dp(2)") )
				( member ( signalRef "@baseboard_fab2_lib.baseboard_fab2(sch_1):m_k_clk_dp(3)") )
				( objectStatus "M_K_CLK_DP" )
			)
			( bus "@baseboard_fab2_lib.baseboard_fab2(sch_1):m_k_cs_n"
				( memberType ( signal ) )
				( member ( signalRef "@baseboard_fab2_lib.baseboard_fab2(sch_1):m_k_cs_n(0)") )
				( member ( signalRef "@baseboard_fab2_lib.baseboard_fab2(sch_1):m_k_cs_n(1)") )
				( member ( signalRef "@baseboard_fab2_lib.baseboard_fab2(sch_1):m_k_cs_n(2)") )
				( member ( signalRef "@baseboard_fab2_lib.baseboard_fab2(sch_1):m_k_cs_n(3)") )
				( member ( signalRef "@baseboard_fab2_lib.baseboard_fab2(sch_1):m_k_cs_n(4)") )
				( member ( signalRef "@baseboard_fab2_lib.baseboard_fab2(sch_1):m_k_cs_n(5)") )
				( member ( signalRef "@baseboard_fab2_lib.baseboard_fab2(sch_1):m_k_cs_n(6)") )
				( member ( signalRef "@baseboard_fab2_lib.baseboard_fab2(sch_1):m_k_cs_n(7)") )
				( objectStatus "M_K_CS_N" )
			)
			( bus "@baseboard_fab2_lib.baseboard_fab2(sch_1):m_k_dq"
				( memberType ( signal ) )
				( member ( signalRef "@baseboard_fab2_lib.baseboard_fab2(sch_1):m_k_dq(0)") )
				( member ( signalRef "@baseboard_fab2_lib.baseboard_fab2(sch_1):m_k_dq(1)") )
				( member ( signalRef "@baseboard_fab2_lib.baseboard_fab2(sch_1):m_k_dq(2)") )
				( member ( signalRef "@baseboard_fab2_lib.baseboard_fab2(sch_1):m_k_dq(3)") )
				( member ( signalRef "@baseboard_fab2_lib.baseboard_fab2(sch_1):m_k_dq(4)") )
				( member ( signalRef "@baseboard_fab2_lib.baseboard_fab2(sch_1):m_k_dq(5)") )
				( member ( signalRef "@baseboard_fab2_lib.baseboard_fab2(sch_1):m_k_dq(6)") )
				( member ( signalRef "@baseboard_fab2_lib.baseboard_fab2(sch_1):m_k_dq(7)") )
				( member ( signalRef "@baseboard_fab2_lib.baseboard_fab2(sch_1):m_k_dq(8)") )
				( member ( signalRef "@baseboard_fab2_lib.baseboard_fab2(sch_1):m_k_dq(9)") )
				( member ( signalRef "@baseboard_fab2_lib.baseboard_fab2(sch_1):m_k_dq(10)") )
				( member ( signalRef "@baseboard_fab2_lib.baseboard_fab2(sch_1):m_k_dq(11)") )
				( member ( signalRef "@baseboard_fab2_lib.baseboard_fab2(sch_1):m_k_dq(12)") )
				( member ( signalRef "@baseboard_fab2_lib.baseboard_fab2(sch_1):m_k_dq(13)") )
				( member ( signalRef "@baseboard_fab2_lib.baseboard_fab2(sch_1):m_k_dq(14)") )
				( member ( signalRef "@baseboard_fab2_lib.baseboard_fab2(sch_1):m_k_dq(15)") )
				( member ( signalRef "@baseboard_fab2_lib.baseboard_fab2(sch_1):m_k_dq(16)") )
				( member ( signalRef "@baseboard_fab2_lib.baseboard_fab2(sch_1):m_k_dq(17)") )
				( member ( signalRef "@baseboard_fab2_lib.baseboard_fab2(sch_1):m_k_dq(18)") )
				( member ( signalRef "@baseboard_fab2_lib.baseboard_fab2(sch_1):m_k_dq(19)") )
				( member ( signalRef "@baseboard_fab2_lib.baseboard_fab2(sch_1):m_k_dq(20)") )
				( member ( signalRef "@baseboard_fab2_lib.baseboard_fab2(sch_1):m_k_dq(21)") )
				( member ( signalRef "@baseboard_fab2_lib.baseboard_fab2(sch_1):m_k_dq(22)") )
				( member ( signalRef "@baseboard_fab2_lib.baseboard_fab2(sch_1):m_k_dq(23)") )
				( member ( signalRef "@baseboard_fab2_lib.baseboard_fab2(sch_1):m_k_dq(24)") )
				( member ( signalRef "@baseboard_fab2_lib.baseboard_fab2(sch_1):m_k_dq(25)") )
				( member ( signalRef "@baseboard_fab2_lib.baseboard_fab2(sch_1):m_k_dq(26)") )
				( member ( signalRef "@baseboard_fab2_lib.baseboard_fab2(sch_1):m_k_dq(27)") )
				( member ( signalRef "@baseboard_fab2_lib.baseboard_fab2(sch_1):m_k_dq(28)") )
				( member ( signalRef "@baseboard_fab2_lib.baseboard_fab2(sch_1):m_k_dq(29)") )
				( member ( signalRef "@baseboard_fab2_lib.baseboard_fab2(sch_1):m_k_dq(30)") )
				( member ( signalRef "@baseboard_fab2_lib.baseboard_fab2(sch_1):m_k_dq(31)") )
				( member ( signalRef "@baseboard_fab2_lib.baseboard_fab2(sch_1):m_k_dq(32)") )
				( member ( signalRef "@baseboard_fab2_lib.baseboard_fab2(sch_1):m_k_dq(33)") )
				( member ( signalRef "@baseboard_fab2_lib.baseboard_fab2(sch_1):m_k_dq(34)") )
				( member ( signalRef "@baseboard_fab2_lib.baseboard_fab2(sch_1):m_k_dq(35)") )
				( member ( signalRef "@baseboard_fab2_lib.baseboard_fab2(sch_1):m_k_dq(36)") )
				( member ( signalRef "@baseboard_fab2_lib.baseboard_fab2(sch_1):m_k_dq(37)") )
				( member ( signalRef "@baseboard_fab2_lib.baseboard_fab2(sch_1):m_k_dq(38)") )
				( member ( signalRef "@baseboard_fab2_lib.baseboard_fab2(sch_1):m_k_dq(39)") )
				( member ( signalRef "@baseboard_fab2_lib.baseboard_fab2(sch_1):m_k_dq(40)") )
				( member ( signalRef "@baseboard_fab2_lib.baseboard_fab2(sch_1):m_k_dq(41)") )
				( member ( signalRef "@baseboard_fab2_lib.baseboard_fab2(sch_1):m_k_dq(42)") )
				( member ( signalRef "@baseboard_fab2_lib.baseboard_fab2(sch_1):m_k_dq(43)") )
				( member ( signalRef "@baseboard_fab2_lib.baseboard_fab2(sch_1):m_k_dq(44)") )
				( member ( signalRef "@baseboard_fab2_lib.baseboard_fab2(sch_1):m_k_dq(45)") )
				( member ( signalRef "@baseboard_fab2_lib.baseboard_fab2(sch_1):m_k_dq(46)") )
				( member ( signalRef "@baseboard_fab2_lib.baseboard_fab2(sch_1):m_k_dq(47)") )
				( member ( signalRef "@baseboard_fab2_lib.baseboard_fab2(sch_1):m_k_dq(48)") )
				( member ( signalRef "@baseboard_fab2_lib.baseboard_fab2(sch_1):m_k_dq(49)") )
				( member ( signalRef "@baseboard_fab2_lib.baseboard_fab2(sch_1):m_k_dq(50)") )
				( member ( signalRef "@baseboard_fab2_lib.baseboard_fab2(sch_1):m_k_dq(51)") )
				( member ( signalRef "@baseboard_fab2_lib.baseboard_fab2(sch_1):m_k_dq(52)") )
				( member ( signalRef "@baseboard_fab2_lib.baseboard_fab2(sch_1):m_k_dq(53)") )
				( member ( signalRef "@baseboard_fab2_lib.baseboard_fab2(sch_1):m_k_dq(54)") )
				( member ( signalRef "@baseboard_fab2_lib.baseboard_fab2(sch_1):m_k_dq(55)") )
				( member ( signalRef "@baseboard_fab2_lib.baseboard_fab2(sch_1):m_k_dq(56)") )
				( member ( signalRef "@baseboard_fab2_lib.baseboard_fab2(sch_1):m_k_dq(57)") )
				( member ( signalRef "@baseboard_fab2_lib.baseboard_fab2(sch_1):m_k_dq(58)") )
				( member ( signalRef "@baseboard_fab2_lib.baseboard_fab2(sch_1):m_k_dq(59)") )
				( member ( signalRef "@baseboard_fab2_lib.baseboard_fab2(sch_1):m_k_dq(60)") )
				( member ( signalRef "@baseboard_fab2_lib.baseboard_fab2(sch_1):m_k_dq(61)") )
				( member ( signalRef "@baseboard_fab2_lib.baseboard_fab2(sch_1):m_k_dq(62)") )
				( member ( signalRef "@baseboard_fab2_lib.baseboard_fab2(sch_1):m_k_dq(63)") )
				( objectStatus "M_K_DQ" )
			)
			( bus "@baseboard_fab2_lib.baseboard_fab2(sch_1):m_k_dqs_dn"
				( memberType ( signal ) )
				( member ( signalRef "@baseboard_fab2_lib.baseboard_fab2(sch_1):m_k_dqs_dn(0)") )
				( member ( signalRef "@baseboard_fab2_lib.baseboard_fab2(sch_1):m_k_dqs_dn(1)") )
				( member ( signalRef "@baseboard_fab2_lib.baseboard_fab2(sch_1):m_k_dqs_dn(2)") )
				( member ( signalRef "@baseboard_fab2_lib.baseboard_fab2(sch_1):m_k_dqs_dn(3)") )
				( member ( signalRef "@baseboard_fab2_lib.baseboard_fab2(sch_1):m_k_dqs_dn(4)") )
				( member ( signalRef "@baseboard_fab2_lib.baseboard_fab2(sch_1):m_k_dqs_dn(5)") )
				( member ( signalRef "@baseboard_fab2_lib.baseboard_fab2(sch_1):m_k_dqs_dn(6)") )
				( member ( signalRef "@baseboard_fab2_lib.baseboard_fab2(sch_1):m_k_dqs_dn(7)") )
				( member ( signalRef "@baseboard_fab2_lib.baseboard_fab2(sch_1):m_k_dqs_dn(8)") )
				( member ( signalRef "@baseboard_fab2_lib.baseboard_fab2(sch_1):m_k_dqs_dn(9)") )
				( member ( signalRef "@baseboard_fab2_lib.baseboard_fab2(sch_1):m_k_dqs_dn(10)") )
				( member ( signalRef "@baseboard_fab2_lib.baseboard_fab2(sch_1):m_k_dqs_dn(11)") )
				( member ( signalRef "@baseboard_fab2_lib.baseboard_fab2(sch_1):m_k_dqs_dn(12)") )
				( member ( signalRef "@baseboard_fab2_lib.baseboard_fab2(sch_1):m_k_dqs_dn(13)") )
				( member ( signalRef "@baseboard_fab2_lib.baseboard_fab2(sch_1):m_k_dqs_dn(14)") )
				( member ( signalRef "@baseboard_fab2_lib.baseboard_fab2(sch_1):m_k_dqs_dn(15)") )
				( member ( signalRef "@baseboard_fab2_lib.baseboard_fab2(sch_1):m_k_dqs_dn(16)") )
				( member ( signalRef "@baseboard_fab2_lib.baseboard_fab2(sch_1):m_k_dqs_dn(17)") )
				( objectStatus "M_K_DQS_DN" )
			)
			( bus "@baseboard_fab2_lib.baseboard_fab2(sch_1):m_k_dqs_dp"
				( memberType ( signal ) )
				( member ( signalRef "@baseboard_fab2_lib.baseboard_fab2(sch_1):m_k_dqs_dp(0)") )
				( member ( signalRef "@baseboard_fab2_lib.baseboard_fab2(sch_1):m_k_dqs_dp(1)") )
				( member ( signalRef "@baseboard_fab2_lib.baseboard_fab2(sch_1):m_k_dqs_dp(2)") )
				( member ( signalRef "@baseboard_fab2_lib.baseboard_fab2(sch_1):m_k_dqs_dp(3)") )
				( member ( signalRef "@baseboard_fab2_lib.baseboard_fab2(sch_1):m_k_dqs_dp(4)") )
				( member ( signalRef "@baseboard_fab2_lib.baseboard_fab2(sch_1):m_k_dqs_dp(5)") )
				( member ( signalRef "@baseboard_fab2_lib.baseboard_fab2(sch_1):m_k_dqs_dp(6)") )
				( member ( signalRef "@baseboard_fab2_lib.baseboard_fab2(sch_1):m_k_dqs_dp(7)") )
				( member ( signalRef "@baseboard_fab2_lib.baseboard_fab2(sch_1):m_k_dqs_dp(8)") )
				( member ( signalRef "@baseboard_fab2_lib.baseboard_fab2(sch_1):m_k_dqs_dp(9)") )
				( member ( signalRef "@baseboard_fab2_lib.baseboard_fab2(sch_1):m_k_dqs_dp(10)") )
				( member ( signalRef "@baseboard_fab2_lib.baseboard_fab2(sch_1):m_k_dqs_dp(11)") )
				( member ( signalRef "@baseboard_fab2_lib.baseboard_fab2(sch_1):m_k_dqs_dp(12)") )
				( member ( signalRef "@baseboard_fab2_lib.baseboard_fab2(sch_1):m_k_dqs_dp(13)") )
				( member ( signalRef "@baseboard_fab2_lib.baseboard_fab2(sch_1):m_k_dqs_dp(14)") )
				( member ( signalRef "@baseboard_fab2_lib.baseboard_fab2(sch_1):m_k_dqs_dp(15)") )
				( member ( signalRef "@baseboard_fab2_lib.baseboard_fab2(sch_1):m_k_dqs_dp(16)") )
				( member ( signalRef "@baseboard_fab2_lib.baseboard_fab2(sch_1):m_k_dqs_dp(17)") )
				( objectStatus "M_K_DQS_DP" )
			)
			( bus "@baseboard_fab2_lib.baseboard_fab2(sch_1):m_k_ecc"
				( memberType ( signal ) )
				( member ( signalRef "@baseboard_fab2_lib.baseboard_fab2(sch_1):m_k_ecc(0)") )
				( member ( signalRef "@baseboard_fab2_lib.baseboard_fab2(sch_1):m_k_ecc(1)") )
				( member ( signalRef "@baseboard_fab2_lib.baseboard_fab2(sch_1):m_k_ecc(2)") )
				( member ( signalRef "@baseboard_fab2_lib.baseboard_fab2(sch_1):m_k_ecc(3)") )
				( member ( signalRef "@baseboard_fab2_lib.baseboard_fab2(sch_1):m_k_ecc(4)") )
				( member ( signalRef "@baseboard_fab2_lib.baseboard_fab2(sch_1):m_k_ecc(5)") )
				( member ( signalRef "@baseboard_fab2_lib.baseboard_fab2(sch_1):m_k_ecc(6)") )
				( member ( signalRef "@baseboard_fab2_lib.baseboard_fab2(sch_1):m_k_ecc(7)") )
				( objectStatus "M_K_ECC" )
			)
			( bus "@baseboard_fab2_lib.baseboard_fab2(sch_1):m_k_ma"
				( memberType ( signal ) )
				( member ( signalRef "@baseboard_fab2_lib.baseboard_fab2(sch_1):m_k_ma(0)") )
				( member ( signalRef "@baseboard_fab2_lib.baseboard_fab2(sch_1):m_k_ma(1)") )
				( member ( signalRef "@baseboard_fab2_lib.baseboard_fab2(sch_1):m_k_ma(2)") )
				( member ( signalRef "@baseboard_fab2_lib.baseboard_fab2(sch_1):m_k_ma(3)") )
				( member ( signalRef "@baseboard_fab2_lib.baseboard_fab2(sch_1):m_k_ma(4)") )
				( member ( signalRef "@baseboard_fab2_lib.baseboard_fab2(sch_1):m_k_ma(5)") )
				( member ( signalRef "@baseboard_fab2_lib.baseboard_fab2(sch_1):m_k_ma(6)") )
				( member ( signalRef "@baseboard_fab2_lib.baseboard_fab2(sch_1):m_k_ma(7)") )
				( member ( signalRef "@baseboard_fab2_lib.baseboard_fab2(sch_1):m_k_ma(8)") )
				( member ( signalRef "@baseboard_fab2_lib.baseboard_fab2(sch_1):m_k_ma(9)") )
				( member ( signalRef "@baseboard_fab2_lib.baseboard_fab2(sch_1):m_k_ma(10)") )
				( member ( signalRef "@baseboard_fab2_lib.baseboard_fab2(sch_1):m_k_ma(11)") )
				( member ( signalRef "@baseboard_fab2_lib.baseboard_fab2(sch_1):m_k_ma(12)") )
				( member ( signalRef "@baseboard_fab2_lib.baseboard_fab2(sch_1):m_k_ma(13)") )
				( member ( signalRef "@baseboard_fab2_lib.baseboard_fab2(sch_1):m_k_ma(14)") )
				( member ( signalRef "@baseboard_fab2_lib.baseboard_fab2(sch_1):m_k_ma(15)") )
				( member ( signalRef "@baseboard_fab2_lib.baseboard_fab2(sch_1):m_k_ma(16)") )
				( member ( signalRef "@baseboard_fab2_lib.baseboard_fab2(sch_1):m_k_ma(17)") )
				( objectStatus "M_K_MA" )
			)
			( bus "@baseboard_fab2_lib.baseboard_fab2(sch_1):m_k_odt"
				( memberType ( signal ) )
				( member ( signalRef "@baseboard_fab2_lib.baseboard_fab2(sch_1):m_k_odt(0)") )
				( member ( signalRef "@baseboard_fab2_lib.baseboard_fab2(sch_1):m_k_odt(1)") )
				( member ( signalRef "@baseboard_fab2_lib.baseboard_fab2(sch_1):m_k_odt(2)") )
				( member ( signalRef "@baseboard_fab2_lib.baseboard_fab2(sch_1):m_k_odt(3)") )
				( objectStatus "M_K_ODT" )
			)
			( bus "@baseboard_fab2_lib.baseboard_fab2(sch_1):m_l_ba"
				( memberType ( signal ) )
				( member ( signalRef "@baseboard_fab2_lib.baseboard_fab2(sch_1):m_l_ba(0)") )
				( member ( signalRef "@baseboard_fab2_lib.baseboard_fab2(sch_1):m_l_ba(1)") )
				( objectStatus "M_L_BA" )
			)
			( bus "@baseboard_fab2_lib.baseboard_fab2(sch_1):m_l_bg"
				( memberType ( signal ) )
				( member ( signalRef "@baseboard_fab2_lib.baseboard_fab2(sch_1):m_l_bg(0)") )
				( member ( signalRef "@baseboard_fab2_lib.baseboard_fab2(sch_1):m_l_bg(1)") )
				( objectStatus "M_L_BG" )
			)
			( bus "@baseboard_fab2_lib.baseboard_fab2(sch_1):m_l_c"
				( memberType ( signal ) )
				( member ( signalRef "@baseboard_fab2_lib.baseboard_fab2(sch_1):m_l_c(2)") )
				( objectStatus "M_L_C" )
			)
			( bus "@baseboard_fab2_lib.baseboard_fab2(sch_1):m_l_cke"
				( memberType ( signal ) )
				( member ( signalRef "@baseboard_fab2_lib.baseboard_fab2(sch_1):m_l_cke(0)") )
				( member ( signalRef "@baseboard_fab2_lib.baseboard_fab2(sch_1):m_l_cke(1)") )
				( member ( signalRef "@baseboard_fab2_lib.baseboard_fab2(sch_1):m_l_cke(2)") )
				( member ( signalRef "@baseboard_fab2_lib.baseboard_fab2(sch_1):m_l_cke(3)") )
				( objectStatus "M_L_CKE" )
			)
			( bus "@baseboard_fab2_lib.baseboard_fab2(sch_1):m_l_clk_dn"
				( memberType ( signal ) )
				( member ( signalRef "@baseboard_fab2_lib.baseboard_fab2(sch_1):m_l_clk_dn(0)") )
				( member ( signalRef "@baseboard_fab2_lib.baseboard_fab2(sch_1):m_l_clk_dn(1)") )
				( member ( signalRef "@baseboard_fab2_lib.baseboard_fab2(sch_1):m_l_clk_dn(2)") )
				( member ( signalRef "@baseboard_fab2_lib.baseboard_fab2(sch_1):m_l_clk_dn(3)") )
				( objectStatus "M_L_CLK_DN" )
			)
			( bus "@baseboard_fab2_lib.baseboard_fab2(sch_1):m_l_clk_dp"
				( memberType ( signal ) )
				( member ( signalRef "@baseboard_fab2_lib.baseboard_fab2(sch_1):m_l_clk_dp(0)") )
				( member ( signalRef "@baseboard_fab2_lib.baseboard_fab2(sch_1):m_l_clk_dp(1)") )
				( member ( signalRef "@baseboard_fab2_lib.baseboard_fab2(sch_1):m_l_clk_dp(2)") )
				( member ( signalRef "@baseboard_fab2_lib.baseboard_fab2(sch_1):m_l_clk_dp(3)") )
				( objectStatus "M_L_CLK_DP" )
			)
			( bus "@baseboard_fab2_lib.baseboard_fab2(sch_1):m_l_cs_n"
				( memberType ( signal ) )
				( member ( signalRef "@baseboard_fab2_lib.baseboard_fab2(sch_1):m_l_cs_n(0)") )
				( member ( signalRef "@baseboard_fab2_lib.baseboard_fab2(sch_1):m_l_cs_n(1)") )
				( member ( signalRef "@baseboard_fab2_lib.baseboard_fab2(sch_1):m_l_cs_n(2)") )
				( member ( signalRef "@baseboard_fab2_lib.baseboard_fab2(sch_1):m_l_cs_n(3)") )
				( member ( signalRef "@baseboard_fab2_lib.baseboard_fab2(sch_1):m_l_cs_n(4)") )
				( member ( signalRef "@baseboard_fab2_lib.baseboard_fab2(sch_1):m_l_cs_n(5)") )
				( member ( signalRef "@baseboard_fab2_lib.baseboard_fab2(sch_1):m_l_cs_n(6)") )
				( member ( signalRef "@baseboard_fab2_lib.baseboard_fab2(sch_1):m_l_cs_n(7)") )
				( objectStatus "M_L_CS_N" )
			)
			( bus "@baseboard_fab2_lib.baseboard_fab2(sch_1):m_l_dq"
				( memberType ( signal ) )
				( member ( signalRef "@baseboard_fab2_lib.baseboard_fab2(sch_1):m_l_dq(0)") )
				( member ( signalRef "@baseboard_fab2_lib.baseboard_fab2(sch_1):m_l_dq(1)") )
				( member ( signalRef "@baseboard_fab2_lib.baseboard_fab2(sch_1):m_l_dq(2)") )
				( member ( signalRef "@baseboard_fab2_lib.baseboard_fab2(sch_1):m_l_dq(3)") )
				( member ( signalRef "@baseboard_fab2_lib.baseboard_fab2(sch_1):m_l_dq(4)") )
				( member ( signalRef "@baseboard_fab2_lib.baseboard_fab2(sch_1):m_l_dq(5)") )
				( member ( signalRef "@baseboard_fab2_lib.baseboard_fab2(sch_1):m_l_dq(6)") )
				( member ( signalRef "@baseboard_fab2_lib.baseboard_fab2(sch_1):m_l_dq(7)") )
				( member ( signalRef "@baseboard_fab2_lib.baseboard_fab2(sch_1):m_l_dq(8)") )
				( member ( signalRef "@baseboard_fab2_lib.baseboard_fab2(sch_1):m_l_dq(9)") )
				( member ( signalRef "@baseboard_fab2_lib.baseboard_fab2(sch_1):m_l_dq(10)") )
				( member ( signalRef "@baseboard_fab2_lib.baseboard_fab2(sch_1):m_l_dq(11)") )
				( member ( signalRef "@baseboard_fab2_lib.baseboard_fab2(sch_1):m_l_dq(12)") )
				( member ( signalRef "@baseboard_fab2_lib.baseboard_fab2(sch_1):m_l_dq(13)") )
				( member ( signalRef "@baseboard_fab2_lib.baseboard_fab2(sch_1):m_l_dq(14)") )
				( member ( signalRef "@baseboard_fab2_lib.baseboard_fab2(sch_1):m_l_dq(15)") )
				( member ( signalRef "@baseboard_fab2_lib.baseboard_fab2(sch_1):m_l_dq(16)") )
				( member ( signalRef "@baseboard_fab2_lib.baseboard_fab2(sch_1):m_l_dq(17)") )
				( member ( signalRef "@baseboard_fab2_lib.baseboard_fab2(sch_1):m_l_dq(18)") )
				( member ( signalRef "@baseboard_fab2_lib.baseboard_fab2(sch_1):m_l_dq(19)") )
				( member ( signalRef "@baseboard_fab2_lib.baseboard_fab2(sch_1):m_l_dq(20)") )
				( member ( signalRef "@baseboard_fab2_lib.baseboard_fab2(sch_1):m_l_dq(21)") )
				( member ( signalRef "@baseboard_fab2_lib.baseboard_fab2(sch_1):m_l_dq(22)") )
				( member ( signalRef "@baseboard_fab2_lib.baseboard_fab2(sch_1):m_l_dq(23)") )
				( member ( signalRef "@baseboard_fab2_lib.baseboard_fab2(sch_1):m_l_dq(24)") )
				( member ( signalRef "@baseboard_fab2_lib.baseboard_fab2(sch_1):m_l_dq(25)") )
				( member ( signalRef "@baseboard_fab2_lib.baseboard_fab2(sch_1):m_l_dq(26)") )
				( member ( signalRef "@baseboard_fab2_lib.baseboard_fab2(sch_1):m_l_dq(27)") )
				( member ( signalRef "@baseboard_fab2_lib.baseboard_fab2(sch_1):m_l_dq(28)") )
				( member ( signalRef "@baseboard_fab2_lib.baseboard_fab2(sch_1):m_l_dq(29)") )
				( member ( signalRef "@baseboard_fab2_lib.baseboard_fab2(sch_1):m_l_dq(30)") )
				( member ( signalRef "@baseboard_fab2_lib.baseboard_fab2(sch_1):m_l_dq(31)") )
				( member ( signalRef "@baseboard_fab2_lib.baseboard_fab2(sch_1):m_l_dq(32)") )
				( member ( signalRef "@baseboard_fab2_lib.baseboard_fab2(sch_1):m_l_dq(33)") )
				( member ( signalRef "@baseboard_fab2_lib.baseboard_fab2(sch_1):m_l_dq(34)") )
				( member ( signalRef "@baseboard_fab2_lib.baseboard_fab2(sch_1):m_l_dq(35)") )
				( member ( signalRef "@baseboard_fab2_lib.baseboard_fab2(sch_1):m_l_dq(36)") )
				( member ( signalRef "@baseboard_fab2_lib.baseboard_fab2(sch_1):m_l_dq(37)") )
				( member ( signalRef "@baseboard_fab2_lib.baseboard_fab2(sch_1):m_l_dq(38)") )
				( member ( signalRef "@baseboard_fab2_lib.baseboard_fab2(sch_1):m_l_dq(39)") )
				( member ( signalRef "@baseboard_fab2_lib.baseboard_fab2(sch_1):m_l_dq(40)") )
				( member ( signalRef "@baseboard_fab2_lib.baseboard_fab2(sch_1):m_l_dq(41)") )
				( member ( signalRef "@baseboard_fab2_lib.baseboard_fab2(sch_1):m_l_dq(42)") )
				( member ( signalRef "@baseboard_fab2_lib.baseboard_fab2(sch_1):m_l_dq(43)") )
				( member ( signalRef "@baseboard_fab2_lib.baseboard_fab2(sch_1):m_l_dq(44)") )
				( member ( signalRef "@baseboard_fab2_lib.baseboard_fab2(sch_1):m_l_dq(45)") )
				( member ( signalRef "@baseboard_fab2_lib.baseboard_fab2(sch_1):m_l_dq(46)") )
				( member ( signalRef "@baseboard_fab2_lib.baseboard_fab2(sch_1):m_l_dq(47)") )
				( member ( signalRef "@baseboard_fab2_lib.baseboard_fab2(sch_1):m_l_dq(48)") )
				( member ( signalRef "@baseboard_fab2_lib.baseboard_fab2(sch_1):m_l_dq(49)") )
				( member ( signalRef "@baseboard_fab2_lib.baseboard_fab2(sch_1):m_l_dq(50)") )
				( member ( signalRef "@baseboard_fab2_lib.baseboard_fab2(sch_1):m_l_dq(51)") )
				( member ( signalRef "@baseboard_fab2_lib.baseboard_fab2(sch_1):m_l_dq(52)") )
				( member ( signalRef "@baseboard_fab2_lib.baseboard_fab2(sch_1):m_l_dq(53)") )
				( member ( signalRef "@baseboard_fab2_lib.baseboard_fab2(sch_1):m_l_dq(54)") )
				( member ( signalRef "@baseboard_fab2_lib.baseboard_fab2(sch_1):m_l_dq(55)") )
				( member ( signalRef "@baseboard_fab2_lib.baseboard_fab2(sch_1):m_l_dq(56)") )
				( member ( signalRef "@baseboard_fab2_lib.baseboard_fab2(sch_1):m_l_dq(57)") )
				( member ( signalRef "@baseboard_fab2_lib.baseboard_fab2(sch_1):m_l_dq(58)") )
				( member ( signalRef "@baseboard_fab2_lib.baseboard_fab2(sch_1):m_l_dq(59)") )
				( member ( signalRef "@baseboard_fab2_lib.baseboard_fab2(sch_1):m_l_dq(60)") )
				( member ( signalRef "@baseboard_fab2_lib.baseboard_fab2(sch_1):m_l_dq(61)") )
				( member ( signalRef "@baseboard_fab2_lib.baseboard_fab2(sch_1):m_l_dq(62)") )
				( member ( signalRef "@baseboard_fab2_lib.baseboard_fab2(sch_1):m_l_dq(63)") )
				( objectStatus "M_L_DQ" )
			)
			( bus "@baseboard_fab2_lib.baseboard_fab2(sch_1):m_l_dqs_dn"
				( memberType ( signal ) )
				( member ( signalRef "@baseboard_fab2_lib.baseboard_fab2(sch_1):m_l_dqs_dn(0)") )
				( member ( signalRef "@baseboard_fab2_lib.baseboard_fab2(sch_1):m_l_dqs_dn(1)") )
				( member ( signalRef "@baseboard_fab2_lib.baseboard_fab2(sch_1):m_l_dqs_dn(2)") )
				( member ( signalRef "@baseboard_fab2_lib.baseboard_fab2(sch_1):m_l_dqs_dn(3)") )
				( member ( signalRef "@baseboard_fab2_lib.baseboard_fab2(sch_1):m_l_dqs_dn(4)") )
				( member ( signalRef "@baseboard_fab2_lib.baseboard_fab2(sch_1):m_l_dqs_dn(5)") )
				( member ( signalRef "@baseboard_fab2_lib.baseboard_fab2(sch_1):m_l_dqs_dn(6)") )
				( member ( signalRef "@baseboard_fab2_lib.baseboard_fab2(sch_1):m_l_dqs_dn(7)") )
				( member ( signalRef "@baseboard_fab2_lib.baseboard_fab2(sch_1):m_l_dqs_dn(8)") )
				( member ( signalRef "@baseboard_fab2_lib.baseboard_fab2(sch_1):m_l_dqs_dn(9)") )
				( member ( signalRef "@baseboard_fab2_lib.baseboard_fab2(sch_1):m_l_dqs_dn(10)") )
				( member ( signalRef "@baseboard_fab2_lib.baseboard_fab2(sch_1):m_l_dqs_dn(11)") )
				( member ( signalRef "@baseboard_fab2_lib.baseboard_fab2(sch_1):m_l_dqs_dn(12)") )
				( member ( signalRef "@baseboard_fab2_lib.baseboard_fab2(sch_1):m_l_dqs_dn(13)") )
				( member ( signalRef "@baseboard_fab2_lib.baseboard_fab2(sch_1):m_l_dqs_dn(14)") )
				( member ( signalRef "@baseboard_fab2_lib.baseboard_fab2(sch_1):m_l_dqs_dn(15)") )
				( member ( signalRef "@baseboard_fab2_lib.baseboard_fab2(sch_1):m_l_dqs_dn(16)") )
				( member ( signalRef "@baseboard_fab2_lib.baseboard_fab2(sch_1):m_l_dqs_dn(17)") )
				( objectStatus "M_L_DQS_DN" )
			)
			( bus "@baseboard_fab2_lib.baseboard_fab2(sch_1):m_l_dqs_dp"
				( memberType ( signal ) )
				( member ( signalRef "@baseboard_fab2_lib.baseboard_fab2(sch_1):m_l_dqs_dp(0)") )
				( member ( signalRef "@baseboard_fab2_lib.baseboard_fab2(sch_1):m_l_dqs_dp(1)") )
				( member ( signalRef "@baseboard_fab2_lib.baseboard_fab2(sch_1):m_l_dqs_dp(2)") )
				( member ( signalRef "@baseboard_fab2_lib.baseboard_fab2(sch_1):m_l_dqs_dp(3)") )
				( member ( signalRef "@baseboard_fab2_lib.baseboard_fab2(sch_1):m_l_dqs_dp(4)") )
				( member ( signalRef "@baseboard_fab2_lib.baseboard_fab2(sch_1):m_l_dqs_dp(5)") )
				( member ( signalRef "@baseboard_fab2_lib.baseboard_fab2(sch_1):m_l_dqs_dp(6)") )
				( member ( signalRef "@baseboard_fab2_lib.baseboard_fab2(sch_1):m_l_dqs_dp(7)") )
				( member ( signalRef "@baseboard_fab2_lib.baseboard_fab2(sch_1):m_l_dqs_dp(8)") )
				( member ( signalRef "@baseboard_fab2_lib.baseboard_fab2(sch_1):m_l_dqs_dp(9)") )
				( member ( signalRef "@baseboard_fab2_lib.baseboard_fab2(sch_1):m_l_dqs_dp(10)") )
				( member ( signalRef "@baseboard_fab2_lib.baseboard_fab2(sch_1):m_l_dqs_dp(11)") )
				( member ( signalRef "@baseboard_fab2_lib.baseboard_fab2(sch_1):m_l_dqs_dp(12)") )
				( member ( signalRef "@baseboard_fab2_lib.baseboard_fab2(sch_1):m_l_dqs_dp(13)") )
				( member ( signalRef "@baseboard_fab2_lib.baseboard_fab2(sch_1):m_l_dqs_dp(14)") )
				( member ( signalRef "@baseboard_fab2_lib.baseboard_fab2(sch_1):m_l_dqs_dp(15)") )
				( member ( signalRef "@baseboard_fab2_lib.baseboard_fab2(sch_1):m_l_dqs_dp(16)") )
				( member ( signalRef "@baseboard_fab2_lib.baseboard_fab2(sch_1):m_l_dqs_dp(17)") )
				( objectStatus "M_L_DQS_DP" )
			)
			( bus "@baseboard_fab2_lib.baseboard_fab2(sch_1):m_l_ecc"
				( memberType ( signal ) )
				( member ( signalRef "@baseboard_fab2_lib.baseboard_fab2(sch_1):m_l_ecc(0)") )
				( member ( signalRef "@baseboard_fab2_lib.baseboard_fab2(sch_1):m_l_ecc(1)") )
				( member ( signalRef "@baseboard_fab2_lib.baseboard_fab2(sch_1):m_l_ecc(2)") )
				( member ( signalRef "@baseboard_fab2_lib.baseboard_fab2(sch_1):m_l_ecc(3)") )
				( member ( signalRef "@baseboard_fab2_lib.baseboard_fab2(sch_1):m_l_ecc(4)") )
				( member ( signalRef "@baseboard_fab2_lib.baseboard_fab2(sch_1):m_l_ecc(5)") )
				( member ( signalRef "@baseboard_fab2_lib.baseboard_fab2(sch_1):m_l_ecc(6)") )
				( member ( signalRef "@baseboard_fab2_lib.baseboard_fab2(sch_1):m_l_ecc(7)") )
				( objectStatus "M_L_ECC" )
			)
			( bus "@baseboard_fab2_lib.baseboard_fab2(sch_1):m_l_ma"
				( memberType ( signal ) )
				( member ( signalRef "@baseboard_fab2_lib.baseboard_fab2(sch_1):m_l_ma(0)") )
				( member ( signalRef "@baseboard_fab2_lib.baseboard_fab2(sch_1):m_l_ma(1)") )
				( member ( signalRef "@baseboard_fab2_lib.baseboard_fab2(sch_1):m_l_ma(2)") )
				( member ( signalRef "@baseboard_fab2_lib.baseboard_fab2(sch_1):m_l_ma(3)") )
				( member ( signalRef "@baseboard_fab2_lib.baseboard_fab2(sch_1):m_l_ma(4)") )
				( member ( signalRef "@baseboard_fab2_lib.baseboard_fab2(sch_1):m_l_ma(5)") )
				( member ( signalRef "@baseboard_fab2_lib.baseboard_fab2(sch_1):m_l_ma(6)") )
				( member ( signalRef "@baseboard_fab2_lib.baseboard_fab2(sch_1):m_l_ma(7)") )
				( member ( signalRef "@baseboard_fab2_lib.baseboard_fab2(sch_1):m_l_ma(8)") )
				( member ( signalRef "@baseboard_fab2_lib.baseboard_fab2(sch_1):m_l_ma(9)") )
				( member ( signalRef "@baseboard_fab2_lib.baseboard_fab2(sch_1):m_l_ma(10)") )
				( member ( signalRef "@baseboard_fab2_lib.baseboard_fab2(sch_1):m_l_ma(11)") )
				( member ( signalRef "@baseboard_fab2_lib.baseboard_fab2(sch_1):m_l_ma(12)") )
				( member ( signalRef "@baseboard_fab2_lib.baseboard_fab2(sch_1):m_l_ma(13)") )
				( member ( signalRef "@baseboard_fab2_lib.baseboard_fab2(sch_1):m_l_ma(14)") )
				( member ( signalRef "@baseboard_fab2_lib.baseboard_fab2(sch_1):m_l_ma(15)") )
				( member ( signalRef "@baseboard_fab2_lib.baseboard_fab2(sch_1):m_l_ma(16)") )
				( member ( signalRef "@baseboard_fab2_lib.baseboard_fab2(sch_1):m_l_ma(17)") )
				( objectStatus "M_L_MA" )
			)
			( bus "@baseboard_fab2_lib.baseboard_fab2(sch_1):m_l_odt"
				( memberType ( signal ) )
				( member ( signalRef "@baseboard_fab2_lib.baseboard_fab2(sch_1):m_l_odt(0)") )
				( member ( signalRef "@baseboard_fab2_lib.baseboard_fab2(sch_1):m_l_odt(1)") )
				( member ( signalRef "@baseboard_fab2_lib.baseboard_fab2(sch_1):m_l_odt(2)") )
				( member ( signalRef "@baseboard_fab2_lib.baseboard_fab2(sch_1):m_l_odt(3)") )
				( objectStatus "M_L_ODT" )
			)
			( bus "@baseboard_fab2_lib.baseboard_fab2(sch_1):m_m_ba"
				( memberType ( signal ) )
				( member ( signalRef "@baseboard_fab2_lib.baseboard_fab2(sch_1):m_m_ba(0)") )
				( member ( signalRef "@baseboard_fab2_lib.baseboard_fab2(sch_1):m_m_ba(1)") )
				( objectStatus "M_M_BA" )
			)
			( bus "@baseboard_fab2_lib.baseboard_fab2(sch_1):m_m_bg"
				( memberType ( signal ) )
				( member ( signalRef "@baseboard_fab2_lib.baseboard_fab2(sch_1):m_m_bg(0)") )
				( member ( signalRef "@baseboard_fab2_lib.baseboard_fab2(sch_1):m_m_bg(1)") )
				( objectStatus "M_M_BG" )
			)
			( bus "@baseboard_fab2_lib.baseboard_fab2(sch_1):m_m_c"
				( memberType ( signal ) )
				( member ( signalRef "@baseboard_fab2_lib.baseboard_fab2(sch_1):m_m_c(2)") )
				( objectStatus "M_M_C" )
			)
			( bus "@baseboard_fab2_lib.baseboard_fab2(sch_1):m_m_cke"
				( memberType ( signal ) )
				( member ( signalRef "@baseboard_fab2_lib.baseboard_fab2(sch_1):m_m_cke(0)") )
				( member ( signalRef "@baseboard_fab2_lib.baseboard_fab2(sch_1):m_m_cke(1)") )
				( member ( signalRef "@baseboard_fab2_lib.baseboard_fab2(sch_1):m_m_cke(2)") )
				( member ( signalRef "@baseboard_fab2_lib.baseboard_fab2(sch_1):m_m_cke(3)") )
				( objectStatus "M_M_CKE" )
			)
			( bus "@baseboard_fab2_lib.baseboard_fab2(sch_1):m_m_clk_dn"
				( memberType ( signal ) )
				( member ( signalRef "@baseboard_fab2_lib.baseboard_fab2(sch_1):m_m_clk_dn(0)") )
				( member ( signalRef "@baseboard_fab2_lib.baseboard_fab2(sch_1):m_m_clk_dn(1)") )
				( member ( signalRef "@baseboard_fab2_lib.baseboard_fab2(sch_1):m_m_clk_dn(2)") )
				( member ( signalRef "@baseboard_fab2_lib.baseboard_fab2(sch_1):m_m_clk_dn(3)") )
				( objectStatus "M_M_CLK_DN" )
			)
			( bus "@baseboard_fab2_lib.baseboard_fab2(sch_1):m_m_clk_dp"
				( memberType ( signal ) )
				( member ( signalRef "@baseboard_fab2_lib.baseboard_fab2(sch_1):m_m_clk_dp(0)") )
				( member ( signalRef "@baseboard_fab2_lib.baseboard_fab2(sch_1):m_m_clk_dp(1)") )
				( member ( signalRef "@baseboard_fab2_lib.baseboard_fab2(sch_1):m_m_clk_dp(2)") )
				( member ( signalRef "@baseboard_fab2_lib.baseboard_fab2(sch_1):m_m_clk_dp(3)") )
				( objectStatus "M_M_CLK_DP" )
			)
			( bus "@baseboard_fab2_lib.baseboard_fab2(sch_1):m_m_cs_n"
				( memberType ( signal ) )
				( member ( signalRef "@baseboard_fab2_lib.baseboard_fab2(sch_1):m_m_cs_n(0)") )
				( member ( signalRef "@baseboard_fab2_lib.baseboard_fab2(sch_1):m_m_cs_n(1)") )
				( member ( signalRef "@baseboard_fab2_lib.baseboard_fab2(sch_1):m_m_cs_n(2)") )
				( member ( signalRef "@baseboard_fab2_lib.baseboard_fab2(sch_1):m_m_cs_n(3)") )
				( member ( signalRef "@baseboard_fab2_lib.baseboard_fab2(sch_1):m_m_cs_n(4)") )
				( member ( signalRef "@baseboard_fab2_lib.baseboard_fab2(sch_1):m_m_cs_n(5)") )
				( member ( signalRef "@baseboard_fab2_lib.baseboard_fab2(sch_1):m_m_cs_n(6)") )
				( member ( signalRef "@baseboard_fab2_lib.baseboard_fab2(sch_1):m_m_cs_n(7)") )
				( objectStatus "M_M_CS_N" )
			)
			( bus "@baseboard_fab2_lib.baseboard_fab2(sch_1):m_m_dq"
				( memberType ( signal ) )
				( member ( signalRef "@baseboard_fab2_lib.baseboard_fab2(sch_1):m_m_dq(0)") )
				( member ( signalRef "@baseboard_fab2_lib.baseboard_fab2(sch_1):m_m_dq(1)") )
				( member ( signalRef "@baseboard_fab2_lib.baseboard_fab2(sch_1):m_m_dq(2)") )
				( member ( signalRef "@baseboard_fab2_lib.baseboard_fab2(sch_1):m_m_dq(3)") )
				( member ( signalRef "@baseboard_fab2_lib.baseboard_fab2(sch_1):m_m_dq(4)") )
				( member ( signalRef "@baseboard_fab2_lib.baseboard_fab2(sch_1):m_m_dq(5)") )
				( member ( signalRef "@baseboard_fab2_lib.baseboard_fab2(sch_1):m_m_dq(6)") )
				( member ( signalRef "@baseboard_fab2_lib.baseboard_fab2(sch_1):m_m_dq(7)") )
				( member ( signalRef "@baseboard_fab2_lib.baseboard_fab2(sch_1):m_m_dq(8)") )
				( member ( signalRef "@baseboard_fab2_lib.baseboard_fab2(sch_1):m_m_dq(9)") )
				( member ( signalRef "@baseboard_fab2_lib.baseboard_fab2(sch_1):m_m_dq(10)") )
				( member ( signalRef "@baseboard_fab2_lib.baseboard_fab2(sch_1):m_m_dq(11)") )
				( member ( signalRef "@baseboard_fab2_lib.baseboard_fab2(sch_1):m_m_dq(12)") )
				( member ( signalRef "@baseboard_fab2_lib.baseboard_fab2(sch_1):m_m_dq(13)") )
				( member ( signalRef "@baseboard_fab2_lib.baseboard_fab2(sch_1):m_m_dq(14)") )
				( member ( signalRef "@baseboard_fab2_lib.baseboard_fab2(sch_1):m_m_dq(15)") )
				( member ( signalRef "@baseboard_fab2_lib.baseboard_fab2(sch_1):m_m_dq(16)") )
				( member ( signalRef "@baseboard_fab2_lib.baseboard_fab2(sch_1):m_m_dq(17)") )
				( member ( signalRef "@baseboard_fab2_lib.baseboard_fab2(sch_1):m_m_dq(18)") )
				( member ( signalRef "@baseboard_fab2_lib.baseboard_fab2(sch_1):m_m_dq(19)") )
				( member ( signalRef "@baseboard_fab2_lib.baseboard_fab2(sch_1):m_m_dq(20)") )
				( member ( signalRef "@baseboard_fab2_lib.baseboard_fab2(sch_1):m_m_dq(21)") )
				( member ( signalRef "@baseboard_fab2_lib.baseboard_fab2(sch_1):m_m_dq(22)") )
				( member ( signalRef "@baseboard_fab2_lib.baseboard_fab2(sch_1):m_m_dq(23)") )
				( member ( signalRef "@baseboard_fab2_lib.baseboard_fab2(sch_1):m_m_dq(24)") )
				( member ( signalRef "@baseboard_fab2_lib.baseboard_fab2(sch_1):m_m_dq(25)") )
				( member ( signalRef "@baseboard_fab2_lib.baseboard_fab2(sch_1):m_m_dq(26)") )
				( member ( signalRef "@baseboard_fab2_lib.baseboard_fab2(sch_1):m_m_dq(27)") )
				( member ( signalRef "@baseboard_fab2_lib.baseboard_fab2(sch_1):m_m_dq(28)") )
				( member ( signalRef "@baseboard_fab2_lib.baseboard_fab2(sch_1):m_m_dq(29)") )
				( member ( signalRef "@baseboard_fab2_lib.baseboard_fab2(sch_1):m_m_dq(30)") )
				( member ( signalRef "@baseboard_fab2_lib.baseboard_fab2(sch_1):m_m_dq(31)") )
				( member ( signalRef "@baseboard_fab2_lib.baseboard_fab2(sch_1):m_m_dq(32)") )
				( member ( signalRef "@baseboard_fab2_lib.baseboard_fab2(sch_1):m_m_dq(33)") )
				( member ( signalRef "@baseboard_fab2_lib.baseboard_fab2(sch_1):m_m_dq(34)") )
				( member ( signalRef "@baseboard_fab2_lib.baseboard_fab2(sch_1):m_m_dq(35)") )
				( member ( signalRef "@baseboard_fab2_lib.baseboard_fab2(sch_1):m_m_dq(36)") )
				( member ( signalRef "@baseboard_fab2_lib.baseboard_fab2(sch_1):m_m_dq(37)") )
				( member ( signalRef "@baseboard_fab2_lib.baseboard_fab2(sch_1):m_m_dq(38)") )
				( member ( signalRef "@baseboard_fab2_lib.baseboard_fab2(sch_1):m_m_dq(39)") )
				( member ( signalRef "@baseboard_fab2_lib.baseboard_fab2(sch_1):m_m_dq(40)") )
				( member ( signalRef "@baseboard_fab2_lib.baseboard_fab2(sch_1):m_m_dq(41)") )
				( member ( signalRef "@baseboard_fab2_lib.baseboard_fab2(sch_1):m_m_dq(42)") )
				( member ( signalRef "@baseboard_fab2_lib.baseboard_fab2(sch_1):m_m_dq(43)") )
				( member ( signalRef "@baseboard_fab2_lib.baseboard_fab2(sch_1):m_m_dq(44)") )
				( member ( signalRef "@baseboard_fab2_lib.baseboard_fab2(sch_1):m_m_dq(45)") )
				( member ( signalRef "@baseboard_fab2_lib.baseboard_fab2(sch_1):m_m_dq(46)") )
				( member ( signalRef "@baseboard_fab2_lib.baseboard_fab2(sch_1):m_m_dq(47)") )
				( member ( signalRef "@baseboard_fab2_lib.baseboard_fab2(sch_1):m_m_dq(48)") )
				( member ( signalRef "@baseboard_fab2_lib.baseboard_fab2(sch_1):m_m_dq(49)") )
				( member ( signalRef "@baseboard_fab2_lib.baseboard_fab2(sch_1):m_m_dq(50)") )
				( member ( signalRef "@baseboard_fab2_lib.baseboard_fab2(sch_1):m_m_dq(51)") )
				( member ( signalRef "@baseboard_fab2_lib.baseboard_fab2(sch_1):m_m_dq(52)") )
				( member ( signalRef "@baseboard_fab2_lib.baseboard_fab2(sch_1):m_m_dq(53)") )
				( member ( signalRef "@baseboard_fab2_lib.baseboard_fab2(sch_1):m_m_dq(54)") )
				( member ( signalRef "@baseboard_fab2_lib.baseboard_fab2(sch_1):m_m_dq(55)") )
				( member ( signalRef "@baseboard_fab2_lib.baseboard_fab2(sch_1):m_m_dq(56)") )
				( member ( signalRef "@baseboard_fab2_lib.baseboard_fab2(sch_1):m_m_dq(57)") )
				( member ( signalRef "@baseboard_fab2_lib.baseboard_fab2(sch_1):m_m_dq(58)") )
				( member ( signalRef "@baseboard_fab2_lib.baseboard_fab2(sch_1):m_m_dq(59)") )
				( member ( signalRef "@baseboard_fab2_lib.baseboard_fab2(sch_1):m_m_dq(60)") )
				( member ( signalRef "@baseboard_fab2_lib.baseboard_fab2(sch_1):m_m_dq(61)") )
				( member ( signalRef "@baseboard_fab2_lib.baseboard_fab2(sch_1):m_m_dq(62)") )
				( member ( signalRef "@baseboard_fab2_lib.baseboard_fab2(sch_1):m_m_dq(63)") )
				( objectStatus "M_M_DQ" )
			)
			( bus "@baseboard_fab2_lib.baseboard_fab2(sch_1):m_m_dqs_dn"
				( memberType ( signal ) )
				( member ( signalRef "@baseboard_fab2_lib.baseboard_fab2(sch_1):m_m_dqs_dn(0)") )
				( member ( signalRef "@baseboard_fab2_lib.baseboard_fab2(sch_1):m_m_dqs_dn(1)") )
				( member ( signalRef "@baseboard_fab2_lib.baseboard_fab2(sch_1):m_m_dqs_dn(2)") )
				( member ( signalRef "@baseboard_fab2_lib.baseboard_fab2(sch_1):m_m_dqs_dn(3)") )
				( member ( signalRef "@baseboard_fab2_lib.baseboard_fab2(sch_1):m_m_dqs_dn(4)") )
				( member ( signalRef "@baseboard_fab2_lib.baseboard_fab2(sch_1):m_m_dqs_dn(5)") )
				( member ( signalRef "@baseboard_fab2_lib.baseboard_fab2(sch_1):m_m_dqs_dn(6)") )
				( member ( signalRef "@baseboard_fab2_lib.baseboard_fab2(sch_1):m_m_dqs_dn(7)") )
				( member ( signalRef "@baseboard_fab2_lib.baseboard_fab2(sch_1):m_m_dqs_dn(8)") )
				( member ( signalRef "@baseboard_fab2_lib.baseboard_fab2(sch_1):m_m_dqs_dn(9)") )
				( member ( signalRef "@baseboard_fab2_lib.baseboard_fab2(sch_1):m_m_dqs_dn(10)") )
				( member ( signalRef "@baseboard_fab2_lib.baseboard_fab2(sch_1):m_m_dqs_dn(11)") )
				( member ( signalRef "@baseboard_fab2_lib.baseboard_fab2(sch_1):m_m_dqs_dn(12)") )
				( member ( signalRef "@baseboard_fab2_lib.baseboard_fab2(sch_1):m_m_dqs_dn(13)") )
				( member ( signalRef "@baseboard_fab2_lib.baseboard_fab2(sch_1):m_m_dqs_dn(14)") )
				( member ( signalRef "@baseboard_fab2_lib.baseboard_fab2(sch_1):m_m_dqs_dn(15)") )
				( member ( signalRef "@baseboard_fab2_lib.baseboard_fab2(sch_1):m_m_dqs_dn(16)") )
				( member ( signalRef "@baseboard_fab2_lib.baseboard_fab2(sch_1):m_m_dqs_dn(17)") )
				( objectStatus "M_M_DQS_DN" )
			)
			( bus "@baseboard_fab2_lib.baseboard_fab2(sch_1):m_m_dqs_dp"
				( memberType ( signal ) )
				( member ( signalRef "@baseboard_fab2_lib.baseboard_fab2(sch_1):m_m_dqs_dp(0)") )
				( member ( signalRef "@baseboard_fab2_lib.baseboard_fab2(sch_1):m_m_dqs_dp(1)") )
				( member ( signalRef "@baseboard_fab2_lib.baseboard_fab2(sch_1):m_m_dqs_dp(2)") )
				( member ( signalRef "@baseboard_fab2_lib.baseboard_fab2(sch_1):m_m_dqs_dp(3)") )
				( member ( signalRef "@baseboard_fab2_lib.baseboard_fab2(sch_1):m_m_dqs_dp(4)") )
				( member ( signalRef "@baseboard_fab2_lib.baseboard_fab2(sch_1):m_m_dqs_dp(5)") )
				( member ( signalRef "@baseboard_fab2_lib.baseboard_fab2(sch_1):m_m_dqs_dp(6)") )
				( member ( signalRef "@baseboard_fab2_lib.baseboard_fab2(sch_1):m_m_dqs_dp(7)") )
				( member ( signalRef "@baseboard_fab2_lib.baseboard_fab2(sch_1):m_m_dqs_dp(8)") )
				( member ( signalRef "@baseboard_fab2_lib.baseboard_fab2(sch_1):m_m_dqs_dp(9)") )
				( member ( signalRef "@baseboard_fab2_lib.baseboard_fab2(sch_1):m_m_dqs_dp(10)") )
				( member ( signalRef "@baseboard_fab2_lib.baseboard_fab2(sch_1):m_m_dqs_dp(11)") )
				( member ( signalRef "@baseboard_fab2_lib.baseboard_fab2(sch_1):m_m_dqs_dp(12)") )
				( member ( signalRef "@baseboard_fab2_lib.baseboard_fab2(sch_1):m_m_dqs_dp(13)") )
				( member ( signalRef "@baseboard_fab2_lib.baseboard_fab2(sch_1):m_m_dqs_dp(14)") )
				( member ( signalRef "@baseboard_fab2_lib.baseboard_fab2(sch_1):m_m_dqs_dp(15)") )
				( member ( signalRef "@baseboard_fab2_lib.baseboard_fab2(sch_1):m_m_dqs_dp(16)") )
				( member ( signalRef "@baseboard_fab2_lib.baseboard_fab2(sch_1):m_m_dqs_dp(17)") )
				( objectStatus "M_M_DQS_DP" )
			)
			( bus "@baseboard_fab2_lib.baseboard_fab2(sch_1):m_m_ecc"
				( memberType ( signal ) )
				( member ( signalRef "@baseboard_fab2_lib.baseboard_fab2(sch_1):m_m_ecc(0)") )
				( member ( signalRef "@baseboard_fab2_lib.baseboard_fab2(sch_1):m_m_ecc(1)") )
				( member ( signalRef "@baseboard_fab2_lib.baseboard_fab2(sch_1):m_m_ecc(2)") )
				( member ( signalRef "@baseboard_fab2_lib.baseboard_fab2(sch_1):m_m_ecc(3)") )
				( member ( signalRef "@baseboard_fab2_lib.baseboard_fab2(sch_1):m_m_ecc(4)") )
				( member ( signalRef "@baseboard_fab2_lib.baseboard_fab2(sch_1):m_m_ecc(5)") )
				( member ( signalRef "@baseboard_fab2_lib.baseboard_fab2(sch_1):m_m_ecc(6)") )
				( member ( signalRef "@baseboard_fab2_lib.baseboard_fab2(sch_1):m_m_ecc(7)") )
				( objectStatus "M_M_ECC" )
			)
			( bus "@baseboard_fab2_lib.baseboard_fab2(sch_1):m_m_ma"
				( memberType ( signal ) )
				( member ( signalRef "@baseboard_fab2_lib.baseboard_fab2(sch_1):m_m_ma(0)") )
				( member ( signalRef "@baseboard_fab2_lib.baseboard_fab2(sch_1):m_m_ma(1)") )
				( member ( signalRef "@baseboard_fab2_lib.baseboard_fab2(sch_1):m_m_ma(2)") )
				( member ( signalRef "@baseboard_fab2_lib.baseboard_fab2(sch_1):m_m_ma(3)") )
				( member ( signalRef "@baseboard_fab2_lib.baseboard_fab2(sch_1):m_m_ma(4)") )
				( member ( signalRef "@baseboard_fab2_lib.baseboard_fab2(sch_1):m_m_ma(5)") )
				( member ( signalRef "@baseboard_fab2_lib.baseboard_fab2(sch_1):m_m_ma(6)") )
				( member ( signalRef "@baseboard_fab2_lib.baseboard_fab2(sch_1):m_m_ma(7)") )
				( member ( signalRef "@baseboard_fab2_lib.baseboard_fab2(sch_1):m_m_ma(8)") )
				( member ( signalRef "@baseboard_fab2_lib.baseboard_fab2(sch_1):m_m_ma(9)") )
				( member ( signalRef "@baseboard_fab2_lib.baseboard_fab2(sch_1):m_m_ma(10)") )
				( member ( signalRef "@baseboard_fab2_lib.baseboard_fab2(sch_1):m_m_ma(11)") )
				( member ( signalRef "@baseboard_fab2_lib.baseboard_fab2(sch_1):m_m_ma(12)") )
				( member ( signalRef "@baseboard_fab2_lib.baseboard_fab2(sch_1):m_m_ma(13)") )
				( member ( signalRef "@baseboard_fab2_lib.baseboard_fab2(sch_1):m_m_ma(14)") )
				( member ( signalRef "@baseboard_fab2_lib.baseboard_fab2(sch_1):m_m_ma(15)") )
				( member ( signalRef "@baseboard_fab2_lib.baseboard_fab2(sch_1):m_m_ma(16)") )
				( member ( signalRef "@baseboard_fab2_lib.baseboard_fab2(sch_1):m_m_ma(17)") )
				( objectStatus "M_M_MA" )
			)
			( bus "@baseboard_fab2_lib.baseboard_fab2(sch_1):m_m_odt"
				( memberType ( signal ) )
				( member ( signalRef "@baseboard_fab2_lib.baseboard_fab2(sch_1):m_m_odt(0)") )
				( member ( signalRef "@baseboard_fab2_lib.baseboard_fab2(sch_1):m_m_odt(1)") )
				( member ( signalRef "@baseboard_fab2_lib.baseboard_fab2(sch_1):m_m_odt(2)") )
				( member ( signalRef "@baseboard_fab2_lib.baseboard_fab2(sch_1):m_m_odt(3)") )
				( objectStatus "M_M_ODT" )
			)
			( bus "@baseboard_fab2_lib.baseboard_fab2(sch_1):tp_p3e_cpu1_pe1_mp_rxn"
				( memberType ( signal ) )
				( member ( signalRef "@baseboard_fab2_lib.baseboard_fab2(sch_1):tp_p3e_cpu1_pe1_mp_rxn(0)") )
				( member ( signalRef "@baseboard_fab2_lib.baseboard_fab2(sch_1):tp_p3e_cpu1_pe1_mp_rxn(1)") )
				( member ( signalRef "@baseboard_fab2_lib.baseboard_fab2(sch_1):tp_p3e_cpu1_pe1_mp_rxn(2)") )
				( member ( signalRef "@baseboard_fab2_lib.baseboard_fab2(sch_1):tp_p3e_cpu1_pe1_mp_rxn(3)") )
				( member ( signalRef "@baseboard_fab2_lib.baseboard_fab2(sch_1):tp_p3e_cpu1_pe1_mp_rxn(4)") )
				( member ( signalRef "@baseboard_fab2_lib.baseboard_fab2(sch_1):tp_p3e_cpu1_pe1_mp_rxn(5)") )
				( member ( signalRef "@baseboard_fab2_lib.baseboard_fab2(sch_1):tp_p3e_cpu1_pe1_mp_rxn(6)") )
				( member ( signalRef "@baseboard_fab2_lib.baseboard_fab2(sch_1):tp_p3e_cpu1_pe1_mp_rxn(7)") )
				( objectStatus "TP_P3E_CPU1_PE1_MP_RXN" )
			)
			( bus "@baseboard_fab2_lib.baseboard_fab2(sch_1):tp_p3e_cpu1_pe1_mp_rxp"
				( memberType ( signal ) )
				( member ( signalRef "@baseboard_fab2_lib.baseboard_fab2(sch_1):tp_p3e_cpu1_pe1_mp_rxp(0)") )
				( member ( signalRef "@baseboard_fab2_lib.baseboard_fab2(sch_1):tp_p3e_cpu1_pe1_mp_rxp(1)") )
				( member ( signalRef "@baseboard_fab2_lib.baseboard_fab2(sch_1):tp_p3e_cpu1_pe1_mp_rxp(2)") )
				( member ( signalRef "@baseboard_fab2_lib.baseboard_fab2(sch_1):tp_p3e_cpu1_pe1_mp_rxp(3)") )
				( member ( signalRef "@baseboard_fab2_lib.baseboard_fab2(sch_1):tp_p3e_cpu1_pe1_mp_rxp(4)") )
				( member ( signalRef "@baseboard_fab2_lib.baseboard_fab2(sch_1):tp_p3e_cpu1_pe1_mp_rxp(5)") )
				( member ( signalRef "@baseboard_fab2_lib.baseboard_fab2(sch_1):tp_p3e_cpu1_pe1_mp_rxp(6)") )
				( member ( signalRef "@baseboard_fab2_lib.baseboard_fab2(sch_1):tp_p3e_cpu1_pe1_mp_rxp(7)") )
				( objectStatus "TP_P3E_CPU1_PE1_MP_RXP" )
			)
			( bus "@baseboard_fab2_lib.baseboard_fab2(sch_1):tp_p3e_cpu1_pe1_mp_txn"
				( memberType ( signal ) )
				( member ( signalRef "@baseboard_fab2_lib.baseboard_fab2(sch_1):tp_p3e_cpu1_pe1_mp_txn(0)") )
				( member ( signalRef "@baseboard_fab2_lib.baseboard_fab2(sch_1):tp_p3e_cpu1_pe1_mp_txn(1)") )
				( member ( signalRef "@baseboard_fab2_lib.baseboard_fab2(sch_1):tp_p3e_cpu1_pe1_mp_txn(2)") )
				( member ( signalRef "@baseboard_fab2_lib.baseboard_fab2(sch_1):tp_p3e_cpu1_pe1_mp_txn(3)") )
				( member ( signalRef "@baseboard_fab2_lib.baseboard_fab2(sch_1):tp_p3e_cpu1_pe1_mp_txn(4)") )
				( member ( signalRef "@baseboard_fab2_lib.baseboard_fab2(sch_1):tp_p3e_cpu1_pe1_mp_txn(5)") )
				( member ( signalRef "@baseboard_fab2_lib.baseboard_fab2(sch_1):tp_p3e_cpu1_pe1_mp_txn(6)") )
				( member ( signalRef "@baseboard_fab2_lib.baseboard_fab2(sch_1):tp_p3e_cpu1_pe1_mp_txn(7)") )
				( objectStatus "TP_P3E_CPU1_PE1_MP_TXN" )
			)
			( bus "@baseboard_fab2_lib.baseboard_fab2(sch_1):tp_p3e_cpu1_pe1_mp_txp"
				( memberType ( signal ) )
				( member ( signalRef "@baseboard_fab2_lib.baseboard_fab2(sch_1):tp_p3e_cpu1_pe1_mp_txp(0)") )
				( member ( signalRef "@baseboard_fab2_lib.baseboard_fab2(sch_1):tp_p3e_cpu1_pe1_mp_txp(1)") )
				( member ( signalRef "@baseboard_fab2_lib.baseboard_fab2(sch_1):tp_p3e_cpu1_pe1_mp_txp(2)") )
				( member ( signalRef "@baseboard_fab2_lib.baseboard_fab2(sch_1):tp_p3e_cpu1_pe1_mp_txp(3)") )
				( member ( signalRef "@baseboard_fab2_lib.baseboard_fab2(sch_1):tp_p3e_cpu1_pe1_mp_txp(4)") )
				( member ( signalRef "@baseboard_fab2_lib.baseboard_fab2(sch_1):tp_p3e_cpu1_pe1_mp_txp(5)") )
				( member ( signalRef "@baseboard_fab2_lib.baseboard_fab2(sch_1):tp_p3e_cpu1_pe1_mp_txp(6)") )
				( member ( signalRef "@baseboard_fab2_lib.baseboard_fab2(sch_1):tp_p3e_cpu1_pe1_mp_txp(7)") )
				( objectStatus "TP_P3E_CPU1_PE1_MP_TXP" )
			)
			( bus "@baseboard_fab2_lib.baseboard_fab2(sch_1):tp_p3e_cpu1_pe1_rsr3_rxn"
				( memberType ( signal ) )
				( member ( signalRef "@baseboard_fab2_lib.baseboard_fab2(sch_1):tp_p3e_cpu1_pe1_rsr3_rxn(8)") )
				( member ( signalRef "@baseboard_fab2_lib.baseboard_fab2(sch_1):tp_p3e_cpu1_pe1_rsr3_rxn(9)") )
				( member ( signalRef "@baseboard_fab2_lib.baseboard_fab2(sch_1):tp_p3e_cpu1_pe1_rsr3_rxn(10)") )
				( member ( signalRef "@baseboard_fab2_lib.baseboard_fab2(sch_1):tp_p3e_cpu1_pe1_rsr3_rxn(11)") )
				( member ( signalRef "@baseboard_fab2_lib.baseboard_fab2(sch_1):tp_p3e_cpu1_pe1_rsr3_rxn(12)") )
				( member ( signalRef "@baseboard_fab2_lib.baseboard_fab2(sch_1):tp_p3e_cpu1_pe1_rsr3_rxn(13)") )
				( member ( signalRef "@baseboard_fab2_lib.baseboard_fab2(sch_1):tp_p3e_cpu1_pe1_rsr3_rxn(14)") )
				( member ( signalRef "@baseboard_fab2_lib.baseboard_fab2(sch_1):tp_p3e_cpu1_pe1_rsr3_rxn(15)") )
				( objectStatus "TP_P3E_CPU1_PE1_RSR3_RXN" )
			)
			( bus "@baseboard_fab2_lib.baseboard_fab2(sch_1):tp_p3e_cpu1_pe1_rsr3_rxp"
				( memberType ( signal ) )
				( member ( signalRef "@baseboard_fab2_lib.baseboard_fab2(sch_1):tp_p3e_cpu1_pe1_rsr3_rxp(8)") )
				( member ( signalRef "@baseboard_fab2_lib.baseboard_fab2(sch_1):tp_p3e_cpu1_pe1_rsr3_rxp(9)") )
				( member ( signalRef "@baseboard_fab2_lib.baseboard_fab2(sch_1):tp_p3e_cpu1_pe1_rsr3_rxp(10)") )
				( member ( signalRef "@baseboard_fab2_lib.baseboard_fab2(sch_1):tp_p3e_cpu1_pe1_rsr3_rxp(11)") )
				( member ( signalRef "@baseboard_fab2_lib.baseboard_fab2(sch_1):tp_p3e_cpu1_pe1_rsr3_rxp(12)") )
				( member ( signalRef "@baseboard_fab2_lib.baseboard_fab2(sch_1):tp_p3e_cpu1_pe1_rsr3_rxp(13)") )
				( member ( signalRef "@baseboard_fab2_lib.baseboard_fab2(sch_1):tp_p3e_cpu1_pe1_rsr3_rxp(14)") )
				( member ( signalRef "@baseboard_fab2_lib.baseboard_fab2(sch_1):tp_p3e_cpu1_pe1_rsr3_rxp(15)") )
				( objectStatus "TP_P3E_CPU1_PE1_RSR3_RXP" )
			)
			( bus "@baseboard_fab2_lib.baseboard_fab2(sch_1):tp_p3e_cpu1_pe1_rsr3_txn"
				( memberType ( signal ) )
				( member ( signalRef "@baseboard_fab2_lib.baseboard_fab2(sch_1):tp_p3e_cpu1_pe1_rsr3_txn(8)") )
				( member ( signalRef "@baseboard_fab2_lib.baseboard_fab2(sch_1):tp_p3e_cpu1_pe1_rsr3_txn(9)") )
				( member ( signalRef "@baseboard_fab2_lib.baseboard_fab2(sch_1):tp_p3e_cpu1_pe1_rsr3_txn(10)") )
				( member ( signalRef "@baseboard_fab2_lib.baseboard_fab2(sch_1):tp_p3e_cpu1_pe1_rsr3_txn(11)") )
				( member ( signalRef "@baseboard_fab2_lib.baseboard_fab2(sch_1):tp_p3e_cpu1_pe1_rsr3_txn(12)") )
				( member ( signalRef "@baseboard_fab2_lib.baseboard_fab2(sch_1):tp_p3e_cpu1_pe1_rsr3_txn(13)") )
				( member ( signalRef "@baseboard_fab2_lib.baseboard_fab2(sch_1):tp_p3e_cpu1_pe1_rsr3_txn(14)") )
				( member ( signalRef "@baseboard_fab2_lib.baseboard_fab2(sch_1):tp_p3e_cpu1_pe1_rsr3_txn(15)") )
				( objectStatus "TP_P3E_CPU1_PE1_RSR3_TXN" )
			)
			( bus "@baseboard_fab2_lib.baseboard_fab2(sch_1):tp_p3e_cpu1_pe1_rsr3_txp"
				( memberType ( signal ) )
				( member ( signalRef "@baseboard_fab2_lib.baseboard_fab2(sch_1):tp_p3e_cpu1_pe1_rsr3_txp(8)") )
				( member ( signalRef "@baseboard_fab2_lib.baseboard_fab2(sch_1):tp_p3e_cpu1_pe1_rsr3_txp(9)") )
				( member ( signalRef "@baseboard_fab2_lib.baseboard_fab2(sch_1):tp_p3e_cpu1_pe1_rsr3_txp(10)") )
				( member ( signalRef "@baseboard_fab2_lib.baseboard_fab2(sch_1):tp_p3e_cpu1_pe1_rsr3_txp(11)") )
				( member ( signalRef "@baseboard_fab2_lib.baseboard_fab2(sch_1):tp_p3e_cpu1_pe1_rsr3_txp(12)") )
				( member ( signalRef "@baseboard_fab2_lib.baseboard_fab2(sch_1):tp_p3e_cpu1_pe1_rsr3_txp(13)") )
				( member ( signalRef "@baseboard_fab2_lib.baseboard_fab2(sch_1):tp_p3e_cpu1_pe1_rsr3_txp(14)") )
				( member ( signalRef "@baseboard_fab2_lib.baseboard_fab2(sch_1):tp_p3e_cpu1_pe1_rsr3_txp(15)") )
				( objectStatus "TP_P3E_CPU1_PE1_RSR3_TXP" )
			)
			( bus "@baseboard_fab2_lib.baseboard_fab2(sch_1):tp_p3e_cpu1_pe2_rsr_rxn"
				( memberType ( signal ) )
				( member ( signalRef "@baseboard_fab2_lib.baseboard_fab2(sch_1):tp_p3e_cpu1_pe2_rsr_rxn(0)") )
				( member ( signalRef "@baseboard_fab2_lib.baseboard_fab2(sch_1):tp_p3e_cpu1_pe2_rsr_rxn(1)") )
				( member ( signalRef "@baseboard_fab2_lib.baseboard_fab2(sch_1):tp_p3e_cpu1_pe2_rsr_rxn(2)") )
				( member ( signalRef "@baseboard_fab2_lib.baseboard_fab2(sch_1):tp_p3e_cpu1_pe2_rsr_rxn(3)") )
				( member ( signalRef "@baseboard_fab2_lib.baseboard_fab2(sch_1):tp_p3e_cpu1_pe2_rsr_rxn(4)") )
				( member ( signalRef "@baseboard_fab2_lib.baseboard_fab2(sch_1):tp_p3e_cpu1_pe2_rsr_rxn(5)") )
				( member ( signalRef "@baseboard_fab2_lib.baseboard_fab2(sch_1):tp_p3e_cpu1_pe2_rsr_rxn(6)") )
				( member ( signalRef "@baseboard_fab2_lib.baseboard_fab2(sch_1):tp_p3e_cpu1_pe2_rsr_rxn(7)") )
				( member ( signalRef "@baseboard_fab2_lib.baseboard_fab2(sch_1):tp_p3e_cpu1_pe2_rsr_rxn(8)") )
				( member ( signalRef "@baseboard_fab2_lib.baseboard_fab2(sch_1):tp_p3e_cpu1_pe2_rsr_rxn(9)") )
				( member ( signalRef "@baseboard_fab2_lib.baseboard_fab2(sch_1):tp_p3e_cpu1_pe2_rsr_rxn(10)") )
				( member ( signalRef "@baseboard_fab2_lib.baseboard_fab2(sch_1):tp_p3e_cpu1_pe2_rsr_rxn(11)") )
				( member ( signalRef "@baseboard_fab2_lib.baseboard_fab2(sch_1):tp_p3e_cpu1_pe2_rsr_rxn(12)") )
				( member ( signalRef "@baseboard_fab2_lib.baseboard_fab2(sch_1):tp_p3e_cpu1_pe2_rsr_rxn(13)") )
				( member ( signalRef "@baseboard_fab2_lib.baseboard_fab2(sch_1):tp_p3e_cpu1_pe2_rsr_rxn(14)") )
				( member ( signalRef "@baseboard_fab2_lib.baseboard_fab2(sch_1):tp_p3e_cpu1_pe2_rsr_rxn(15)") )
				( objectStatus "TP_P3E_CPU1_PE2_RSR_RXN" )
			)
			( bus "@baseboard_fab2_lib.baseboard_fab2(sch_1):tp_p3e_cpu1_pe2_rsr_rxp"
				( memberType ( signal ) )
				( member ( signalRef "@baseboard_fab2_lib.baseboard_fab2(sch_1):tp_p3e_cpu1_pe2_rsr_rxp(0)") )
				( member ( signalRef "@baseboard_fab2_lib.baseboard_fab2(sch_1):tp_p3e_cpu1_pe2_rsr_rxp(1)") )
				( member ( signalRef "@baseboard_fab2_lib.baseboard_fab2(sch_1):tp_p3e_cpu1_pe2_rsr_rxp(2)") )
				( member ( signalRef "@baseboard_fab2_lib.baseboard_fab2(sch_1):tp_p3e_cpu1_pe2_rsr_rxp(3)") )
				( member ( signalRef "@baseboard_fab2_lib.baseboard_fab2(sch_1):tp_p3e_cpu1_pe2_rsr_rxp(4)") )
				( member ( signalRef "@baseboard_fab2_lib.baseboard_fab2(sch_1):tp_p3e_cpu1_pe2_rsr_rxp(5)") )
				( member ( signalRef "@baseboard_fab2_lib.baseboard_fab2(sch_1):tp_p3e_cpu1_pe2_rsr_rxp(6)") )
				( member ( signalRef "@baseboard_fab2_lib.baseboard_fab2(sch_1):tp_p3e_cpu1_pe2_rsr_rxp(7)") )
				( member ( signalRef "@baseboard_fab2_lib.baseboard_fab2(sch_1):tp_p3e_cpu1_pe2_rsr_rxp(8)") )
				( member ( signalRef "@baseboard_fab2_lib.baseboard_fab2(sch_1):tp_p3e_cpu1_pe2_rsr_rxp(9)") )
				( member ( signalRef "@baseboard_fab2_lib.baseboard_fab2(sch_1):tp_p3e_cpu1_pe2_rsr_rxp(10)") )
				( member ( signalRef "@baseboard_fab2_lib.baseboard_fab2(sch_1):tp_p3e_cpu1_pe2_rsr_rxp(11)") )
				( member ( signalRef "@baseboard_fab2_lib.baseboard_fab2(sch_1):tp_p3e_cpu1_pe2_rsr_rxp(12)") )
				( member ( signalRef "@baseboard_fab2_lib.baseboard_fab2(sch_1):tp_p3e_cpu1_pe2_rsr_rxp(13)") )
				( member ( signalRef "@baseboard_fab2_lib.baseboard_fab2(sch_1):tp_p3e_cpu1_pe2_rsr_rxp(14)") )
				( member ( signalRef "@baseboard_fab2_lib.baseboard_fab2(sch_1):tp_p3e_cpu1_pe2_rsr_rxp(15)") )
				( objectStatus "TP_P3E_CPU1_PE2_RSR_RXP" )
			)
			( bus "@baseboard_fab2_lib.baseboard_fab2(sch_1):tp_p3e_cpu1_pe2_rsr_txn"
				( memberType ( signal ) )
				( member ( signalRef "@baseboard_fab2_lib.baseboard_fab2(sch_1):tp_p3e_cpu1_pe2_rsr_txn(0)") )
				( member ( signalRef "@baseboard_fab2_lib.baseboard_fab2(sch_1):tp_p3e_cpu1_pe2_rsr_txn(1)") )
				( member ( signalRef "@baseboard_fab2_lib.baseboard_fab2(sch_1):tp_p3e_cpu1_pe2_rsr_txn(2)") )
				( member ( signalRef "@baseboard_fab2_lib.baseboard_fab2(sch_1):tp_p3e_cpu1_pe2_rsr_txn(3)") )
				( member ( signalRef "@baseboard_fab2_lib.baseboard_fab2(sch_1):tp_p3e_cpu1_pe2_rsr_txn(4)") )
				( member ( signalRef "@baseboard_fab2_lib.baseboard_fab2(sch_1):tp_p3e_cpu1_pe2_rsr_txn(5)") )
				( member ( signalRef "@baseboard_fab2_lib.baseboard_fab2(sch_1):tp_p3e_cpu1_pe2_rsr_txn(6)") )
				( member ( signalRef "@baseboard_fab2_lib.baseboard_fab2(sch_1):tp_p3e_cpu1_pe2_rsr_txn(7)") )
				( member ( signalRef "@baseboard_fab2_lib.baseboard_fab2(sch_1):tp_p3e_cpu1_pe2_rsr_txn(8)") )
				( member ( signalRef "@baseboard_fab2_lib.baseboard_fab2(sch_1):tp_p3e_cpu1_pe2_rsr_txn(9)") )
				( member ( signalRef "@baseboard_fab2_lib.baseboard_fab2(sch_1):tp_p3e_cpu1_pe2_rsr_txn(10)") )
				( member ( signalRef "@baseboard_fab2_lib.baseboard_fab2(sch_1):tp_p3e_cpu1_pe2_rsr_txn(11)") )
				( member ( signalRef "@baseboard_fab2_lib.baseboard_fab2(sch_1):tp_p3e_cpu1_pe2_rsr_txn(12)") )
				( member ( signalRef "@baseboard_fab2_lib.baseboard_fab2(sch_1):tp_p3e_cpu1_pe2_rsr_txn(13)") )
				( member ( signalRef "@baseboard_fab2_lib.baseboard_fab2(sch_1):tp_p3e_cpu1_pe2_rsr_txn(14)") )
				( member ( signalRef "@baseboard_fab2_lib.baseboard_fab2(sch_1):tp_p3e_cpu1_pe2_rsr_txn(15)") )
				( objectStatus "TP_P3E_CPU1_PE2_RSR_TXN" )
			)
			( bus "@baseboard_fab2_lib.baseboard_fab2(sch_1):tp_p3e_cpu1_pe2_rsr_txp"
				( memberType ( signal ) )
				( member ( signalRef "@baseboard_fab2_lib.baseboard_fab2(sch_1):tp_p3e_cpu1_pe2_rsr_txp(0)") )
				( member ( signalRef "@baseboard_fab2_lib.baseboard_fab2(sch_1):tp_p3e_cpu1_pe2_rsr_txp(1)") )
				( member ( signalRef "@baseboard_fab2_lib.baseboard_fab2(sch_1):tp_p3e_cpu1_pe2_rsr_txp(2)") )
				( member ( signalRef "@baseboard_fab2_lib.baseboard_fab2(sch_1):tp_p3e_cpu1_pe2_rsr_txp(3)") )
				( member ( signalRef "@baseboard_fab2_lib.baseboard_fab2(sch_1):tp_p3e_cpu1_pe2_rsr_txp(4)") )
				( member ( signalRef "@baseboard_fab2_lib.baseboard_fab2(sch_1):tp_p3e_cpu1_pe2_rsr_txp(5)") )
				( member ( signalRef "@baseboard_fab2_lib.baseboard_fab2(sch_1):tp_p3e_cpu1_pe2_rsr_txp(6)") )
				( member ( signalRef "@baseboard_fab2_lib.baseboard_fab2(sch_1):tp_p3e_cpu1_pe2_rsr_txp(7)") )
				( member ( signalRef "@baseboard_fab2_lib.baseboard_fab2(sch_1):tp_p3e_cpu1_pe2_rsr_txp(8)") )
				( member ( signalRef "@baseboard_fab2_lib.baseboard_fab2(sch_1):tp_p3e_cpu1_pe2_rsr_txp(9)") )
				( member ( signalRef "@baseboard_fab2_lib.baseboard_fab2(sch_1):tp_p3e_cpu1_pe2_rsr_txp(10)") )
				( member ( signalRef "@baseboard_fab2_lib.baseboard_fab2(sch_1):tp_p3e_cpu1_pe2_rsr_txp(11)") )
				( member ( signalRef "@baseboard_fab2_lib.baseboard_fab2(sch_1):tp_p3e_cpu1_pe2_rsr_txp(12)") )
				( member ( signalRef "@baseboard_fab2_lib.baseboard_fab2(sch_1):tp_p3e_cpu1_pe2_rsr_txp(13)") )
				( member ( signalRef "@baseboard_fab2_lib.baseboard_fab2(sch_1):tp_p3e_cpu1_pe2_rsr_txp(14)") )
				( member ( signalRef "@baseboard_fab2_lib.baseboard_fab2(sch_1):tp_p3e_cpu1_pe2_rsr_txp(15)") )
				( objectStatus "TP_P3E_CPU1_PE2_RSR_TXP" )
			)
			( bus "@baseboard_fab2_lib.baseboard_fab2(sch_1):p3e_cpu1_pe3_mp_rxn"
				( memberType ( signal ) )
				( member ( signalRef "@baseboard_fab2_lib.baseboard_fab2(sch_1):p3e_cpu1_pe3_mp_rxn(0)") )
				( member ( signalRef "@baseboard_fab2_lib.baseboard_fab2(sch_1):p3e_cpu1_pe3_mp_rxn(1)") )
				( member ( signalRef "@baseboard_fab2_lib.baseboard_fab2(sch_1):p3e_cpu1_pe3_mp_rxn(2)") )
				( member ( signalRef "@baseboard_fab2_lib.baseboard_fab2(sch_1):p3e_cpu1_pe3_mp_rxn(3)") )
				( member ( signalRef "@baseboard_fab2_lib.baseboard_fab2(sch_1):p3e_cpu1_pe3_mp_rxn(4)") )
				( member ( signalRef "@baseboard_fab2_lib.baseboard_fab2(sch_1):p3e_cpu1_pe3_mp_rxn(5)") )
				( member ( signalRef "@baseboard_fab2_lib.baseboard_fab2(sch_1):p3e_cpu1_pe3_mp_rxn(6)") )
				( member ( signalRef "@baseboard_fab2_lib.baseboard_fab2(sch_1):p3e_cpu1_pe3_mp_rxn(7)") )
				( member ( signalRef "@baseboard_fab2_lib.baseboard_fab2(sch_1):p3e_cpu1_pe3_mp_rxn(8)") )
				( member ( signalRef "@baseboard_fab2_lib.baseboard_fab2(sch_1):p3e_cpu1_pe3_mp_rxn(9)") )
				( member ( signalRef "@baseboard_fab2_lib.baseboard_fab2(sch_1):p3e_cpu1_pe3_mp_rxn(10)") )
				( member ( signalRef "@baseboard_fab2_lib.baseboard_fab2(sch_1):p3e_cpu1_pe3_mp_rxn(11)") )
				( member ( signalRef "@baseboard_fab2_lib.baseboard_fab2(sch_1):p3e_cpu1_pe3_mp_rxn(12)") )
				( member ( signalRef "@baseboard_fab2_lib.baseboard_fab2(sch_1):p3e_cpu1_pe3_mp_rxn(13)") )
				( member ( signalRef "@baseboard_fab2_lib.baseboard_fab2(sch_1):p3e_cpu1_pe3_mp_rxn(14)") )
				( member ( signalRef "@baseboard_fab2_lib.baseboard_fab2(sch_1):p3e_cpu1_pe3_mp_rxn(15)") )
				( objectStatus "P3E_CPU1_PE3_MP_RXN" )
			)
			( bus "@baseboard_fab2_lib.baseboard_fab2(sch_1):p3e_cpu1_pe3_mp_rxp"
				( memberType ( signal ) )
				( member ( signalRef "@baseboard_fab2_lib.baseboard_fab2(sch_1):p3e_cpu1_pe3_mp_rxp(0)") )
				( member ( signalRef "@baseboard_fab2_lib.baseboard_fab2(sch_1):p3e_cpu1_pe3_mp_rxp(1)") )
				( member ( signalRef "@baseboard_fab2_lib.baseboard_fab2(sch_1):p3e_cpu1_pe3_mp_rxp(2)") )
				( member ( signalRef "@baseboard_fab2_lib.baseboard_fab2(sch_1):p3e_cpu1_pe3_mp_rxp(3)") )
				( member ( signalRef "@baseboard_fab2_lib.baseboard_fab2(sch_1):p3e_cpu1_pe3_mp_rxp(4)") )
				( member ( signalRef "@baseboard_fab2_lib.baseboard_fab2(sch_1):p3e_cpu1_pe3_mp_rxp(5)") )
				( member ( signalRef "@baseboard_fab2_lib.baseboard_fab2(sch_1):p3e_cpu1_pe3_mp_rxp(6)") )
				( member ( signalRef "@baseboard_fab2_lib.baseboard_fab2(sch_1):p3e_cpu1_pe3_mp_rxp(7)") )
				( member ( signalRef "@baseboard_fab2_lib.baseboard_fab2(sch_1):p3e_cpu1_pe3_mp_rxp(8)") )
				( member ( signalRef "@baseboard_fab2_lib.baseboard_fab2(sch_1):p3e_cpu1_pe3_mp_rxp(9)") )
				( member ( signalRef "@baseboard_fab2_lib.baseboard_fab2(sch_1):p3e_cpu1_pe3_mp_rxp(10)") )
				( member ( signalRef "@baseboard_fab2_lib.baseboard_fab2(sch_1):p3e_cpu1_pe3_mp_rxp(11)") )
				( member ( signalRef "@baseboard_fab2_lib.baseboard_fab2(sch_1):p3e_cpu1_pe3_mp_rxp(12)") )
				( member ( signalRef "@baseboard_fab2_lib.baseboard_fab2(sch_1):p3e_cpu1_pe3_mp_rxp(13)") )
				( member ( signalRef "@baseboard_fab2_lib.baseboard_fab2(sch_1):p3e_cpu1_pe3_mp_rxp(14)") )
				( member ( signalRef "@baseboard_fab2_lib.baseboard_fab2(sch_1):p3e_cpu1_pe3_mp_rxp(15)") )
				( objectStatus "P3E_CPU1_PE3_MP_RXP" )
			)
			( bus "@baseboard_fab2_lib.baseboard_fab2(sch_1):p3e_cpu1_pe3_mp_txn"
				( memberType ( signal ) )
				( member ( signalRef "@baseboard_fab2_lib.baseboard_fab2(sch_1):p3e_cpu1_pe3_mp_txn(0)") )
				( member ( signalRef "@baseboard_fab2_lib.baseboard_fab2(sch_1):p3e_cpu1_pe3_mp_txn(1)") )
				( member ( signalRef "@baseboard_fab2_lib.baseboard_fab2(sch_1):p3e_cpu1_pe3_mp_txn(2)") )
				( member ( signalRef "@baseboard_fab2_lib.baseboard_fab2(sch_1):p3e_cpu1_pe3_mp_txn(3)") )
				( member ( signalRef "@baseboard_fab2_lib.baseboard_fab2(sch_1):p3e_cpu1_pe3_mp_txn(4)") )
				( member ( signalRef "@baseboard_fab2_lib.baseboard_fab2(sch_1):p3e_cpu1_pe3_mp_txn(5)") )
				( member ( signalRef "@baseboard_fab2_lib.baseboard_fab2(sch_1):p3e_cpu1_pe3_mp_txn(6)") )
				( member ( signalRef "@baseboard_fab2_lib.baseboard_fab2(sch_1):p3e_cpu1_pe3_mp_txn(7)") )
				( member ( signalRef "@baseboard_fab2_lib.baseboard_fab2(sch_1):p3e_cpu1_pe3_mp_txn(8)") )
				( member ( signalRef "@baseboard_fab2_lib.baseboard_fab2(sch_1):p3e_cpu1_pe3_mp_txn(9)") )
				( member ( signalRef "@baseboard_fab2_lib.baseboard_fab2(sch_1):p3e_cpu1_pe3_mp_txn(10)") )
				( member ( signalRef "@baseboard_fab2_lib.baseboard_fab2(sch_1):p3e_cpu1_pe3_mp_txn(11)") )
				( member ( signalRef "@baseboard_fab2_lib.baseboard_fab2(sch_1):p3e_cpu1_pe3_mp_txn(12)") )
				( member ( signalRef "@baseboard_fab2_lib.baseboard_fab2(sch_1):p3e_cpu1_pe3_mp_txn(13)") )
				( member ( signalRef "@baseboard_fab2_lib.baseboard_fab2(sch_1):p3e_cpu1_pe3_mp_txn(14)") )
				( member ( signalRef "@baseboard_fab2_lib.baseboard_fab2(sch_1):p3e_cpu1_pe3_mp_txn(15)") )
				( objectStatus "P3E_CPU1_PE3_MP_TXN" )
			)
			( bus "@baseboard_fab2_lib.baseboard_fab2(sch_1):p3e_cpu1_pe3_mp_txp"
				( memberType ( signal ) )
				( member ( signalRef "@baseboard_fab2_lib.baseboard_fab2(sch_1):p3e_cpu1_pe3_mp_txp(0)") )
				( member ( signalRef "@baseboard_fab2_lib.baseboard_fab2(sch_1):p3e_cpu1_pe3_mp_txp(1)") )
				( member ( signalRef "@baseboard_fab2_lib.baseboard_fab2(sch_1):p3e_cpu1_pe3_mp_txp(2)") )
				( member ( signalRef "@baseboard_fab2_lib.baseboard_fab2(sch_1):p3e_cpu1_pe3_mp_txp(3)") )
				( member ( signalRef "@baseboard_fab2_lib.baseboard_fab2(sch_1):p3e_cpu1_pe3_mp_txp(4)") )
				( member ( signalRef "@baseboard_fab2_lib.baseboard_fab2(sch_1):p3e_cpu1_pe3_mp_txp(5)") )
				( member ( signalRef "@baseboard_fab2_lib.baseboard_fab2(sch_1):p3e_cpu1_pe3_mp_txp(6)") )
				( member ( signalRef "@baseboard_fab2_lib.baseboard_fab2(sch_1):p3e_cpu1_pe3_mp_txp(7)") )
				( member ( signalRef "@baseboard_fab2_lib.baseboard_fab2(sch_1):p3e_cpu1_pe3_mp_txp(8)") )
				( member ( signalRef "@baseboard_fab2_lib.baseboard_fab2(sch_1):p3e_cpu1_pe3_mp_txp(9)") )
				( member ( signalRef "@baseboard_fab2_lib.baseboard_fab2(sch_1):p3e_cpu1_pe3_mp_txp(10)") )
				( member ( signalRef "@baseboard_fab2_lib.baseboard_fab2(sch_1):p3e_cpu1_pe3_mp_txp(11)") )
				( member ( signalRef "@baseboard_fab2_lib.baseboard_fab2(sch_1):p3e_cpu1_pe3_mp_txp(12)") )
				( member ( signalRef "@baseboard_fab2_lib.baseboard_fab2(sch_1):p3e_cpu1_pe3_mp_txp(13)") )
				( member ( signalRef "@baseboard_fab2_lib.baseboard_fab2(sch_1):p3e_cpu1_pe3_mp_txp(14)") )
				( member ( signalRef "@baseboard_fab2_lib.baseboard_fab2(sch_1):p3e_cpu1_pe3_mp_txp(15)") )
				( objectStatus "P3E_CPU1_PE3_MP_TXP" )
			)
			( bus "@baseboard_fab2_lib.baseboard_fab2(sch_1):nc_db1200zl"
				( memberType ( signal ) )
				( member ( signalRef "@baseboard_fab2_lib.baseboard_fab2(sch_1):nc_db1200zl(0)") )
				( member ( signalRef "@baseboard_fab2_lib.baseboard_fab2(sch_1):nc_db1200zl(1)") )
				( member ( signalRef "@baseboard_fab2_lib.baseboard_fab2(sch_1):nc_db1200zl(2)") )
				( objectStatus "NC_DB1200ZL" )
			)
			( bus "@baseboard_fab2_lib.baseboard_fab2(sch_1):p3e_cpu0_pe1_pch_c_txn"
				( memberType ( signal ) )
				( member ( signalRef "@baseboard_fab2_lib.baseboard_fab2(sch_1):p3e_cpu0_pe1_pch_c_txn(8)") )
				( member ( signalRef "@baseboard_fab2_lib.baseboard_fab2(sch_1):p3e_cpu0_pe1_pch_c_txn(9)") )
				( member ( signalRef "@baseboard_fab2_lib.baseboard_fab2(sch_1):p3e_cpu0_pe1_pch_c_txn(10)") )
				( member ( signalRef "@baseboard_fab2_lib.baseboard_fab2(sch_1):p3e_cpu0_pe1_pch_c_txn(11)") )
				( member ( signalRef "@baseboard_fab2_lib.baseboard_fab2(sch_1):p3e_cpu0_pe1_pch_c_txn(12)") )
				( member ( signalRef "@baseboard_fab2_lib.baseboard_fab2(sch_1):p3e_cpu0_pe1_pch_c_txn(13)") )
				( member ( signalRef "@baseboard_fab2_lib.baseboard_fab2(sch_1):p3e_cpu0_pe1_pch_c_txn(14)") )
				( member ( signalRef "@baseboard_fab2_lib.baseboard_fab2(sch_1):p3e_cpu0_pe1_pch_c_txn(15)") )
				( objectStatus "P3E_CPU0_PE1_PCH_C_TXN" )
			)
			( bus "@baseboard_fab2_lib.baseboard_fab2(sch_1):p3e_cpu0_pe1_pch_c_txp"
				( memberType ( signal ) )
				( member ( signalRef "@baseboard_fab2_lib.baseboard_fab2(sch_1):p3e_cpu0_pe1_pch_c_txp(8)") )
				( member ( signalRef "@baseboard_fab2_lib.baseboard_fab2(sch_1):p3e_cpu0_pe1_pch_c_txp(9)") )
				( member ( signalRef "@baseboard_fab2_lib.baseboard_fab2(sch_1):p3e_cpu0_pe1_pch_c_txp(10)") )
				( member ( signalRef "@baseboard_fab2_lib.baseboard_fab2(sch_1):p3e_cpu0_pe1_pch_c_txp(11)") )
				( member ( signalRef "@baseboard_fab2_lib.baseboard_fab2(sch_1):p3e_cpu0_pe1_pch_c_txp(12)") )
				( member ( signalRef "@baseboard_fab2_lib.baseboard_fab2(sch_1):p3e_cpu0_pe1_pch_c_txp(13)") )
				( member ( signalRef "@baseboard_fab2_lib.baseboard_fab2(sch_1):p3e_cpu0_pe1_pch_c_txp(14)") )
				( member ( signalRef "@baseboard_fab2_lib.baseboard_fab2(sch_1):p3e_cpu0_pe1_pch_c_txp(15)") )
				( objectStatus "P3E_CPU0_PE1_PCH_C_TXP" )
			)
			( bus "@baseboard_fab2_lib.baseboard_fab2(sch_1):p3e_cpu0_pe1_pch_r_rxn"
				( memberType ( signal ) )
				( member ( signalRef "@baseboard_fab2_lib.baseboard_fab2(sch_1):p3e_cpu0_pe1_pch_r_rxn(8)") )
				( member ( signalRef "@baseboard_fab2_lib.baseboard_fab2(sch_1):p3e_cpu0_pe1_pch_r_rxn(9)") )
				( member ( signalRef "@baseboard_fab2_lib.baseboard_fab2(sch_1):p3e_cpu0_pe1_pch_r_rxn(10)") )
				( member ( signalRef "@baseboard_fab2_lib.baseboard_fab2(sch_1):p3e_cpu0_pe1_pch_r_rxn(11)") )
				( member ( signalRef "@baseboard_fab2_lib.baseboard_fab2(sch_1):p3e_cpu0_pe1_pch_r_rxn(12)") )
				( member ( signalRef "@baseboard_fab2_lib.baseboard_fab2(sch_1):p3e_cpu0_pe1_pch_r_rxn(13)") )
				( member ( signalRef "@baseboard_fab2_lib.baseboard_fab2(sch_1):p3e_cpu0_pe1_pch_r_rxn(14)") )
				( member ( signalRef "@baseboard_fab2_lib.baseboard_fab2(sch_1):p3e_cpu0_pe1_pch_r_rxn(15)") )
				( objectStatus "P3E_CPU0_PE1_PCH_R_RXN" )
			)
			( bus "@baseboard_fab2_lib.baseboard_fab2(sch_1):p3e_cpu0_pe1_pch_r_rxp"
				( memberType ( signal ) )
				( member ( signalRef "@baseboard_fab2_lib.baseboard_fab2(sch_1):p3e_cpu0_pe1_pch_r_rxp(8)") )
				( member ( signalRef "@baseboard_fab2_lib.baseboard_fab2(sch_1):p3e_cpu0_pe1_pch_r_rxp(9)") )
				( member ( signalRef "@baseboard_fab2_lib.baseboard_fab2(sch_1):p3e_cpu0_pe1_pch_r_rxp(10)") )
				( member ( signalRef "@baseboard_fab2_lib.baseboard_fab2(sch_1):p3e_cpu0_pe1_pch_r_rxp(11)") )
				( member ( signalRef "@baseboard_fab2_lib.baseboard_fab2(sch_1):p3e_cpu0_pe1_pch_r_rxp(12)") )
				( member ( signalRef "@baseboard_fab2_lib.baseboard_fab2(sch_1):p3e_cpu0_pe1_pch_r_rxp(13)") )
				( member ( signalRef "@baseboard_fab2_lib.baseboard_fab2(sch_1):p3e_cpu0_pe1_pch_r_rxp(14)") )
				( member ( signalRef "@baseboard_fab2_lib.baseboard_fab2(sch_1):p3e_cpu0_pe1_pch_r_rxp(15)") )
				( objectStatus "P3E_CPU0_PE1_PCH_R_RXP" )
			)
			( bus "@baseboard_fab2_lib.baseboard_fab2(sch_1):p3e_cpu0_pe2_ss_c_txn"
				( memberType ( signal ) )
				( member ( signalRef "@baseboard_fab2_lib.baseboard_fab2(sch_1):p3e_cpu0_pe2_ss_c_txn(0)") )
				( member ( signalRef "@baseboard_fab2_lib.baseboard_fab2(sch_1):p3e_cpu0_pe2_ss_c_txn(1)") )
				( member ( signalRef "@baseboard_fab2_lib.baseboard_fab2(sch_1):p3e_cpu0_pe2_ss_c_txn(2)") )
				( member ( signalRef "@baseboard_fab2_lib.baseboard_fab2(sch_1):p3e_cpu0_pe2_ss_c_txn(3)") )
				( member ( signalRef "@baseboard_fab2_lib.baseboard_fab2(sch_1):p3e_cpu0_pe2_ss_c_txn(4)") )
				( member ( signalRef "@baseboard_fab2_lib.baseboard_fab2(sch_1):p3e_cpu0_pe2_ss_c_txn(5)") )
				( member ( signalRef "@baseboard_fab2_lib.baseboard_fab2(sch_1):p3e_cpu0_pe2_ss_c_txn(6)") )
				( member ( signalRef "@baseboard_fab2_lib.baseboard_fab2(sch_1):p3e_cpu0_pe2_ss_c_txn(7)") )
				( member ( signalRef "@baseboard_fab2_lib.baseboard_fab2(sch_1):p3e_cpu0_pe2_ss_c_txn(8)") )
				( member ( signalRef "@baseboard_fab2_lib.baseboard_fab2(sch_1):p3e_cpu0_pe2_ss_c_txn(9)") )
				( member ( signalRef "@baseboard_fab2_lib.baseboard_fab2(sch_1):p3e_cpu0_pe2_ss_c_txn(10)") )
				( member ( signalRef "@baseboard_fab2_lib.baseboard_fab2(sch_1):p3e_cpu0_pe2_ss_c_txn(11)") )
				( member ( signalRef "@baseboard_fab2_lib.baseboard_fab2(sch_1):p3e_cpu0_pe2_ss_c_txn(12)") )
				( member ( signalRef "@baseboard_fab2_lib.baseboard_fab2(sch_1):p3e_cpu0_pe2_ss_c_txn(13)") )
				( member ( signalRef "@baseboard_fab2_lib.baseboard_fab2(sch_1):p3e_cpu0_pe2_ss_c_txn(14)") )
				( member ( signalRef "@baseboard_fab2_lib.baseboard_fab2(sch_1):p3e_cpu0_pe2_ss_c_txn(15)") )
				( objectStatus "P3E_CPU0_PE2_SS_C_TXN" )
			)
			( bus "@baseboard_fab2_lib.baseboard_fab2(sch_1):p3e_cpu0_pe2_ss_c_txp"
				( memberType ( signal ) )
				( member ( signalRef "@baseboard_fab2_lib.baseboard_fab2(sch_1):p3e_cpu0_pe2_ss_c_txp(0)") )
				( member ( signalRef "@baseboard_fab2_lib.baseboard_fab2(sch_1):p3e_cpu0_pe2_ss_c_txp(1)") )
				( member ( signalRef "@baseboard_fab2_lib.baseboard_fab2(sch_1):p3e_cpu0_pe2_ss_c_txp(2)") )
				( member ( signalRef "@baseboard_fab2_lib.baseboard_fab2(sch_1):p3e_cpu0_pe2_ss_c_txp(3)") )
				( member ( signalRef "@baseboard_fab2_lib.baseboard_fab2(sch_1):p3e_cpu0_pe2_ss_c_txp(4)") )
				( member ( signalRef "@baseboard_fab2_lib.baseboard_fab2(sch_1):p3e_cpu0_pe2_ss_c_txp(5)") )
				( member ( signalRef "@baseboard_fab2_lib.baseboard_fab2(sch_1):p3e_cpu0_pe2_ss_c_txp(6)") )
				( member ( signalRef "@baseboard_fab2_lib.baseboard_fab2(sch_1):p3e_cpu0_pe2_ss_c_txp(7)") )
				( member ( signalRef "@baseboard_fab2_lib.baseboard_fab2(sch_1):p3e_cpu0_pe2_ss_c_txp(8)") )
				( member ( signalRef "@baseboard_fab2_lib.baseboard_fab2(sch_1):p3e_cpu0_pe2_ss_c_txp(9)") )
				( member ( signalRef "@baseboard_fab2_lib.baseboard_fab2(sch_1):p3e_cpu0_pe2_ss_c_txp(10)") )
				( member ( signalRef "@baseboard_fab2_lib.baseboard_fab2(sch_1):p3e_cpu0_pe2_ss_c_txp(11)") )
				( member ( signalRef "@baseboard_fab2_lib.baseboard_fab2(sch_1):p3e_cpu0_pe2_ss_c_txp(12)") )
				( member ( signalRef "@baseboard_fab2_lib.baseboard_fab2(sch_1):p3e_cpu0_pe2_ss_c_txp(13)") )
				( member ( signalRef "@baseboard_fab2_lib.baseboard_fab2(sch_1):p3e_cpu0_pe2_ss_c_txp(14)") )
				( member ( signalRef "@baseboard_fab2_lib.baseboard_fab2(sch_1):p3e_cpu0_pe2_ss_c_txp(15)") )
				( objectStatus "P3E_CPU0_PE2_SS_C_TXP" )
			)
			( bus "@baseboard_fab2_lib.baseboard_fab2(sch_1):p3e_ocp_cpu0_pe3_c_txn"
				( memberType ( signal ) )
				( member ( signalRef "@baseboard_fab2_lib.baseboard_fab2(sch_1):p3e_ocp_cpu0_pe3_c_txn(0)") )
				( member ( signalRef "@baseboard_fab2_lib.baseboard_fab2(sch_1):p3e_ocp_cpu0_pe3_c_txn(1)") )
				( member ( signalRef "@baseboard_fab2_lib.baseboard_fab2(sch_1):p3e_ocp_cpu0_pe3_c_txn(2)") )
				( member ( signalRef "@baseboard_fab2_lib.baseboard_fab2(sch_1):p3e_ocp_cpu0_pe3_c_txn(3)") )
				( member ( signalRef "@baseboard_fab2_lib.baseboard_fab2(sch_1):p3e_ocp_cpu0_pe3_c_txn(4)") )
				( member ( signalRef "@baseboard_fab2_lib.baseboard_fab2(sch_1):p3e_ocp_cpu0_pe3_c_txn(5)") )
				( member ( signalRef "@baseboard_fab2_lib.baseboard_fab2(sch_1):p3e_ocp_cpu0_pe3_c_txn(6)") )
				( member ( signalRef "@baseboard_fab2_lib.baseboard_fab2(sch_1):p3e_ocp_cpu0_pe3_c_txn(7)") )
				( member ( signalRef "@baseboard_fab2_lib.baseboard_fab2(sch_1):p3e_ocp_cpu0_pe3_c_txn(8)") )
				( member ( signalRef "@baseboard_fab2_lib.baseboard_fab2(sch_1):p3e_ocp_cpu0_pe3_c_txn(9)") )
				( member ( signalRef "@baseboard_fab2_lib.baseboard_fab2(sch_1):p3e_ocp_cpu0_pe3_c_txn(10)") )
				( member ( signalRef "@baseboard_fab2_lib.baseboard_fab2(sch_1):p3e_ocp_cpu0_pe3_c_txn(11)") )
				( member ( signalRef "@baseboard_fab2_lib.baseboard_fab2(sch_1):p3e_ocp_cpu0_pe3_c_txn(12)") )
				( member ( signalRef "@baseboard_fab2_lib.baseboard_fab2(sch_1):p3e_ocp_cpu0_pe3_c_txn(13)") )
				( member ( signalRef "@baseboard_fab2_lib.baseboard_fab2(sch_1):p3e_ocp_cpu0_pe3_c_txn(14)") )
				( member ( signalRef "@baseboard_fab2_lib.baseboard_fab2(sch_1):p3e_ocp_cpu0_pe3_c_txn(15)") )
				( objectStatus "P3E_OCP_CPU0_PE3_C_TXN" )
			)
			( bus "@baseboard_fab2_lib.baseboard_fab2(sch_1):p3e_ocp_cpu0_pe3_c_txp"
				( memberType ( signal ) )
				( member ( signalRef "@baseboard_fab2_lib.baseboard_fab2(sch_1):p3e_ocp_cpu0_pe3_c_txp(0)") )
				( member ( signalRef "@baseboard_fab2_lib.baseboard_fab2(sch_1):p3e_ocp_cpu0_pe3_c_txp(1)") )
				( member ( signalRef "@baseboard_fab2_lib.baseboard_fab2(sch_1):p3e_ocp_cpu0_pe3_c_txp(2)") )
				( member ( signalRef "@baseboard_fab2_lib.baseboard_fab2(sch_1):p3e_ocp_cpu0_pe3_c_txp(3)") )
				( member ( signalRef "@baseboard_fab2_lib.baseboard_fab2(sch_1):p3e_ocp_cpu0_pe3_c_txp(4)") )
				( member ( signalRef "@baseboard_fab2_lib.baseboard_fab2(sch_1):p3e_ocp_cpu0_pe3_c_txp(5)") )
				( member ( signalRef "@baseboard_fab2_lib.baseboard_fab2(sch_1):p3e_ocp_cpu0_pe3_c_txp(6)") )
				( member ( signalRef "@baseboard_fab2_lib.baseboard_fab2(sch_1):p3e_ocp_cpu0_pe3_c_txp(7)") )
				( member ( signalRef "@baseboard_fab2_lib.baseboard_fab2(sch_1):p3e_ocp_cpu0_pe3_c_txp(8)") )
				( member ( signalRef "@baseboard_fab2_lib.baseboard_fab2(sch_1):p3e_ocp_cpu0_pe3_c_txp(9)") )
				( member ( signalRef "@baseboard_fab2_lib.baseboard_fab2(sch_1):p3e_ocp_cpu0_pe3_c_txp(10)") )
				( member ( signalRef "@baseboard_fab2_lib.baseboard_fab2(sch_1):p3e_ocp_cpu0_pe3_c_txp(11)") )
				( member ( signalRef "@baseboard_fab2_lib.baseboard_fab2(sch_1):p3e_ocp_cpu0_pe3_c_txp(12)") )
				( member ( signalRef "@baseboard_fab2_lib.baseboard_fab2(sch_1):p3e_ocp_cpu0_pe3_c_txp(13)") )
				( member ( signalRef "@baseboard_fab2_lib.baseboard_fab2(sch_1):p3e_ocp_cpu0_pe3_c_txp(14)") )
				( member ( signalRef "@baseboard_fab2_lib.baseboard_fab2(sch_1):p3e_ocp_cpu0_pe3_c_txp(15)") )
				( objectStatus "P3E_OCP_CPU0_PE3_C_TXP" )
			)
			( bus "@baseboard_fab2_lib.baseboard_fab2(sch_1):p3e_cpu0_pe1_ss_c_txn"
				( memberType ( signal ) )
				( member ( signalRef "@baseboard_fab2_lib.baseboard_fab2(sch_1):p3e_cpu0_pe1_ss_c_txn(0)") )
				( member ( signalRef "@baseboard_fab2_lib.baseboard_fab2(sch_1):p3e_cpu0_pe1_ss_c_txn(1)") )
				( member ( signalRef "@baseboard_fab2_lib.baseboard_fab2(sch_1):p3e_cpu0_pe1_ss_c_txn(2)") )
				( member ( signalRef "@baseboard_fab2_lib.baseboard_fab2(sch_1):p3e_cpu0_pe1_ss_c_txn(3)") )
				( member ( signalRef "@baseboard_fab2_lib.baseboard_fab2(sch_1):p3e_cpu0_pe1_ss_c_txn(4)") )
				( member ( signalRef "@baseboard_fab2_lib.baseboard_fab2(sch_1):p3e_cpu0_pe1_ss_c_txn(5)") )
				( member ( signalRef "@baseboard_fab2_lib.baseboard_fab2(sch_1):p3e_cpu0_pe1_ss_c_txn(6)") )
				( member ( signalRef "@baseboard_fab2_lib.baseboard_fab2(sch_1):p3e_cpu0_pe1_ss_c_txn(7)") )
				( objectStatus "P3E_CPU0_PE1_SS_C_TXN" )
			)
			( bus "@baseboard_fab2_lib.baseboard_fab2(sch_1):p3e_cpu0_pe1_ss_c_txp"
				( memberType ( signal ) )
				( member ( signalRef "@baseboard_fab2_lib.baseboard_fab2(sch_1):p3e_cpu0_pe1_ss_c_txp(0)") )
				( member ( signalRef "@baseboard_fab2_lib.baseboard_fab2(sch_1):p3e_cpu0_pe1_ss_c_txp(1)") )
				( member ( signalRef "@baseboard_fab2_lib.baseboard_fab2(sch_1):p3e_cpu0_pe1_ss_c_txp(2)") )
				( member ( signalRef "@baseboard_fab2_lib.baseboard_fab2(sch_1):p3e_cpu0_pe1_ss_c_txp(3)") )
				( member ( signalRef "@baseboard_fab2_lib.baseboard_fab2(sch_1):p3e_cpu0_pe1_ss_c_txp(4)") )
				( member ( signalRef "@baseboard_fab2_lib.baseboard_fab2(sch_1):p3e_cpu0_pe1_ss_c_txp(5)") )
				( member ( signalRef "@baseboard_fab2_lib.baseboard_fab2(sch_1):p3e_cpu0_pe1_ss_c_txp(6)") )
				( member ( signalRef "@baseboard_fab2_lib.baseboard_fab2(sch_1):p3e_cpu0_pe1_ss_c_txp(7)") )
				( objectStatus "P3E_CPU0_PE1_SS_C_TXP" )
			)
			( bus "@baseboard_fab2_lib.baseboard_fab2(sch_1):p3e_cpu0_pe1_ss_r_rxn"
				( memberType ( signal ) )
				( member ( signalRef "@baseboard_fab2_lib.baseboard_fab2(sch_1):p3e_cpu0_pe1_ss_r_rxn(0)") )
				( member ( signalRef "@baseboard_fab2_lib.baseboard_fab2(sch_1):p3e_cpu0_pe1_ss_r_rxn(1)") )
				( member ( signalRef "@baseboard_fab2_lib.baseboard_fab2(sch_1):p3e_cpu0_pe1_ss_r_rxn(2)") )
				( member ( signalRef "@baseboard_fab2_lib.baseboard_fab2(sch_1):p3e_cpu0_pe1_ss_r_rxn(3)") )
				( member ( signalRef "@baseboard_fab2_lib.baseboard_fab2(sch_1):p3e_cpu0_pe1_ss_r_rxn(4)") )
				( member ( signalRef "@baseboard_fab2_lib.baseboard_fab2(sch_1):p3e_cpu0_pe1_ss_r_rxn(5)") )
				( member ( signalRef "@baseboard_fab2_lib.baseboard_fab2(sch_1):p3e_cpu0_pe1_ss_r_rxn(6)") )
				( member ( signalRef "@baseboard_fab2_lib.baseboard_fab2(sch_1):p3e_cpu0_pe1_ss_r_rxn(7)") )
				( objectStatus "P3E_CPU0_PE1_SS_R_RXN" )
			)
			( bus "@baseboard_fab2_lib.baseboard_fab2(sch_1):p3e_cpu0_pe1_ss_r_rxp"
				( memberType ( signal ) )
				( member ( signalRef "@baseboard_fab2_lib.baseboard_fab2(sch_1):p3e_cpu0_pe1_ss_r_rxp(0)") )
				( member ( signalRef "@baseboard_fab2_lib.baseboard_fab2(sch_1):p3e_cpu0_pe1_ss_r_rxp(1)") )
				( member ( signalRef "@baseboard_fab2_lib.baseboard_fab2(sch_1):p3e_cpu0_pe1_ss_r_rxp(2)") )
				( member ( signalRef "@baseboard_fab2_lib.baseboard_fab2(sch_1):p3e_cpu0_pe1_ss_r_rxp(3)") )
				( member ( signalRef "@baseboard_fab2_lib.baseboard_fab2(sch_1):p3e_cpu0_pe1_ss_r_rxp(4)") )
				( member ( signalRef "@baseboard_fab2_lib.baseboard_fab2(sch_1):p3e_cpu0_pe1_ss_r_rxp(5)") )
				( member ( signalRef "@baseboard_fab2_lib.baseboard_fab2(sch_1):p3e_cpu0_pe1_ss_r_rxp(6)") )
				( member ( signalRef "@baseboard_fab2_lib.baseboard_fab2(sch_1):p3e_cpu0_pe1_ss_r_rxp(7)") )
				( objectStatus "P3E_CPU0_PE1_SS_R_RXP" )
			)
			( bus "@baseboard_fab2_lib.baseboard_fab2(sch_1):p3e_pch_m2_rx_dn"
				( memberType ( signal ) )
				( member ( signalRef "@baseboard_fab2_lib.baseboard_fab2(sch_1):p3e_pch_m2_rx_dn(1)") )
				( member ( signalRef "@baseboard_fab2_lib.baseboard_fab2(sch_1):p3e_pch_m2_rx_dn(2)") )
				( member ( signalRef "@baseboard_fab2_lib.baseboard_fab2(sch_1):p3e_pch_m2_rx_dn(3)") )
				( objectStatus "P3E_PCH_M2_RX_DN" )
			)
			( bus "@baseboard_fab2_lib.baseboard_fab2(sch_1):p3e_pch_m2_rx_dp"
				( memberType ( signal ) )
				( member ( signalRef "@baseboard_fab2_lib.baseboard_fab2(sch_1):p3e_pch_m2_rx_dp(1)") )
				( member ( signalRef "@baseboard_fab2_lib.baseboard_fab2(sch_1):p3e_pch_m2_rx_dp(2)") )
				( member ( signalRef "@baseboard_fab2_lib.baseboard_fab2(sch_1):p3e_pch_m2_rx_dp(3)") )
				( objectStatus "P3E_PCH_M2_RX_DP" )
			)
			( bus "@baseboard_fab2_lib.baseboard_fab2(sch_1):p3e_pch_m2_tx_dn"
				( memberType ( signal ) )
				( member ( signalRef "@baseboard_fab2_lib.baseboard_fab2(sch_1):p3e_pch_m2_tx_dn(1)") )
				( member ( signalRef "@baseboard_fab2_lib.baseboard_fab2(sch_1):p3e_pch_m2_tx_dn(2)") )
				( member ( signalRef "@baseboard_fab2_lib.baseboard_fab2(sch_1):p3e_pch_m2_tx_dn(3)") )
				( objectStatus "P3E_PCH_M2_TX_DN" )
			)
			( bus "@baseboard_fab2_lib.baseboard_fab2(sch_1):p3e_pch_m2_tx_dp"
				( memberType ( signal ) )
				( member ( signalRef "@baseboard_fab2_lib.baseboard_fab2(sch_1):p3e_pch_m2_tx_dp(1)") )
				( member ( signalRef "@baseboard_fab2_lib.baseboard_fab2(sch_1):p3e_pch_m2_tx_dp(2)") )
				( member ( signalRef "@baseboard_fab2_lib.baseboard_fab2(sch_1):p3e_pch_m2_tx_dp(3)") )
				( objectStatus "P3E_PCH_M2_TX_DP" )
			)
			( bus "@baseboard_fab2_lib.baseboard_fab2(sch_1):sata6g_pch_pcie_up_sata_rxn"
				( memberType ( signal ) )
				( member ( signalRef "@baseboard_fab2_lib.baseboard_fab2(sch_1):sata6g_pch_pcie_up_sata_rxn(0)") )
				( member ( signalRef "@baseboard_fab2_lib.baseboard_fab2(sch_1):sata6g_pch_pcie_up_sata_rxn(1)") )
				( member ( signalRef "@baseboard_fab2_lib.baseboard_fab2(sch_1):sata6g_pch_pcie_up_sata_rxn(2)") )
				( member ( signalRef "@baseboard_fab2_lib.baseboard_fab2(sch_1):sata6g_pch_pcie_up_sata_rxn(3)") )
				( member ( signalRef "@baseboard_fab2_lib.baseboard_fab2(sch_1):sata6g_pch_pcie_up_sata_rxn(4)") )
				( member ( signalRef "@baseboard_fab2_lib.baseboard_fab2(sch_1):sata6g_pch_pcie_up_sata_rxn(5)") )
				( member ( signalRef "@baseboard_fab2_lib.baseboard_fab2(sch_1):sata6g_pch_pcie_up_sata_rxn(6)") )
				( member ( signalRef "@baseboard_fab2_lib.baseboard_fab2(sch_1):sata6g_pch_pcie_up_sata_rxn(7)") )
				( objectStatus "SATA6G_PCH_PCIE_UP_SATA_RXN" )
			)
			( bus "@baseboard_fab2_lib.baseboard_fab2(sch_1):sata6g_pch_pcie_up_sata_rxp"
				( memberType ( signal ) )
				( member ( signalRef "@baseboard_fab2_lib.baseboard_fab2(sch_1):sata6g_pch_pcie_up_sata_rxp(0)") )
				( member ( signalRef "@baseboard_fab2_lib.baseboard_fab2(sch_1):sata6g_pch_pcie_up_sata_rxp(1)") )
				( member ( signalRef "@baseboard_fab2_lib.baseboard_fab2(sch_1):sata6g_pch_pcie_up_sata_rxp(2)") )
				( member ( signalRef "@baseboard_fab2_lib.baseboard_fab2(sch_1):sata6g_pch_pcie_up_sata_rxp(3)") )
				( member ( signalRef "@baseboard_fab2_lib.baseboard_fab2(sch_1):sata6g_pch_pcie_up_sata_rxp(4)") )
				( member ( signalRef "@baseboard_fab2_lib.baseboard_fab2(sch_1):sata6g_pch_pcie_up_sata_rxp(5)") )
				( member ( signalRef "@baseboard_fab2_lib.baseboard_fab2(sch_1):sata6g_pch_pcie_up_sata_rxp(6)") )
				( member ( signalRef "@baseboard_fab2_lib.baseboard_fab2(sch_1):sata6g_pch_pcie_up_sata_rxp(7)") )
				( objectStatus "SATA6G_PCH_PCIE_UP_SATA_RXP" )
			)
			( bus "@baseboard_fab2_lib.baseboard_fab2(sch_1):sata6g_pch_pcie_up_sata_txn"
				( memberType ( signal ) )
				( member ( signalRef "@baseboard_fab2_lib.baseboard_fab2(sch_1):sata6g_pch_pcie_up_sata_txn(0)") )
				( member ( signalRef "@baseboard_fab2_lib.baseboard_fab2(sch_1):sata6g_pch_pcie_up_sata_txn(1)") )
				( member ( signalRef "@baseboard_fab2_lib.baseboard_fab2(sch_1):sata6g_pch_pcie_up_sata_txn(2)") )
				( member ( signalRef "@baseboard_fab2_lib.baseboard_fab2(sch_1):sata6g_pch_pcie_up_sata_txn(3)") )
				( member ( signalRef "@baseboard_fab2_lib.baseboard_fab2(sch_1):sata6g_pch_pcie_up_sata_txn(4)") )
				( member ( signalRef "@baseboard_fab2_lib.baseboard_fab2(sch_1):sata6g_pch_pcie_up_sata_txn(5)") )
				( member ( signalRef "@baseboard_fab2_lib.baseboard_fab2(sch_1):sata6g_pch_pcie_up_sata_txn(6)") )
				( member ( signalRef "@baseboard_fab2_lib.baseboard_fab2(sch_1):sata6g_pch_pcie_up_sata_txn(7)") )
				( objectStatus "SATA6G_PCH_PCIE_UP_SATA_TXN" )
			)
			( bus "@baseboard_fab2_lib.baseboard_fab2(sch_1):sata6g_pch_pcie_up_sata_txp"
				( memberType ( signal ) )
				( member ( signalRef "@baseboard_fab2_lib.baseboard_fab2(sch_1):sata6g_pch_pcie_up_sata_txp(0)") )
				( member ( signalRef "@baseboard_fab2_lib.baseboard_fab2(sch_1):sata6g_pch_pcie_up_sata_txp(1)") )
				( member ( signalRef "@baseboard_fab2_lib.baseboard_fab2(sch_1):sata6g_pch_pcie_up_sata_txp(2)") )
				( member ( signalRef "@baseboard_fab2_lib.baseboard_fab2(sch_1):sata6g_pch_pcie_up_sata_txp(3)") )
				( member ( signalRef "@baseboard_fab2_lib.baseboard_fab2(sch_1):sata6g_pch_pcie_up_sata_txp(4)") )
				( member ( signalRef "@baseboard_fab2_lib.baseboard_fab2(sch_1):sata6g_pch_pcie_up_sata_txp(5)") )
				( member ( signalRef "@baseboard_fab2_lib.baseboard_fab2(sch_1):sata6g_pch_pcie_up_sata_txp(6)") )
				( member ( signalRef "@baseboard_fab2_lib.baseboard_fab2(sch_1):sata6g_pch_pcie_up_sata_txp(7)") )
				( objectStatus "SATA6G_PCH_PCIE_UP_SATA_TXP" )
			)
			( bus "@baseboard_fab2_lib.baseboard_fab2(sch_1):sata6g_rx_dn"
				( memberType ( signal ) )
				( member ( signalRef "@baseboard_fab2_lib.baseboard_fab2(sch_1):sata6g_rx_dn(0)") )
				( member ( signalRef "@baseboard_fab2_lib.baseboard_fab2(sch_1):sata6g_rx_dn(1)") )
				( member ( signalRef "@baseboard_fab2_lib.baseboard_fab2(sch_1):sata6g_rx_dn(2)") )
				( member ( signalRef "@baseboard_fab2_lib.baseboard_fab2(sch_1):sata6g_rx_dn(3)") )
				( objectStatus "SATA6G_RX_DN" )
			)
			( bus "@baseboard_fab2_lib.baseboard_fab2(sch_1):sata6g_rx_dp"
				( memberType ( signal ) )
				( member ( signalRef "@baseboard_fab2_lib.baseboard_fab2(sch_1):sata6g_rx_dp(0)") )
				( member ( signalRef "@baseboard_fab2_lib.baseboard_fab2(sch_1):sata6g_rx_dp(1)") )
				( member ( signalRef "@baseboard_fab2_lib.baseboard_fab2(sch_1):sata6g_rx_dp(2)") )
				( member ( signalRef "@baseboard_fab2_lib.baseboard_fab2(sch_1):sata6g_rx_dp(3)") )
				( objectStatus "SATA6G_RX_DP" )
			)
			( bus "@baseboard_fab2_lib.baseboard_fab2(sch_1):sata6g_tx_dn"
				( memberType ( signal ) )
				( member ( signalRef "@baseboard_fab2_lib.baseboard_fab2(sch_1):sata6g_tx_dn(0)") )
				( member ( signalRef "@baseboard_fab2_lib.baseboard_fab2(sch_1):sata6g_tx_dn(1)") )
				( member ( signalRef "@baseboard_fab2_lib.baseboard_fab2(sch_1):sata6g_tx_dn(2)") )
				( member ( signalRef "@baseboard_fab2_lib.baseboard_fab2(sch_1):sata6g_tx_dn(3)") )
				( objectStatus "SATA6G_TX_DN" )
			)
			( bus "@baseboard_fab2_lib.baseboard_fab2(sch_1):sata6g_tx_dp"
				( memberType ( signal ) )
				( member ( signalRef "@baseboard_fab2_lib.baseboard_fab2(sch_1):sata6g_tx_dp(0)") )
				( member ( signalRef "@baseboard_fab2_lib.baseboard_fab2(sch_1):sata6g_tx_dp(1)") )
				( member ( signalRef "@baseboard_fab2_lib.baseboard_fab2(sch_1):sata6g_tx_dp(2)") )
				( member ( signalRef "@baseboard_fab2_lib.baseboard_fab2(sch_1):sata6g_tx_dp(3)") )
				( objectStatus "SATA6G_TX_DP" )
			)
			( bus "@baseboard_fab2_lib.baseboard_fab2(sch_1):dmi_cpu0_pch_rx_dn"
				( memberType ( signal ) )
				( member ( signalRef "@baseboard_fab2_lib.baseboard_fab2(sch_1):dmi_cpu0_pch_rx_dn(0)") )
				( member ( signalRef "@baseboard_fab2_lib.baseboard_fab2(sch_1):dmi_cpu0_pch_rx_dn(1)") )
				( member ( signalRef "@baseboard_fab2_lib.baseboard_fab2(sch_1):dmi_cpu0_pch_rx_dn(2)") )
				( member ( signalRef "@baseboard_fab2_lib.baseboard_fab2(sch_1):dmi_cpu0_pch_rx_dn(3)") )
				( objectStatus "DMI_CPU0_PCH_RX_DN" )
			)
			( bus "@baseboard_fab2_lib.baseboard_fab2(sch_1):dmi_cpu0_pch_rx_dp"
				( memberType ( signal ) )
				( member ( signalRef "@baseboard_fab2_lib.baseboard_fab2(sch_1):dmi_cpu0_pch_rx_dp(0)") )
				( member ( signalRef "@baseboard_fab2_lib.baseboard_fab2(sch_1):dmi_cpu0_pch_rx_dp(1)") )
				( member ( signalRef "@baseboard_fab2_lib.baseboard_fab2(sch_1):dmi_cpu0_pch_rx_dp(2)") )
				( member ( signalRef "@baseboard_fab2_lib.baseboard_fab2(sch_1):dmi_cpu0_pch_rx_dp(3)") )
				( objectStatus "DMI_CPU0_PCH_RX_DP" )
			)
			( bus "@baseboard_fab2_lib.baseboard_fab2(sch_1):dmi_cpu0_pch_tx_c_dn"
				( memberType ( signal ) )
				( member ( signalRef "@baseboard_fab2_lib.baseboard_fab2(sch_1):dmi_cpu0_pch_tx_c_dn(0)") )
				( member ( signalRef "@baseboard_fab2_lib.baseboard_fab2(sch_1):dmi_cpu0_pch_tx_c_dn(1)") )
				( member ( signalRef "@baseboard_fab2_lib.baseboard_fab2(sch_1):dmi_cpu0_pch_tx_c_dn(2)") )
				( member ( signalRef "@baseboard_fab2_lib.baseboard_fab2(sch_1):dmi_cpu0_pch_tx_c_dn(3)") )
				( objectStatus "DMI_CPU0_PCH_TX_C_DN" )
			)
			( bus "@baseboard_fab2_lib.baseboard_fab2(sch_1):dmi_cpu0_pch_tx_c_dp"
				( memberType ( signal ) )
				( member ( signalRef "@baseboard_fab2_lib.baseboard_fab2(sch_1):dmi_cpu0_pch_tx_c_dp(0)") )
				( member ( signalRef "@baseboard_fab2_lib.baseboard_fab2(sch_1):dmi_cpu0_pch_tx_c_dp(1)") )
				( member ( signalRef "@baseboard_fab2_lib.baseboard_fab2(sch_1):dmi_cpu0_pch_tx_c_dp(2)") )
				( member ( signalRef "@baseboard_fab2_lib.baseboard_fab2(sch_1):dmi_cpu0_pch_tx_c_dp(3)") )
				( objectStatus "DMI_CPU0_PCH_TX_C_DP" )
			)
			( bus "@baseboard_fab2_lib.baseboard_fab2(sch_1):lpc_lad_io"
				( memberType ( signal ) )
				( alias ( busRef "@baseboard_fab2_lib.baseboard_fab2(sch_1):page119_lpc_lad_io") )
				( member ( signalRef "@baseboard_fab2_lib.baseboard_fab2(sch_1):lpc_lad0_io0") )
				( member ( signalRef "@baseboard_fab2_lib.baseboard_fab2(sch_1):lpc_lad1_io1") )
				( member ( signalRef "@baseboard_fab2_lib.baseboard_fab2(sch_1):lpc_lad2_io2") )
				( member ( signalRef "@baseboard_fab2_lib.baseboard_fab2(sch_1):lpc_lad3_io3") )
				( objectStatus "LPC_LAD_IO" )
			)
			( bus "@baseboard_fab2_lib.baseboard_fab2(sch_1):page119_lpc_lad_io"
				( memberType ( signal ) )
				( objectFlag fObjectAlias )
				( member ( signalRef "@baseboard_fab2_lib.baseboard_fab2(sch_1):page119_lpc_lad_io(0)") )
				( member ( signalRef "@baseboard_fab2_lib.baseboard_fab2(sch_1):page119_lpc_lad_io(1)") )
				( member ( signalRef "@baseboard_fab2_lib.baseboard_fab2(sch_1):page119_lpc_lad_io(2)") )
				( member ( signalRef "@baseboard_fab2_lib.baseboard_fab2(sch_1):page119_lpc_lad_io(3)") )
				( objectStatus "PAGE119_LPC_LAD_IO" )
			)
			( bus "@baseboard_fab2_lib.baseboard_fab2(sch_1):fm_roma"
				( memberType ( signal ) )
				( alias ( busRef "@baseboard_fab2_lib.baseboard_fab2(sch_1):page143_fm_roma") )
				( attribute "BUS_NAME" "FM_ROMA"
					( Origin gPackager )
				)
				( member ( signalRef "@baseboard_fab2_lib.baseboard_fab2(sch_1):fm_roma(0)") )
				( objectStatus "FM_ROMA" )
			)
			( bus "@baseboard_fab2_lib.baseboard_fab2(sch_1):page143_fm_roma"
				( memberType ( signal ) )
				( objectFlag fObjectAlias )
				( member ( signalRef "@baseboard_fab2_lib.baseboard_fab2(sch_1):page143_fm_roma(0)") )
				( objectStatus "PAGE143_FM_ROMA" )
			)
			( bus "@baseboard_fab2_lib.baseboard_fab2(sch_1):p3e_cpu1_pe3_mp_c_txn"
				( memberType ( signal ) )
				( member ( signalRef "@baseboard_fab2_lib.baseboard_fab2(sch_1):p3e_cpu1_pe3_mp_c_txn(0)") )
				( member ( signalRef "@baseboard_fab2_lib.baseboard_fab2(sch_1):p3e_cpu1_pe3_mp_c_txn(1)") )
				( member ( signalRef "@baseboard_fab2_lib.baseboard_fab2(sch_1):p3e_cpu1_pe3_mp_c_txn(2)") )
				( member ( signalRef "@baseboard_fab2_lib.baseboard_fab2(sch_1):p3e_cpu1_pe3_mp_c_txn(3)") )
				( member ( signalRef "@baseboard_fab2_lib.baseboard_fab2(sch_1):p3e_cpu1_pe3_mp_c_txn(4)") )
				( member ( signalRef "@baseboard_fab2_lib.baseboard_fab2(sch_1):p3e_cpu1_pe3_mp_c_txn(5)") )
				( member ( signalRef "@baseboard_fab2_lib.baseboard_fab2(sch_1):p3e_cpu1_pe3_mp_c_txn(6)") )
				( member ( signalRef "@baseboard_fab2_lib.baseboard_fab2(sch_1):p3e_cpu1_pe3_mp_c_txn(7)") )
				( member ( signalRef "@baseboard_fab2_lib.baseboard_fab2(sch_1):p3e_cpu1_pe3_mp_c_txn(8)") )
				( member ( signalRef "@baseboard_fab2_lib.baseboard_fab2(sch_1):p3e_cpu1_pe3_mp_c_txn(9)") )
				( member ( signalRef "@baseboard_fab2_lib.baseboard_fab2(sch_1):p3e_cpu1_pe3_mp_c_txn(10)") )
				( member ( signalRef "@baseboard_fab2_lib.baseboard_fab2(sch_1):p3e_cpu1_pe3_mp_c_txn(11)") )
				( member ( signalRef "@baseboard_fab2_lib.baseboard_fab2(sch_1):p3e_cpu1_pe3_mp_c_txn(12)") )
				( member ( signalRef "@baseboard_fab2_lib.baseboard_fab2(sch_1):p3e_cpu1_pe3_mp_c_txn(13)") )
				( member ( signalRef "@baseboard_fab2_lib.baseboard_fab2(sch_1):p3e_cpu1_pe3_mp_c_txn(14)") )
				( member ( signalRef "@baseboard_fab2_lib.baseboard_fab2(sch_1):p3e_cpu1_pe3_mp_c_txn(15)") )
				( objectStatus "P3E_CPU1_PE3_MP_C_TXN" )
			)
			( bus "@baseboard_fab2_lib.baseboard_fab2(sch_1):p3e_cpu1_pe3_mp_c_txp"
				( memberType ( signal ) )
				( member ( signalRef "@baseboard_fab2_lib.baseboard_fab2(sch_1):p3e_cpu1_pe3_mp_c_txp(0)") )
				( member ( signalRef "@baseboard_fab2_lib.baseboard_fab2(sch_1):p3e_cpu1_pe3_mp_c_txp(1)") )
				( member ( signalRef "@baseboard_fab2_lib.baseboard_fab2(sch_1):p3e_cpu1_pe3_mp_c_txp(2)") )
				( member ( signalRef "@baseboard_fab2_lib.baseboard_fab2(sch_1):p3e_cpu1_pe3_mp_c_txp(3)") )
				( member ( signalRef "@baseboard_fab2_lib.baseboard_fab2(sch_1):p3e_cpu1_pe3_mp_c_txp(4)") )
				( member ( signalRef "@baseboard_fab2_lib.baseboard_fab2(sch_1):p3e_cpu1_pe3_mp_c_txp(5)") )
				( member ( signalRef "@baseboard_fab2_lib.baseboard_fab2(sch_1):p3e_cpu1_pe3_mp_c_txp(6)") )
				( member ( signalRef "@baseboard_fab2_lib.baseboard_fab2(sch_1):p3e_cpu1_pe3_mp_c_txp(7)") )
				( member ( signalRef "@baseboard_fab2_lib.baseboard_fab2(sch_1):p3e_cpu1_pe3_mp_c_txp(8)") )
				( member ( signalRef "@baseboard_fab2_lib.baseboard_fab2(sch_1):p3e_cpu1_pe3_mp_c_txp(9)") )
				( member ( signalRef "@baseboard_fab2_lib.baseboard_fab2(sch_1):p3e_cpu1_pe3_mp_c_txp(10)") )
				( member ( signalRef "@baseboard_fab2_lib.baseboard_fab2(sch_1):p3e_cpu1_pe3_mp_c_txp(11)") )
				( member ( signalRef "@baseboard_fab2_lib.baseboard_fab2(sch_1):p3e_cpu1_pe3_mp_c_txp(12)") )
				( member ( signalRef "@baseboard_fab2_lib.baseboard_fab2(sch_1):p3e_cpu1_pe3_mp_c_txp(13)") )
				( member ( signalRef "@baseboard_fab2_lib.baseboard_fab2(sch_1):p3e_cpu1_pe3_mp_c_txp(14)") )
				( member ( signalRef "@baseboard_fab2_lib.baseboard_fab2(sch_1):p3e_cpu1_pe3_mp_c_txp(15)") )
				( objectStatus "P3E_CPU1_PE3_MP_C_TXP" )
			)
			( bus "@baseboard_fab2_lib.baseboard_fab2(sch_1):nc_m2"
				( memberType ( signal ) )
				( member ( signalRef "@baseboard_fab2_lib.baseboard_fab2(sch_1):nc_m2(0)") )
				( member ( signalRef "@baseboard_fab2_lib.baseboard_fab2(sch_1):nc_m2(1)") )
				( member ( signalRef "@baseboard_fab2_lib.baseboard_fab2(sch_1):nc_m2(2)") )
				( member ( signalRef "@baseboard_fab2_lib.baseboard_fab2(sch_1):nc_m2(3)") )
				( member ( signalRef "@baseboard_fab2_lib.baseboard_fab2(sch_1):nc_m2(4)") )
				( member ( signalRef "@baseboard_fab2_lib.baseboard_fab2(sch_1):nc_m2(5)") )
				( member ( signalRef "@baseboard_fab2_lib.baseboard_fab2(sch_1):nc_m2(6)") )
				( member ( signalRef "@baseboard_fab2_lib.baseboard_fab2(sch_1):nc_m2(7)") )
				( member ( signalRef "@baseboard_fab2_lib.baseboard_fab2(sch_1):nc_m2(8)") )
				( member ( signalRef "@baseboard_fab2_lib.baseboard_fab2(sch_1):nc_m2(9)") )
				( member ( signalRef "@baseboard_fab2_lib.baseboard_fab2(sch_1):nc_m2(10)") )
				( member ( signalRef "@baseboard_fab2_lib.baseboard_fab2(sch_1):nc_m2(11)") )
				( member ( signalRef "@baseboard_fab2_lib.baseboard_fab2(sch_1):nc_m2(12)") )
				( member ( signalRef "@baseboard_fab2_lib.baseboard_fab2(sch_1):nc_m2(13)") )
				( member ( signalRef "@baseboard_fab2_lib.baseboard_fab2(sch_1):nc_m2(14)") )
				( member ( signalRef "@baseboard_fab2_lib.baseboard_fab2(sch_1):nc_m2(15)") )
				( member ( signalRef "@baseboard_fab2_lib.baseboard_fab2(sch_1):nc_m2(16)") )
				( member ( signalRef "@baseboard_fab2_lib.baseboard_fab2(sch_1):nc_m2(17)") )
				( member ( signalRef "@baseboard_fab2_lib.baseboard_fab2(sch_1):nc_m2(18)") )
				( objectStatus "NC_M2" )
			)
			( bus "@baseboard_fab2_lib.baseboard_fab2(sch_1):p3e_pch_m2_tx_c_dn"
				( memberType ( signal ) )
				( member ( signalRef "@baseboard_fab2_lib.baseboard_fab2(sch_1):p3e_pch_m2_tx_c_dn(1)") )
				( member ( signalRef "@baseboard_fab2_lib.baseboard_fab2(sch_1):p3e_pch_m2_tx_c_dn(2)") )
				( member ( signalRef "@baseboard_fab2_lib.baseboard_fab2(sch_1):p3e_pch_m2_tx_c_dn(3)") )
				( objectStatus "P3E_PCH_M2_TX_C_DN" )
			)
			( bus "@baseboard_fab2_lib.baseboard_fab2(sch_1):p3e_pch_m2_tx_c_dp"
				( memberType ( signal ) )
				( member ( signalRef "@baseboard_fab2_lib.baseboard_fab2(sch_1):p3e_pch_m2_tx_c_dp(1)") )
				( member ( signalRef "@baseboard_fab2_lib.baseboard_fab2(sch_1):p3e_pch_m2_tx_c_dp(2)") )
				( member ( signalRef "@baseboard_fab2_lib.baseboard_fab2(sch_1):p3e_pch_m2_tx_c_dp(3)") )
				( objectStatus "P3E_PCH_M2_TX_C_DP" )
			)
			( bus "@baseboard_fab2_lib.baseboard_fab2(sch_1):tp_rsvd"
				( memberType ( signal ) )
				( member ( signalRef "@baseboard_fab2_lib.baseboard_fab2(sch_1):tp_rsvd(0)") )
				( objectStatus "TP_RSVD" )
			)
			( bus "@baseboard_fab2_lib.baseboard_fab2(sch_1):p3e_cpu0_pe1_pch_con_rxn"
				( memberType ( signal ) )
				( member ( signalRef "@baseboard_fab2_lib.baseboard_fab2(sch_1):p3e_cpu0_pe1_pch_con_rxn(8)") )
				( member ( signalRef "@baseboard_fab2_lib.baseboard_fab2(sch_1):p3e_cpu0_pe1_pch_con_rxn(9)") )
				( member ( signalRef "@baseboard_fab2_lib.baseboard_fab2(sch_1):p3e_cpu0_pe1_pch_con_rxn(10)") )
				( member ( signalRef "@baseboard_fab2_lib.baseboard_fab2(sch_1):p3e_cpu0_pe1_pch_con_rxn(11)") )
				( member ( signalRef "@baseboard_fab2_lib.baseboard_fab2(sch_1):p3e_cpu0_pe1_pch_con_rxn(12)") )
				( member ( signalRef "@baseboard_fab2_lib.baseboard_fab2(sch_1):p3e_cpu0_pe1_pch_con_rxn(13)") )
				( member ( signalRef "@baseboard_fab2_lib.baseboard_fab2(sch_1):p3e_cpu0_pe1_pch_con_rxn(14)") )
				( member ( signalRef "@baseboard_fab2_lib.baseboard_fab2(sch_1):p3e_cpu0_pe1_pch_con_rxn(15)") )
				( objectStatus "P3E_CPU0_PE1_PCH_CON_RXN" )
			)
			( bus "@baseboard_fab2_lib.baseboard_fab2(sch_1):p3e_cpu0_pe1_pch_con_rxp"
				( memberType ( signal ) )
				( member ( signalRef "@baseboard_fab2_lib.baseboard_fab2(sch_1):p3e_cpu0_pe1_pch_con_rxp(8)") )
				( member ( signalRef "@baseboard_fab2_lib.baseboard_fab2(sch_1):p3e_cpu0_pe1_pch_con_rxp(9)") )
				( member ( signalRef "@baseboard_fab2_lib.baseboard_fab2(sch_1):p3e_cpu0_pe1_pch_con_rxp(10)") )
				( member ( signalRef "@baseboard_fab2_lib.baseboard_fab2(sch_1):p3e_cpu0_pe1_pch_con_rxp(11)") )
				( member ( signalRef "@baseboard_fab2_lib.baseboard_fab2(sch_1):p3e_cpu0_pe1_pch_con_rxp(12)") )
				( member ( signalRef "@baseboard_fab2_lib.baseboard_fab2(sch_1):p3e_cpu0_pe1_pch_con_rxp(13)") )
				( member ( signalRef "@baseboard_fab2_lib.baseboard_fab2(sch_1):p3e_cpu0_pe1_pch_con_rxp(14)") )
				( member ( signalRef "@baseboard_fab2_lib.baseboard_fab2(sch_1):p3e_cpu0_pe1_pch_con_rxp(15)") )
				( objectStatus "P3E_CPU0_PE1_PCH_CON_RXP" )
			)
			( bus "@baseboard_fab2_lib.baseboard_fab2(sch_1):p3e_cpu0_pe1_pch_con_txn"
				( memberType ( signal ) )
				( member ( signalRef "@baseboard_fab2_lib.baseboard_fab2(sch_1):p3e_cpu0_pe1_pch_con_txn(8)") )
				( member ( signalRef "@baseboard_fab2_lib.baseboard_fab2(sch_1):p3e_cpu0_pe1_pch_con_txn(9)") )
				( member ( signalRef "@baseboard_fab2_lib.baseboard_fab2(sch_1):p3e_cpu0_pe1_pch_con_txn(10)") )
				( member ( signalRef "@baseboard_fab2_lib.baseboard_fab2(sch_1):p3e_cpu0_pe1_pch_con_txn(11)") )
				( member ( signalRef "@baseboard_fab2_lib.baseboard_fab2(sch_1):p3e_cpu0_pe1_pch_con_txn(12)") )
				( member ( signalRef "@baseboard_fab2_lib.baseboard_fab2(sch_1):p3e_cpu0_pe1_pch_con_txn(13)") )
				( member ( signalRef "@baseboard_fab2_lib.baseboard_fab2(sch_1):p3e_cpu0_pe1_pch_con_txn(14)") )
				( member ( signalRef "@baseboard_fab2_lib.baseboard_fab2(sch_1):p3e_cpu0_pe1_pch_con_txn(15)") )
				( objectStatus "P3E_CPU0_PE1_PCH_CON_TXN" )
			)
			( bus "@baseboard_fab2_lib.baseboard_fab2(sch_1):p3e_cpu0_pe1_pch_con_txp"
				( memberType ( signal ) )
				( member ( signalRef "@baseboard_fab2_lib.baseboard_fab2(sch_1):p3e_cpu0_pe1_pch_con_txp(8)") )
				( member ( signalRef "@baseboard_fab2_lib.baseboard_fab2(sch_1):p3e_cpu0_pe1_pch_con_txp(9)") )
				( member ( signalRef "@baseboard_fab2_lib.baseboard_fab2(sch_1):p3e_cpu0_pe1_pch_con_txp(10)") )
				( member ( signalRef "@baseboard_fab2_lib.baseboard_fab2(sch_1):p3e_cpu0_pe1_pch_con_txp(11)") )
				( member ( signalRef "@baseboard_fab2_lib.baseboard_fab2(sch_1):p3e_cpu0_pe1_pch_con_txp(12)") )
				( member ( signalRef "@baseboard_fab2_lib.baseboard_fab2(sch_1):p3e_cpu0_pe1_pch_con_txp(13)") )
				( member ( signalRef "@baseboard_fab2_lib.baseboard_fab2(sch_1):p3e_cpu0_pe1_pch_con_txp(14)") )
				( member ( signalRef "@baseboard_fab2_lib.baseboard_fab2(sch_1):p3e_cpu0_pe1_pch_con_txp(15)") )
				( objectStatus "P3E_CPU0_PE1_PCH_CON_TXP" )
			)
			( bus "@baseboard_fab2_lib.baseboard_fab2(sch_1):page245_p3e_cpu0_pe2_ss_rxn"
				( memberType ( signal ) )
				( objectFlag fObjectAlias )
				( member ( signalRef "@baseboard_fab2_lib.baseboard_fab2(sch_1):page245_p3e_cpu0_pe2_ss_rxn(8)") )
				( member ( signalRef "@baseboard_fab2_lib.baseboard_fab2(sch_1):page245_p3e_cpu0_pe2_ss_rxn(9)") )
				( member ( signalRef "@baseboard_fab2_lib.baseboard_fab2(sch_1):page245_p3e_cpu0_pe2_ss_rxn(10)") )
				( member ( signalRef "@baseboard_fab2_lib.baseboard_fab2(sch_1):page245_p3e_cpu0_pe2_ss_rxn(11)") )
				( member ( signalRef "@baseboard_fab2_lib.baseboard_fab2(sch_1):page245_p3e_cpu0_pe2_ss_rxn(12)") )
				( member ( signalRef "@baseboard_fab2_lib.baseboard_fab2(sch_1):page245_p3e_cpu0_pe2_ss_rxn(13)") )
				( member ( signalRef "@baseboard_fab2_lib.baseboard_fab2(sch_1):page245_p3e_cpu0_pe2_ss_rxn(14)") )
				( member ( signalRef "@baseboard_fab2_lib.baseboard_fab2(sch_1):page245_p3e_cpu0_pe2_ss_rxn(15)") )
				( objectStatus "PAGE245_P3E_CPU0_PE2_SS_RXN" )
			)
			( bus "@baseboard_fab2_lib.baseboard_fab2(sch_1):page245_p3e_cpu0_pe2_ss_rxp"
				( memberType ( signal ) )
				( objectFlag fObjectAlias )
				( member ( signalRef "@baseboard_fab2_lib.baseboard_fab2(sch_1):page245_p3e_cpu0_pe2_ss_rxp(8)") )
				( member ( signalRef "@baseboard_fab2_lib.baseboard_fab2(sch_1):page245_p3e_cpu0_pe2_ss_rxp(9)") )
				( member ( signalRef "@baseboard_fab2_lib.baseboard_fab2(sch_1):page245_p3e_cpu0_pe2_ss_rxp(10)") )
				( member ( signalRef "@baseboard_fab2_lib.baseboard_fab2(sch_1):page245_p3e_cpu0_pe2_ss_rxp(11)") )
				( member ( signalRef "@baseboard_fab2_lib.baseboard_fab2(sch_1):page245_p3e_cpu0_pe2_ss_rxp(12)") )
				( member ( signalRef "@baseboard_fab2_lib.baseboard_fab2(sch_1):page245_p3e_cpu0_pe2_ss_rxp(13)") )
				( member ( signalRef "@baseboard_fab2_lib.baseboard_fab2(sch_1):page245_p3e_cpu0_pe2_ss_rxp(14)") )
				( member ( signalRef "@baseboard_fab2_lib.baseboard_fab2(sch_1):page245_p3e_cpu0_pe2_ss_rxp(15)") )
				( objectStatus "PAGE245_P3E_CPU0_PE2_SS_RXP" )
			)
		)
	)
)
